G04 ================== begin FILE IDENTIFICATION RECORD ==================*
G04 Layout Name:  15126-1b.brd*
G04 Film Name:    SE_REF_L14*
G04 File Format:  Gerber RS274X*
G04 File Origin:  Cadence Allegro 16.6-2015-S079*
G04 Origin Date:  Fri Feb 10 17:23:38 2017*
G04 *
G04 Layer:  BOARD GEOMETRY/PANEL_OUTLINE*
G04 Layer:  BOARD GEOMETRY/SE_REF_L14_TBL*
G04 Layer:  BOARD GEOMETRY/SE_REF_L14_BOTTOM*
G04 *
G04 Offset:    (0.00 0.00)*
G04 Mirror:    No*
G04 Mode:      Positive*
G04 Rotation:  0*
G04 FullContactRelief:  No*
G04 UndefLineWidth:     6.00*
G04 ================== end FILE IDENTIFICATION RECORD ====================*
%FSLAX35Y35*MOIN*%
%IR0*IPPOS*OFA0.00000B0.00000*MIA0B0*SFA1.00000B1.00000*%
%ADD10C,.02*%
%ADD11C,.006*%
%ADD12C,.0065*%
%ADD13C,.00425*%
G75*
%LPD*%
G75*
G54D10*
G01X2026678Y631398D02*
Y527448D01*
G01D02*
X2744178D01*
G01X2026678Y562098D02*
X2744178D01*
G01X2026678Y596748D02*
X2744178D01*
G01X2026678Y631398D02*
X2744178D01*
G01X2201678D02*
Y527448D01*
G01X2429178Y631398D02*
Y527448D01*
G01X2534178Y631398D02*
Y527448D01*
G01X2744178Y631398D02*
Y527448D01*
G54D11*
G01X-17372Y-95792D02*
Y-113292D01*
G01X-22394Y-95792D02*
X-12350D01*
G01X-3584Y-113292D02*
Y-95792D01*
G01Y-104250D02*
X-2492Y-102792D01*
X-1400Y-101917D01*
X346Y-101626D01*
X1656Y-101917D01*
X3185Y-103084D01*
X3840Y-104834D01*
Y-113292D01*
G01X17628Y-101626D02*
Y-113292D01*
G01Y-96959D02*
X17191Y-96667D01*
Y-96084D01*
X17628Y-95792D01*
X18065Y-96084D01*
Y-96667D01*
X17628Y-96959D01*
G01X31853Y-111251D02*
X32945Y-112417D01*
X34473Y-113292D01*
X35783D01*
X37093Y-112709D01*
X37966Y-111834D01*
X38403Y-110668D01*
X38185Y-108917D01*
X37311Y-108042D01*
X33381Y-106292D01*
X32508Y-104250D01*
X32945Y-102792D01*
X33818Y-101917D01*
X35128Y-101626D01*
X36438Y-101917D01*
X37748Y-102792D01*
G01X67071Y-117667D02*
X68600Y-118834D01*
X70346Y-119125D01*
X71874Y-118834D01*
X73185Y-117376D01*
X74058Y-115334D01*
Y-101626D01*
G01Y-103959D02*
X73185Y-102792D01*
X71874Y-101917D01*
X70346Y-101626D01*
X68600Y-102209D01*
X67508Y-103375D01*
X66634Y-105417D01*
X66198Y-107459D01*
X66416Y-109209D01*
X67290Y-111251D01*
X68600Y-112709D01*
X70346Y-113292D01*
X71656Y-113000D01*
X73185Y-111834D01*
X74058Y-110668D01*
G01X84353Y-105417D02*
X91340D01*
X90685Y-103375D01*
X89593Y-102209D01*
X88065Y-101626D01*
X86536Y-101917D01*
X85226Y-102792D01*
X84353Y-104834D01*
X83916Y-106584D01*
Y-108334D01*
X84353Y-110084D01*
X85445Y-111834D01*
X86755Y-113000D01*
X88283Y-113292D01*
X89811Y-112709D01*
X91340Y-110959D01*
G01X102071Y-113292D02*
Y-101626D01*
G01Y-103959D02*
X103163Y-102792D01*
X104255Y-101917D01*
X105783Y-101626D01*
X106874Y-101917D01*
X108185Y-102792D01*
G01X118698Y-113292D02*
Y-95792D01*
G01Y-104542D02*
X119790Y-102792D01*
X121100Y-101917D01*
X122410Y-101626D01*
X124374Y-102209D01*
X125685Y-103375D01*
X126558Y-105417D01*
Y-107750D01*
X126121Y-110084D01*
X125248Y-111834D01*
X123720Y-113000D01*
X122410Y-113292D01*
X121100Y-113000D01*
X119790Y-112126D01*
X118698Y-110668D01*
G01X136853Y-105417D02*
X143840D01*
X143185Y-103375D01*
X142093Y-102209D01*
X140565Y-101626D01*
X139036Y-101917D01*
X137726Y-102792D01*
X136853Y-104834D01*
X136416Y-106584D01*
Y-108334D01*
X136853Y-110084D01*
X137945Y-111834D01*
X139255Y-113000D01*
X140783Y-113292D01*
X142311Y-112709D01*
X143840Y-110959D01*
G01X154571Y-113292D02*
Y-101626D01*
G01Y-103959D02*
X155663Y-102792D01*
X156755Y-101917D01*
X158283Y-101626D01*
X159374Y-101917D01*
X160685Y-102792D01*
G01X192628Y-101626D02*
Y-113292D01*
G01Y-96959D02*
X192191Y-96667D01*
Y-96084D01*
X192628Y-95792D01*
X193065Y-96084D01*
Y-96667D01*
X192628Y-96959D01*
G01X206853Y-111251D02*
X207945Y-112417D01*
X209473Y-113292D01*
X210783D01*
X212093Y-112709D01*
X212966Y-111834D01*
X213403Y-110668D01*
X213185Y-108917D01*
X212311Y-108042D01*
X208381Y-106292D01*
X207508Y-104250D01*
X207945Y-102792D01*
X208818Y-101917D01*
X210128Y-101626D01*
X211438Y-101917D01*
X212748Y-102792D01*
G01X241634Y-117667D02*
X243163Y-118834D01*
X244473Y-119125D01*
X246220Y-118542D01*
X247530Y-117084D01*
X248185Y-114458D01*
Y-101626D01*
G01Y-96959D02*
X247748Y-96667D01*
Y-96084D01*
X248185Y-95792D01*
X248621Y-96084D01*
Y-96667D01*
X248185Y-96959D01*
G01X258916Y-101626D02*
Y-109792D01*
X259790Y-111834D01*
X261100Y-113000D01*
X262628Y-113292D01*
X264156Y-113000D01*
X265466Y-111834D01*
X266340Y-109792D01*
G01Y-113292D02*
Y-101626D01*
G01X276853Y-111251D02*
X277945Y-112417D01*
X279473Y-113292D01*
X280783D01*
X282093Y-112709D01*
X282966Y-111834D01*
X283403Y-110668D01*
X283185Y-108917D01*
X282311Y-108042D01*
X278381Y-106292D01*
X277508Y-104250D01*
X277945Y-102792D01*
X278818Y-101917D01*
X280128Y-101626D01*
X281438Y-101917D01*
X282748Y-102792D01*
G01X297628Y-95792D02*
Y-113292D01*
G01X294571Y-101626D02*
X300685D01*
G01X331318Y-113292D02*
Y-98417D01*
X331755Y-96959D01*
X332628Y-96084D01*
X333938Y-95792D01*
X335248Y-96375D01*
X335903Y-97834D01*
G01X333283Y-102792D02*
X328916D01*
G01X350128Y-113292D02*
X348818Y-113000D01*
X347508Y-111834D01*
X346634Y-109792D01*
X346198Y-107459D01*
X346634Y-105125D01*
X347508Y-103084D01*
X348818Y-101917D01*
X350128Y-101626D01*
X351438Y-101917D01*
X352748Y-103084D01*
X353621Y-105125D01*
X353840Y-107459D01*
X353621Y-109792D01*
X352748Y-111834D01*
X351438Y-113000D01*
X350128Y-113292D01*
G01X364571D02*
Y-101626D01*
G01Y-103959D02*
X365663Y-102792D01*
X366755Y-101917D01*
X368283Y-101626D01*
X369374Y-101917D01*
X370685Y-102792D01*
G01X398043Y-118542D02*
X399353Y-119125D01*
X401100Y-118542D01*
X402191Y-117376D01*
X403065Y-115917D01*
X404374Y-111251D01*
X407213Y-101626D01*
G01X400226D02*
X404374Y-111251D01*
G01X420128Y-113292D02*
X418818Y-113000D01*
X417508Y-111834D01*
X416634Y-109792D01*
X416198Y-107459D01*
X416634Y-105125D01*
X417508Y-103084D01*
X418818Y-101917D01*
X420128Y-101626D01*
X421438Y-101917D01*
X422748Y-103084D01*
X423621Y-105125D01*
X423840Y-107459D01*
X423621Y-109792D01*
X422748Y-111834D01*
X421438Y-113000D01*
X420128Y-113292D01*
G01X433916Y-101626D02*
Y-109792D01*
X434790Y-111834D01*
X436100Y-113000D01*
X437628Y-113292D01*
X439156Y-113000D01*
X440466Y-111834D01*
X441340Y-109792D01*
G01Y-113292D02*
Y-101626D01*
G01X452071Y-113292D02*
Y-101626D01*
G01Y-103959D02*
X453163Y-102792D01*
X454255Y-101917D01*
X455783Y-101626D01*
X456874Y-101917D01*
X458185Y-102792D01*
G01X487071Y-113292D02*
Y-101626D01*
G01Y-103959D02*
X488163Y-102792D01*
X489255Y-101917D01*
X490783Y-101626D01*
X491874Y-101917D01*
X493185Y-102792D01*
G01X504353Y-105417D02*
X511340D01*
X510685Y-103375D01*
X509593Y-102209D01*
X508065Y-101626D01*
X506536Y-101917D01*
X505226Y-102792D01*
X504353Y-104834D01*
X503916Y-106584D01*
Y-108334D01*
X504353Y-110084D01*
X505445Y-111834D01*
X506755Y-113000D01*
X508283Y-113292D01*
X509811Y-112709D01*
X511340Y-110959D01*
G01X523818Y-113292D02*
Y-98417D01*
X524255Y-96959D01*
X525128Y-96084D01*
X526438Y-95792D01*
X527748Y-96375D01*
X528403Y-97834D01*
G01X525783Y-102792D02*
X521416D01*
G01X539353Y-105417D02*
X546340D01*
X545685Y-103375D01*
X544593Y-102209D01*
X543065Y-101626D01*
X541536Y-101917D01*
X540226Y-102792D01*
X539353Y-104834D01*
X538916Y-106584D01*
Y-108334D01*
X539353Y-110084D01*
X540445Y-111834D01*
X541755Y-113000D01*
X543283Y-113292D01*
X544811Y-112709D01*
X546340Y-110959D01*
G01X557071Y-113292D02*
Y-101626D01*
G01Y-103959D02*
X558163Y-102792D01*
X559255Y-101917D01*
X560783Y-101626D01*
X561874Y-101917D01*
X563185Y-102792D01*
G01X574353Y-105417D02*
X581340D01*
X580685Y-103375D01*
X579593Y-102209D01*
X578065Y-101626D01*
X576536Y-101917D01*
X575226Y-102792D01*
X574353Y-104834D01*
X573916Y-106584D01*
Y-108334D01*
X574353Y-110084D01*
X575445Y-111834D01*
X576755Y-113000D01*
X578283Y-113292D01*
X579811Y-112709D01*
X581340Y-110959D01*
G01X591416Y-113292D02*
Y-101626D01*
G01Y-104542D02*
X592290Y-103084D01*
X593600Y-101917D01*
X595346Y-101626D01*
X596874Y-101917D01*
X598185Y-103084D01*
X598840Y-105125D01*
Y-113292D01*
G01X616121Y-103084D02*
X614593Y-101917D01*
X613283Y-101626D01*
X611536Y-102209D01*
X610226Y-103375D01*
X609353Y-105417D01*
X609134Y-107459D01*
X609353Y-109501D01*
X610226Y-111251D01*
X611536Y-112709D01*
X613283Y-113292D01*
X614811Y-112709D01*
X616121Y-111542D01*
G01X626853Y-105417D02*
X633840D01*
X633185Y-103375D01*
X632093Y-102209D01*
X630565Y-101626D01*
X629036Y-101917D01*
X627726Y-102792D01*
X626853Y-104834D01*
X626416Y-106584D01*
Y-108334D01*
X626853Y-110084D01*
X627945Y-111834D01*
X629255Y-113000D01*
X630783Y-113292D01*
X632311Y-112709D01*
X633840Y-110959D01*
G01X665128Y-95792D02*
Y-113292D01*
G01X662071Y-101626D02*
X668185D01*
G01X682628Y-113292D02*
X681318Y-113000D01*
X680008Y-111834D01*
X679134Y-109792D01*
X678698Y-107459D01*
X679134Y-105125D01*
X680008Y-103084D01*
X681318Y-101917D01*
X682628Y-101626D01*
X683938Y-101917D01*
X685248Y-103084D01*
X686121Y-105125D01*
X686340Y-107459D01*
X686121Y-109792D01*
X685248Y-111834D01*
X683938Y-113000D01*
X682628Y-113292D01*
G01X716318D02*
Y-98417D01*
X716755Y-96959D01*
X717628Y-96084D01*
X718938Y-95792D01*
X720248Y-96375D01*
X720903Y-97834D01*
G01X718283Y-102792D02*
X713916D01*
G01X735128Y-101626D02*
Y-113292D01*
G01Y-96959D02*
X734691Y-96667D01*
Y-96084D01*
X735128Y-95792D01*
X735565Y-96084D01*
Y-96667D01*
X735128Y-96959D01*
G01X748916Y-113292D02*
Y-101626D01*
G01Y-104542D02*
X749790Y-103084D01*
X751100Y-101917D01*
X752846Y-101626D01*
X754374Y-101917D01*
X755685Y-103084D01*
X756340Y-105125D01*
Y-113292D01*
G01X774058Y-95792D02*
Y-113292D01*
G01Y-110668D02*
X773185Y-112126D01*
X771874Y-113000D01*
X770346Y-113292D01*
X768600Y-112709D01*
X767290Y-111251D01*
X766416Y-109501D01*
X766198Y-107459D01*
X766416Y-105417D01*
X767290Y-103667D01*
X768600Y-102209D01*
X770346Y-101626D01*
X771874Y-101917D01*
X772966Y-102501D01*
X774058Y-103667D01*
G01X805128Y-95792D02*
Y-113292D01*
G01X802071Y-101626D02*
X808185D01*
G01X818916Y-113292D02*
Y-95792D01*
G01Y-104250D02*
X820008Y-102792D01*
X821100Y-101917D01*
X822846Y-101626D01*
X824156Y-101917D01*
X825685Y-103084D01*
X826340Y-104834D01*
Y-113292D01*
G01X836853Y-105417D02*
X843840D01*
X843185Y-103375D01*
X842093Y-102209D01*
X840565Y-101626D01*
X839036Y-101917D01*
X837726Y-102792D01*
X836853Y-104834D01*
X836416Y-106584D01*
Y-108334D01*
X836853Y-110084D01*
X837945Y-111834D01*
X839255Y-113000D01*
X840783Y-113292D01*
X842311Y-112709D01*
X843840Y-110959D01*
G01X870543D02*
X872290Y-112417D01*
X874255Y-113292D01*
X876001D01*
X877748Y-112417D01*
X879058Y-110959D01*
X879713Y-108917D01*
X879276Y-106876D01*
X878185Y-105125D01*
X876220Y-103959D01*
X873600Y-103375D01*
X872071Y-102209D01*
X871416Y-100167D01*
X871853Y-98125D01*
X872945Y-96667D01*
X874473Y-95792D01*
X876001D01*
X877530Y-96375D01*
X878840Y-97834D01*
G01X896995Y-113292D02*
X888261D01*
Y-95792D01*
X896995D01*
G01X893501Y-104250D02*
X888261D01*
G01X927628Y-101626D02*
Y-113292D01*
G01Y-96959D02*
X927191Y-96667D01*
Y-96084D01*
X927628Y-95792D01*
X928065Y-96084D01*
Y-96667D01*
X927628Y-96959D01*
G01X938578Y-113292D02*
Y-101626D01*
G01Y-104834D02*
X939233Y-103375D01*
X940325Y-102209D01*
X941853Y-101626D01*
X943381Y-102209D01*
X944473Y-103375D01*
X945128Y-104834D01*
Y-113292D01*
G01Y-104834D02*
X945783Y-103375D01*
X946874Y-102209D01*
X948403Y-101626D01*
X949931Y-102209D01*
X951023Y-103375D01*
X951678Y-105125D01*
Y-113292D01*
G01X958698Y-119125D02*
Y-101626D01*
G01Y-104250D02*
X959790Y-102792D01*
X960881Y-101917D01*
X962628Y-101626D01*
X964156Y-101917D01*
X965685Y-103375D01*
X966340Y-105417D01*
X966558Y-107459D01*
X966340Y-109501D01*
X965685Y-111542D01*
X964374Y-112709D01*
X962628Y-113292D01*
X961100Y-113000D01*
X959571Y-112126D01*
X958698Y-110959D01*
G01X976853Y-105417D02*
X983840D01*
X983185Y-103375D01*
X982093Y-102209D01*
X980565Y-101626D01*
X979036Y-101917D01*
X977726Y-102792D01*
X976853Y-104834D01*
X976416Y-106584D01*
Y-108334D01*
X976853Y-110084D01*
X977945Y-111834D01*
X979255Y-113000D01*
X980783Y-113292D01*
X982311Y-112709D01*
X983840Y-110959D01*
G01X1001558Y-95792D02*
Y-113292D01*
G01Y-110668D02*
X1000685Y-112126D01*
X999374Y-113000D01*
X997846Y-113292D01*
X996100Y-112709D01*
X994790Y-111251D01*
X993916Y-109501D01*
X993698Y-107459D01*
X993916Y-105417D01*
X994790Y-103667D01*
X996100Y-102209D01*
X997846Y-101626D01*
X999374Y-101917D01*
X1000466Y-102501D01*
X1001558Y-103667D01*
G01X1019058Y-113292D02*
Y-101626D01*
G01Y-103667D02*
X1018185Y-102501D01*
X1016874Y-101917D01*
X1015346Y-101626D01*
X1013818Y-102209D01*
X1012508Y-103375D01*
X1011634Y-105125D01*
X1011198Y-107459D01*
X1011634Y-109792D01*
X1012508Y-111542D01*
X1013818Y-112709D01*
X1015346Y-113292D01*
X1016874Y-113000D01*
X1018185Y-112126D01*
X1019058Y-110959D01*
G01X1028916Y-113292D02*
Y-101626D01*
G01Y-104542D02*
X1029790Y-103084D01*
X1031100Y-101917D01*
X1032846Y-101626D01*
X1034374Y-101917D01*
X1035685Y-103084D01*
X1036340Y-105125D01*
Y-113292D01*
G01X1053621Y-103084D02*
X1052093Y-101917D01*
X1050783Y-101626D01*
X1049036Y-102209D01*
X1047726Y-103375D01*
X1046853Y-105417D01*
X1046634Y-107459D01*
X1046853Y-109501D01*
X1047726Y-111251D01*
X1049036Y-112709D01*
X1050783Y-113292D01*
X1052311Y-112709D01*
X1053621Y-111542D01*
G01X1064353Y-105417D02*
X1071340D01*
X1070685Y-103375D01*
X1069593Y-102209D01*
X1068065Y-101626D01*
X1066536Y-101917D01*
X1065226Y-102792D01*
X1064353Y-104834D01*
X1063916Y-106584D01*
Y-108334D01*
X1064353Y-110084D01*
X1065445Y-111834D01*
X1066755Y-113000D01*
X1068283Y-113292D01*
X1069811Y-112709D01*
X1071340Y-110959D01*
G01X1102628Y-95792D02*
Y-113292D01*
G01X1099571Y-101626D02*
X1105685D01*
G01X1117071Y-113292D02*
Y-101626D01*
G01Y-103959D02*
X1118163Y-102792D01*
X1119255Y-101917D01*
X1120783Y-101626D01*
X1121874Y-101917D01*
X1123185Y-102792D01*
G01X1141558Y-113292D02*
Y-101626D01*
G01Y-103667D02*
X1140685Y-102501D01*
X1139374Y-101917D01*
X1137846Y-101626D01*
X1136318Y-102209D01*
X1135008Y-103375D01*
X1134134Y-105125D01*
X1133698Y-107459D01*
X1134134Y-109792D01*
X1135008Y-111542D01*
X1136318Y-112709D01*
X1137846Y-113292D01*
X1139374Y-113000D01*
X1140685Y-112126D01*
X1141558Y-110959D01*
G01X1158621Y-103084D02*
X1157093Y-101917D01*
X1155783Y-101626D01*
X1154036Y-102209D01*
X1152726Y-103375D01*
X1151853Y-105417D01*
X1151634Y-107459D01*
X1151853Y-109501D01*
X1152726Y-111251D01*
X1154036Y-112709D01*
X1155783Y-113292D01*
X1157311Y-112709D01*
X1158621Y-111542D01*
G01X1169353Y-105417D02*
X1176340D01*
X1175685Y-103375D01*
X1174593Y-102209D01*
X1173065Y-101626D01*
X1171536Y-101917D01*
X1170226Y-102792D01*
X1169353Y-104834D01*
X1168916Y-106584D01*
Y-108334D01*
X1169353Y-110084D01*
X1170445Y-111834D01*
X1171755Y-113000D01*
X1173283Y-113292D01*
X1174811Y-112709D01*
X1176340Y-110959D01*
G01X1186853Y-111251D02*
X1187945Y-112417D01*
X1189473Y-113292D01*
X1190783D01*
X1192093Y-112709D01*
X1192966Y-111834D01*
X1193403Y-110668D01*
X1193185Y-108917D01*
X1192311Y-108042D01*
X1188381Y-106292D01*
X1187508Y-104250D01*
X1187945Y-102792D01*
X1188818Y-101917D01*
X1190128Y-101626D01*
X1191438Y-101917D01*
X1192748Y-102792D01*
G01X1225128Y-101626D02*
Y-113292D01*
G01Y-96959D02*
X1224691Y-96667D01*
Y-96084D01*
X1225128Y-95792D01*
X1225565Y-96084D01*
Y-96667D01*
X1225128Y-96959D01*
G01X1238916Y-113292D02*
Y-101626D01*
G01Y-104542D02*
X1239790Y-103084D01*
X1241100Y-101917D01*
X1242846Y-101626D01*
X1244374Y-101917D01*
X1245685Y-103084D01*
X1246340Y-105125D01*
Y-113292D01*
G01X1277628D02*
Y-95792D01*
G01X1299058Y-113292D02*
Y-101626D01*
G01Y-103667D02*
X1298185Y-102501D01*
X1296874Y-101917D01*
X1295346Y-101626D01*
X1293818Y-102209D01*
X1292508Y-103375D01*
X1291634Y-105125D01*
X1291198Y-107459D01*
X1291634Y-109792D01*
X1292508Y-111542D01*
X1293818Y-112709D01*
X1295346Y-113292D01*
X1296874Y-113000D01*
X1298185Y-112126D01*
X1299058Y-110959D01*
G01X1308043Y-118542D02*
X1309353Y-119125D01*
X1311100Y-118542D01*
X1312191Y-117376D01*
X1313065Y-115917D01*
X1314374Y-111251D01*
X1317213Y-101626D01*
G01X1310226D02*
X1314374Y-111251D01*
G01X1326853Y-105417D02*
X1333840D01*
X1333185Y-103375D01*
X1332093Y-102209D01*
X1330565Y-101626D01*
X1329036Y-101917D01*
X1327726Y-102792D01*
X1326853Y-104834D01*
X1326416Y-106584D01*
Y-108334D01*
X1326853Y-110084D01*
X1327945Y-111834D01*
X1329255Y-113000D01*
X1330783Y-113292D01*
X1332311Y-112709D01*
X1333840Y-110959D01*
G01X1344571Y-113292D02*
Y-101626D01*
G01Y-103959D02*
X1345663Y-102792D01*
X1346755Y-101917D01*
X1348283Y-101626D01*
X1349374Y-101917D01*
X1350685Y-102792D01*
G01X1378261Y-95792D02*
Y-113292D01*
X1386995D01*
G01X1400128D02*
Y-95792D01*
X1397508Y-99292D01*
G01Y-113292D02*
X1402748D01*
G01X1420248D02*
Y-95792D01*
X1412169Y-108334D01*
X1423087D01*
G01X1435128Y-113875D02*
X1434691Y-113584D01*
Y-113000D01*
X1435128Y-112709D01*
X1435565Y-113000D01*
Y-113584D01*
X1435128Y-113875D01*
G01X2083125Y539822D02*
X2084434Y538364D01*
X2085963Y537490D01*
X2087928Y537198D01*
X2089893Y537781D01*
X2091421Y538948D01*
X2092513Y540989D01*
X2092731Y543323D01*
X2092295Y545656D01*
X2091203Y547115D01*
X2089674Y548281D01*
X2088146Y548573D01*
X2086618Y548281D01*
X2084653Y547115D01*
X2085308Y554698D01*
X2091203D01*
G01X2105428D02*
X2103681Y554115D01*
X2102371Y552656D01*
X2101498Y550907D01*
X2100843Y548573D01*
X2100625Y545948D01*
X2100843Y543323D01*
X2101498Y540989D01*
X2102371Y539239D01*
X2103681Y537781D01*
X2105428Y537198D01*
X2107174Y537781D01*
X2108485Y539239D01*
X2109358Y540989D01*
X2110013Y543323D01*
X2110231Y545948D01*
X2110013Y548573D01*
X2109358Y550907D01*
X2108485Y552656D01*
X2107174Y554115D01*
X2105428Y554698D01*
G01X2122928Y536615D02*
X2122491Y536906D01*
Y537490D01*
X2122928Y537781D01*
X2123365Y537490D01*
Y536906D01*
X2122928Y536615D01*
G01X2140428Y554698D02*
X2138681Y554115D01*
X2137371Y552656D01*
X2136498Y550907D01*
X2135843Y548573D01*
X2135625Y545948D01*
X2135843Y543323D01*
X2136498Y540989D01*
X2137371Y539239D01*
X2138681Y537781D01*
X2140428Y537198D01*
X2142174Y537781D01*
X2143485Y539239D01*
X2144358Y540989D01*
X2145013Y543323D01*
X2145231Y545948D01*
X2145013Y548573D01*
X2144358Y550907D01*
X2143485Y552656D01*
X2142174Y554115D01*
X2140428Y554698D01*
G01X2090548Y571848D02*
Y589348D01*
X2082469Y576806D01*
X2093387D01*
G01X2105428Y589348D02*
X2103681Y588765D01*
X2102371Y587306D01*
X2101498Y585557D01*
X2100843Y583223D01*
X2100625Y580598D01*
X2100843Y577973D01*
X2101498Y575639D01*
X2102371Y573889D01*
X2103681Y572431D01*
X2105428Y571848D01*
X2107174Y572431D01*
X2108485Y573889D01*
X2109358Y575639D01*
X2110013Y577973D01*
X2110231Y580598D01*
X2110013Y583223D01*
X2109358Y585557D01*
X2108485Y587306D01*
X2107174Y588765D01*
X2105428Y589348D01*
G01X2122928Y571265D02*
X2122491Y571556D01*
Y572140D01*
X2122928Y572431D01*
X2123365Y572140D01*
Y571556D01*
X2122928Y571265D01*
G01X2140428Y589348D02*
X2138681Y588765D01*
X2137371Y587306D01*
X2136498Y585557D01*
X2135843Y583223D01*
X2135625Y580598D01*
X2135843Y577973D01*
X2136498Y575639D01*
X2137371Y573889D01*
X2138681Y572431D01*
X2140428Y571848D01*
X2142174Y572431D01*
X2143485Y573889D01*
X2144358Y575639D01*
X2145013Y577973D01*
X2145231Y580598D01*
X2145013Y583223D01*
X2144358Y585557D01*
X2143485Y587306D01*
X2142174Y588765D01*
X2140428Y589348D01*
G01X2050308Y623998D02*
X2055548D01*
G01X2052928D02*
Y606498D01*
G01X2050308D02*
X2055548D01*
G01X2064751D02*
Y623998D01*
X2070428Y609415D01*
X2076105Y623998D01*
Y606498D01*
G01X2083561D02*
Y623998D01*
X2088801D01*
X2090548Y623123D01*
X2091858Y621081D01*
X2092295Y618748D01*
X2091858Y616415D01*
X2090766Y614665D01*
X2088801Y613789D01*
X2083561D01*
G01X2104336Y600665D02*
X2102153Y603581D01*
X2101061Y606498D01*
Y618164D01*
X2102153Y621081D01*
X2104336Y623998D01*
G01X2122928Y606498D02*
X2121181Y606790D01*
X2119653Y607956D01*
X2118343Y609706D01*
X2117469Y611748D01*
X2117033Y614081D01*
Y616415D01*
X2117469Y618748D01*
X2118343Y620790D01*
X2119653Y622539D01*
X2121181Y623706D01*
X2122928Y623998D01*
X2124674Y623706D01*
X2126203Y622539D01*
X2127513Y620790D01*
X2128387Y618748D01*
X2128823Y616415D01*
Y614081D01*
X2128387Y611748D01*
X2127513Y609706D01*
X2126203Y607956D01*
X2124674Y606790D01*
X2122928Y606498D01*
G01X2136716D02*
Y623998D01*
G01Y615540D02*
X2137808Y616998D01*
X2138900Y617873D01*
X2140646Y618164D01*
X2141956Y617873D01*
X2143485Y616706D01*
X2144140Y614956D01*
Y606498D01*
G01X2151378D02*
Y618164D01*
G01Y614956D02*
X2152033Y616415D01*
X2153125Y617581D01*
X2154653Y618164D01*
X2156181Y617581D01*
X2157273Y616415D01*
X2157928Y614956D01*
Y606498D01*
G01Y614956D02*
X2158583Y616415D01*
X2159674Y617581D01*
X2161203Y618164D01*
X2162731Y617581D01*
X2163823Y616415D01*
X2164478Y614665D01*
Y606498D01*
G01X2176520Y600665D02*
X2178703Y603581D01*
X2179795Y606498D01*
Y618164D01*
X2178703Y621081D01*
X2176520Y623998D01*
G01X2028643Y643481D02*
X2030390Y642023D01*
X2032355Y641148D01*
X2034101D01*
X2035848Y642023D01*
X2037158Y643481D01*
X2037813Y645523D01*
X2037376Y647564D01*
X2036285Y649315D01*
X2034320Y650481D01*
X2031700Y651065D01*
X2030171Y652231D01*
X2029516Y654273D01*
X2029953Y656315D01*
X2031045Y657773D01*
X2032573Y658648D01*
X2034101D01*
X2035630Y658065D01*
X2036940Y656606D01*
G01X2055095Y641148D02*
X2046361D01*
Y658648D01*
X2055095D01*
G01X2051601Y650190D02*
X2046361D01*
G01X2083108Y658648D02*
X2088348D01*
G01X2085728D02*
Y641148D01*
G01X2083108D02*
X2088348D01*
G01X2097551D02*
Y658648D01*
X2103228Y644065D01*
X2108905Y658648D01*
Y641148D01*
G01X2116361D02*
Y658648D01*
X2121601D01*
X2123348Y657773D01*
X2124658Y655731D01*
X2125095Y653398D01*
X2124658Y651065D01*
X2123566Y649315D01*
X2121601Y648439D01*
X2116361D01*
G01X2142595Y641148D02*
X2133861D01*
Y658648D01*
X2142595D01*
G01X2139101Y650190D02*
X2133861D01*
G01X2150925Y641148D02*
Y658648D01*
X2155291D01*
X2157038Y657773D01*
X2158348Y656606D01*
X2159440Y654857D01*
X2160313Y652814D01*
X2160531Y649898D01*
X2160313Y646981D01*
X2159440Y644939D01*
X2158348Y643189D01*
X2157038Y642023D01*
X2155291Y641148D01*
X2150925D01*
G01X2167769D02*
X2173228Y658648D01*
X2178687Y641148D01*
G01X2176721Y647273D02*
X2169734D01*
G01X2185706Y641148D02*
Y658648D01*
X2195750Y641148D01*
Y658648D01*
G01X2213031Y657189D02*
X2211721Y658065D01*
X2210193Y658648D01*
X2208446D01*
X2206481Y657773D01*
X2204953Y656315D01*
X2203861Y654564D01*
X2202988Y651648D01*
X2202769Y649023D01*
X2203206Y646398D01*
X2203861Y644648D01*
X2205171Y642898D01*
X2206700Y641731D01*
X2208228Y641148D01*
X2209756D01*
X2211285Y641731D01*
X2212595Y642606D01*
X2213687Y643772D01*
G01X2230095Y641148D02*
X2221361D01*
Y658648D01*
X2230095D01*
G01X2226601Y650190D02*
X2221361D01*
G01X2260728Y658648D02*
Y641148D01*
G01X2255706Y658648D02*
X2265750D01*
G01X2272769Y641148D02*
X2278228Y658648D01*
X2283687Y641148D01*
G01X2281721Y647273D02*
X2274734D01*
G01X2297474Y650481D02*
X2298348Y651356D01*
X2299003Y652814D01*
X2299440Y654857D01*
X2299003Y656606D01*
X2298130Y657773D01*
X2296601Y658648D01*
X2290706D01*
Y641148D01*
X2297911D01*
X2299440Y642314D01*
X2300313Y644065D01*
X2300750Y646106D01*
X2300313Y648148D01*
X2299003Y649898D01*
X2297474Y650481D01*
X2290706D01*
G01X2308861Y658648D02*
Y641148D01*
X2317595D01*
G01X2335095D02*
X2326361D01*
Y658648D01*
X2335095D01*
G01X2331601Y650190D02*
X2326361D01*
G01X2348228Y640565D02*
X2347791Y640856D01*
Y641440D01*
X2348228Y641731D01*
X2348665Y641440D01*
Y640856D01*
X2348228Y640565D01*
G01Y648439D02*
X2347791Y648731D01*
Y649315D01*
X2348228Y649606D01*
X2348665Y649315D01*
Y648731D01*
X2348228Y648439D01*
G01X2378861Y658648D02*
Y641148D01*
X2387595D01*
G01X2400728D02*
Y658648D01*
X2398108Y655148D01*
G01Y641148D02*
X2403348D01*
G01X2420848D02*
Y658648D01*
X2412769Y646106D01*
X2423687D01*
G01X2221378Y623998D02*
X2224434Y606498D01*
X2227928Y623998D01*
X2231421Y606498D01*
X2234478Y623998D01*
G01X2242808D02*
X2248048D01*
G01X2245428D02*
Y606498D01*
G01X2242808D02*
X2248048D01*
G01X2258125D02*
Y623998D01*
X2262491D01*
X2264238Y623123D01*
X2265548Y621956D01*
X2266640Y620207D01*
X2267513Y618164D01*
X2267731Y615248D01*
X2267513Y612331D01*
X2266640Y610289D01*
X2265548Y608539D01*
X2264238Y607373D01*
X2262491Y606498D01*
X2258125D01*
G01X2280428Y623998D02*
Y606498D01*
G01X2275406Y623998D02*
X2285450D01*
G01X2293343Y606498D02*
Y623998D01*
G01X2302513D02*
Y606498D01*
G01Y615248D02*
X2293343D01*
G01X2314336Y600665D02*
X2312153Y603581D01*
X2311061Y606498D01*
Y618164D01*
X2312153Y621081D01*
X2314336Y623998D01*
G01X2326378Y606498D02*
Y618164D01*
G01Y614956D02*
X2327033Y616415D01*
X2328125Y617581D01*
X2329653Y618164D01*
X2331181Y617581D01*
X2332273Y616415D01*
X2332928Y614956D01*
Y606498D01*
G01Y614956D02*
X2333583Y616415D01*
X2334674Y617581D01*
X2336203Y618164D01*
X2337731Y617581D01*
X2338823Y616415D01*
X2339478Y614665D01*
Y606498D01*
G01X2350428Y618164D02*
Y606498D01*
G01Y622831D02*
X2349991Y623123D01*
Y623706D01*
X2350428Y623998D01*
X2350865Y623706D01*
Y623123D01*
X2350428Y622831D01*
G01X2367928Y606498D02*
Y623998D01*
G01X2382153Y608539D02*
X2383245Y607373D01*
X2384773Y606498D01*
X2386083D01*
X2387393Y607081D01*
X2388266Y607956D01*
X2388703Y609122D01*
X2388485Y610873D01*
X2387611Y611748D01*
X2383681Y613498D01*
X2382808Y615540D01*
X2383245Y616998D01*
X2384118Y617873D01*
X2385428Y618164D01*
X2386738Y617873D01*
X2388048Y616998D01*
G01X2404020Y600665D02*
X2406203Y603581D01*
X2407295Y606498D01*
Y618164D01*
X2406203Y621081D01*
X2404020Y623998D01*
G01X2291798Y537198D02*
Y554698D01*
X2283719Y542156D01*
X2294637D01*
G01X2306678Y536615D02*
X2306241Y536906D01*
Y537490D01*
X2306678Y537781D01*
X2307115Y537490D01*
Y536906D01*
X2306678Y536615D01*
G01X2320030Y551781D02*
X2321340Y553531D01*
X2322868Y554406D01*
X2324615Y554698D01*
X2326798Y554115D01*
X2328326Y552656D01*
X2328763Y550907D01*
X2328545Y549156D01*
X2327671Y547698D01*
X2323305Y544781D01*
X2321340Y542740D01*
X2320030Y539822D01*
X2319593Y537198D01*
X2328763D01*
G01X2336875Y539822D02*
X2338184Y538364D01*
X2339713Y537490D01*
X2341678Y537198D01*
X2343643Y537781D01*
X2345171Y538948D01*
X2346263Y540989D01*
X2346481Y543323D01*
X2346045Y545656D01*
X2344953Y547115D01*
X2343424Y548281D01*
X2341896Y548573D01*
X2340368Y548281D01*
X2338403Y547115D01*
X2339058Y554698D01*
X2344953D01*
G01X2293780Y579139D02*
X2295308Y581181D01*
X2296618Y582348D01*
X2298365Y582931D01*
X2299893Y582348D01*
X2300985Y581181D01*
X2301858Y579431D01*
X2302076Y577390D01*
X2301858Y575639D01*
X2300985Y573889D01*
X2299674Y572431D01*
X2298146Y571848D01*
X2296400Y572431D01*
X2294871Y574181D01*
X2293998Y576806D01*
X2293780Y579723D01*
X2294216Y583514D01*
X2294871Y585557D01*
X2295963Y587598D01*
X2297491Y589056D01*
X2299020Y589348D01*
X2300548Y588765D01*
X2301640Y587306D01*
G01X2315428Y571265D02*
X2314991Y571556D01*
Y572140D01*
X2315428Y572431D01*
X2315865Y572140D01*
Y571556D01*
X2315428Y571265D01*
G01X2328125Y574472D02*
X2329434Y573014D01*
X2330963Y572140D01*
X2332928Y571848D01*
X2334893Y572431D01*
X2336421Y573598D01*
X2337513Y575639D01*
X2337731Y577973D01*
X2337295Y580306D01*
X2336203Y581765D01*
X2334674Y582931D01*
X2333146Y583223D01*
X2331618Y582931D01*
X2329653Y581765D01*
X2330308Y589348D01*
X2336203D01*
G01X2455428Y623998D02*
Y606498D01*
G01X2450406Y623998D02*
X2460450D01*
G01X2472928Y606498D02*
Y614373D01*
X2468561Y623998D01*
G01X2477295D02*
X2472928Y614373D01*
G01X2486061Y606498D02*
Y623998D01*
X2491301D01*
X2493048Y623123D01*
X2494358Y621081D01*
X2494795Y618748D01*
X2494358Y616415D01*
X2493266Y614665D01*
X2491301Y613789D01*
X2486061D01*
G01X2512295Y606498D02*
X2503561D01*
Y623998D01*
X2512295D01*
G01X2508801Y615540D02*
X2503561D01*
G01X2468343Y539531D02*
X2470090Y538073D01*
X2472055Y537198D01*
X2473801D01*
X2475548Y538073D01*
X2476858Y539531D01*
X2477513Y541573D01*
X2477076Y543614D01*
X2475985Y545365D01*
X2474020Y546531D01*
X2471400Y547115D01*
X2469871Y548281D01*
X2469216Y550323D01*
X2469653Y552365D01*
X2470745Y553823D01*
X2472273Y554698D01*
X2473801D01*
X2475330Y554115D01*
X2476640Y552656D01*
G01X2494795Y537198D02*
X2486061D01*
Y554698D01*
X2494795D01*
G01X2491301Y546240D02*
X2486061D01*
G01X2468343Y574181D02*
X2470090Y572723D01*
X2472055Y571848D01*
X2473801D01*
X2475548Y572723D01*
X2476858Y574181D01*
X2477513Y576223D01*
X2477076Y578264D01*
X2475985Y580015D01*
X2474020Y581181D01*
X2471400Y581765D01*
X2469871Y582931D01*
X2469216Y584973D01*
X2469653Y587015D01*
X2470745Y588473D01*
X2472273Y589348D01*
X2473801D01*
X2475330Y588765D01*
X2476640Y587306D01*
G01X2494795Y571848D02*
X2486061D01*
Y589348D01*
X2494795D01*
G01X2491301Y580890D02*
X2486061D01*
G01X2556061Y606498D02*
Y623998D01*
X2561520D01*
X2563266Y623123D01*
X2564358Y621956D01*
X2564795Y619623D01*
X2564358Y617289D01*
X2563048Y615831D01*
X2561520Y614956D01*
X2556061D01*
G01X2561520D02*
X2564795Y606498D01*
G01X2574653Y614373D02*
X2581640D01*
X2580985Y616415D01*
X2579893Y617581D01*
X2578365Y618164D01*
X2576836Y617873D01*
X2575526Y616998D01*
X2574653Y614956D01*
X2574216Y613206D01*
Y611456D01*
X2574653Y609706D01*
X2575745Y607956D01*
X2577055Y606790D01*
X2578583Y606498D01*
X2580111Y607081D01*
X2581640Y608831D01*
G01X2594118Y606498D02*
Y621373D01*
X2594555Y622831D01*
X2595428Y623706D01*
X2596738Y623998D01*
X2598048Y623415D01*
X2598703Y621956D01*
G01X2596083Y616998D02*
X2591716D01*
G01X2612928Y605915D02*
X2612491Y606206D01*
Y606790D01*
X2612928Y607081D01*
X2613365Y606790D01*
Y606206D01*
X2612928Y605915D01*
G01X2643561Y606498D02*
Y623998D01*
X2648801D01*
X2650548Y623123D01*
X2651858Y621081D01*
X2652295Y618748D01*
X2651858Y616415D01*
X2650766Y614665D01*
X2648801Y613789D01*
X2643561D01*
G01X2665428Y606498D02*
Y623998D01*
G01X2686858Y606498D02*
Y618164D01*
G01Y616123D02*
X2685985Y617289D01*
X2684674Y617873D01*
X2683146Y618164D01*
X2681618Y617581D01*
X2680308Y616415D01*
X2679434Y614665D01*
X2678998Y612331D01*
X2679434Y609998D01*
X2680308Y608248D01*
X2681618Y607081D01*
X2683146Y606498D01*
X2684674Y606790D01*
X2685985Y607664D01*
X2686858Y608831D01*
G01X2696716Y606498D02*
Y618164D01*
G01Y615248D02*
X2697590Y616706D01*
X2698900Y617873D01*
X2700646Y618164D01*
X2702174Y617873D01*
X2703485Y616706D01*
X2704140Y614665D01*
Y606498D01*
G01X2714653Y614373D02*
X2721640D01*
X2720985Y616415D01*
X2719893Y617581D01*
X2718365Y618164D01*
X2716836Y617873D01*
X2715526Y616998D01*
X2714653Y614956D01*
X2714216Y613206D01*
Y611456D01*
X2714653Y609706D01*
X2715745Y607956D01*
X2717055Y606790D01*
X2718583Y606498D01*
X2720111Y607081D01*
X2721640Y608831D01*
G01X2617311Y554698D02*
Y537198D01*
X2626045D01*
G01X2639178D02*
Y554698D01*
X2636558Y551198D01*
G01Y537198D02*
X2641798D01*
G01X2651875Y540698D02*
X2653184Y538656D01*
X2654931Y537490D01*
X2656896Y537198D01*
X2658643Y537490D01*
X2660390Y538948D01*
X2661481Y540698D01*
X2661700Y542448D01*
X2661263Y544489D01*
X2659735Y545948D01*
X2658206Y546531D01*
X2656241D01*
G01X2658206D02*
X2659516Y547406D01*
X2660608Y548864D01*
X2661045Y550614D01*
X2660608Y552365D01*
X2659516Y553823D01*
X2657551Y554698D01*
X2655586Y554406D01*
X2653621Y553239D01*
G01X2617311Y589348D02*
Y571848D01*
X2626045D01*
G01X2639178D02*
Y589348D01*
X2636558Y585848D01*
G01Y571848D02*
X2641798D01*
G01X2651875Y575348D02*
X2653184Y573306D01*
X2654931Y572140D01*
X2656896Y571848D01*
X2658643Y572140D01*
X2660390Y573598D01*
X2661481Y575348D01*
X2661700Y577098D01*
X2661263Y579139D01*
X2659735Y580598D01*
X2658206Y581181D01*
X2656241D01*
G01X2658206D02*
X2659516Y582056D01*
X2660608Y583514D01*
X2661045Y585264D01*
X2660608Y587015D01*
X2659516Y588473D01*
X2657551Y589348D01*
X2655586Y589056D01*
X2653621Y587889D01*
G01X2835728Y548864D02*
Y537198D01*
G01Y553531D02*
X2835291Y553823D01*
Y554406D01*
X2835728Y554698D01*
X2836165Y554406D01*
Y553823D01*
X2835728Y553531D01*
G01X2849516Y537198D02*
Y548864D01*
G01Y545948D02*
X2850390Y547406D01*
X2851700Y548573D01*
X2853446Y548864D01*
X2854974Y548573D01*
X2856285Y547406D01*
X2856940Y545365D01*
Y537198D01*
G01X2867453Y539239D02*
X2868545Y538073D01*
X2870073Y537198D01*
X2871383D01*
X2872693Y537781D01*
X2873566Y538656D01*
X2874003Y539822D01*
X2873785Y541573D01*
X2872911Y542448D01*
X2868981Y544198D01*
X2868108Y546240D01*
X2868545Y547698D01*
X2869418Y548573D01*
X2870728Y548864D01*
X2872038Y548573D01*
X2873348Y547698D01*
G01X2888228Y548864D02*
Y537198D01*
G01Y553531D02*
X2887791Y553823D01*
Y554406D01*
X2888228Y554698D01*
X2888665Y554406D01*
Y553823D01*
X2888228Y553531D01*
G01X2909658Y554698D02*
Y537198D01*
G01Y539822D02*
X2908785Y538364D01*
X2907474Y537490D01*
X2905946Y537198D01*
X2904200Y537781D01*
X2902890Y539239D01*
X2902016Y540989D01*
X2901798Y543031D01*
X2902016Y545073D01*
X2902890Y546823D01*
X2904200Y548281D01*
X2905946Y548864D01*
X2907474Y548573D01*
X2908566Y547989D01*
X2909658Y546823D01*
G01X2919953Y545073D02*
X2926940D01*
X2926285Y547115D01*
X2925193Y548281D01*
X2923665Y548864D01*
X2922136Y548573D01*
X2920826Y547698D01*
X2919953Y545656D01*
X2919516Y543906D01*
Y542156D01*
X2919953Y540406D01*
X2921045Y538656D01*
X2922355Y537490D01*
X2923883Y537198D01*
X2925411Y537781D01*
X2926940Y539531D01*
G01X2954298Y537198D02*
Y554698D01*
G01Y545948D02*
X2955390Y547698D01*
X2956700Y548573D01*
X2958010Y548864D01*
X2959974Y548281D01*
X2961285Y547115D01*
X2962158Y545073D01*
Y542740D01*
X2961721Y540406D01*
X2960848Y538656D01*
X2959320Y537490D01*
X2958010Y537198D01*
X2956700Y537490D01*
X2955390Y538364D01*
X2954298Y539822D01*
G01X2975728Y537198D02*
X2974418Y537490D01*
X2973108Y538656D01*
X2972234Y540698D01*
X2971798Y543031D01*
X2972234Y545365D01*
X2973108Y547406D01*
X2974418Y548573D01*
X2975728Y548864D01*
X2977038Y548573D01*
X2978348Y547406D01*
X2979221Y545365D01*
X2979440Y543031D01*
X2979221Y540698D01*
X2978348Y538656D01*
X2977038Y537490D01*
X2975728Y537198D01*
G01X2997158D02*
Y548864D01*
G01Y546823D02*
X2996285Y547989D01*
X2994974Y548573D01*
X2993446Y548864D01*
X2991918Y548281D01*
X2990608Y547115D01*
X2989734Y545365D01*
X2989298Y543031D01*
X2989734Y540698D01*
X2990608Y538948D01*
X2991918Y537781D01*
X2993446Y537198D01*
X2994974Y537490D01*
X2996285Y538364D01*
X2997158Y539531D01*
G01X3007671Y537198D02*
Y548864D01*
G01Y546531D02*
X3008763Y547698D01*
X3009855Y548573D01*
X3011383Y548864D01*
X3012474Y548573D01*
X3013785Y547698D01*
G01X3032158Y554698D02*
Y537198D01*
G01Y539822D02*
X3031285Y538364D01*
X3029974Y537490D01*
X3028446Y537198D01*
X3026700Y537781D01*
X3025390Y539239D01*
X3024516Y540989D01*
X3024298Y543031D01*
X3024516Y545073D01*
X3025390Y546823D01*
X3026700Y548281D01*
X3028446Y548864D01*
X3029974Y548573D01*
X3031066Y547989D01*
X3032158Y546823D01*
G01X3063228Y537198D02*
X3061918Y537490D01*
X3060608Y538656D01*
X3059734Y540698D01*
X3059298Y543031D01*
X3059734Y545365D01*
X3060608Y547406D01*
X3061918Y548573D01*
X3063228Y548864D01*
X3064538Y548573D01*
X3065848Y547406D01*
X3066721Y545365D01*
X3066940Y543031D01*
X3066721Y540698D01*
X3065848Y538656D01*
X3064538Y537490D01*
X3063228Y537198D01*
G01X3077016Y548864D02*
Y540698D01*
X3077890Y538656D01*
X3079200Y537490D01*
X3080728Y537198D01*
X3082256Y537490D01*
X3083566Y538656D01*
X3084440Y540698D01*
G01Y537198D02*
Y548864D01*
G01X3098228Y554698D02*
Y537198D01*
G01X3095171Y548864D02*
X3101285D01*
G01X3115728Y537198D02*
Y554698D01*
G01X3133228Y548864D02*
Y537198D01*
G01Y553531D02*
X3132791Y553823D01*
Y554406D01*
X3133228Y554698D01*
X3133665Y554406D01*
Y553823D01*
X3133228Y553531D01*
G01X3147016Y537198D02*
Y548864D01*
G01Y545948D02*
X3147890Y547406D01*
X3149200Y548573D01*
X3150946Y548864D01*
X3152474Y548573D01*
X3153785Y547406D01*
X3154440Y545365D01*
Y537198D01*
G01X3164953Y545073D02*
X3171940D01*
X3171285Y547115D01*
X3170193Y548281D01*
X3168665Y548864D01*
X3167136Y548573D01*
X3165826Y547698D01*
X3164953Y545656D01*
X3164516Y543906D01*
Y542156D01*
X3164953Y540406D01*
X3166045Y538656D01*
X3167355Y537490D01*
X3168883Y537198D01*
X3170411Y537781D01*
X3171940Y539531D01*
G01X3185728Y536615D02*
X3185291Y536906D01*
Y537490D01*
X3185728Y537781D01*
X3186165Y537490D01*
Y536906D01*
X3185728Y536615D01*
G01X2835728Y583514D02*
Y571848D01*
G01Y588181D02*
X2835291Y588473D01*
Y589056D01*
X2835728Y589348D01*
X2836165Y589056D01*
Y588473D01*
X2835728Y588181D01*
G01X2849953Y573889D02*
X2851045Y572723D01*
X2852573Y571848D01*
X2853883D01*
X2855193Y572431D01*
X2856066Y573306D01*
X2856503Y574472D01*
X2856285Y576223D01*
X2855411Y577098D01*
X2851481Y578848D01*
X2850608Y580890D01*
X2851045Y582348D01*
X2851918Y583223D01*
X2853228Y583514D01*
X2854538Y583223D01*
X2855848Y582348D01*
G01X2883206Y571848D02*
Y589348D01*
X2893250Y571848D01*
Y589348D01*
G01X2905728Y571848D02*
X2903981Y572140D01*
X2902453Y573306D01*
X2901143Y575056D01*
X2900269Y577098D01*
X2899833Y579431D01*
Y581765D01*
X2900269Y584098D01*
X2901143Y586140D01*
X2902453Y587889D01*
X2903981Y589056D01*
X2905728Y589348D01*
X2907474Y589056D01*
X2909003Y587889D01*
X2910313Y586140D01*
X2911187Y584098D01*
X2911623Y581765D01*
Y579431D01*
X2911187Y577098D01*
X2910313Y575056D01*
X2909003Y573306D01*
X2907474Y572140D01*
X2905728Y571848D01*
G01X2923228Y589348D02*
Y571848D01*
G01X2918206Y589348D02*
X2928250D01*
G01X2954516Y583514D02*
Y575348D01*
X2955390Y573306D01*
X2956700Y572140D01*
X2958228Y571848D01*
X2959756Y572140D01*
X2961066Y573306D01*
X2961940Y575348D01*
G01Y571848D02*
Y583514D01*
G01X2972453Y573889D02*
X2973545Y572723D01*
X2975073Y571848D01*
X2976383D01*
X2977693Y572431D01*
X2978566Y573306D01*
X2979003Y574472D01*
X2978785Y576223D01*
X2977911Y577098D01*
X2973981Y578848D01*
X2973108Y580890D01*
X2973545Y582348D01*
X2974418Y583223D01*
X2975728Y583514D01*
X2977038Y583223D01*
X2978348Y582348D01*
G01X2989953Y579723D02*
X2996940D01*
X2996285Y581765D01*
X2995193Y582931D01*
X2993665Y583514D01*
X2992136Y583223D01*
X2990826Y582348D01*
X2989953Y580306D01*
X2989516Y578556D01*
Y576806D01*
X2989953Y575056D01*
X2991045Y573306D01*
X2992355Y572140D01*
X2993883Y571848D01*
X2995411Y572431D01*
X2996940Y574181D01*
G01X3014658Y589348D02*
Y571848D01*
G01Y574472D02*
X3013785Y573014D01*
X3012474Y572140D01*
X3010946Y571848D01*
X3009200Y572431D01*
X3007890Y573889D01*
X3007016Y575639D01*
X3006798Y577681D01*
X3007016Y579723D01*
X3007890Y581473D01*
X3009200Y582931D01*
X3010946Y583514D01*
X3012474Y583223D01*
X3013566Y582639D01*
X3014658Y581473D01*
G01X3045728Y583514D02*
Y571848D01*
G01Y588181D02*
X3045291Y588473D01*
Y589056D01*
X3045728Y589348D01*
X3046165Y589056D01*
Y588473D01*
X3045728Y588181D01*
G01X3059516Y571848D02*
Y583514D01*
G01Y580598D02*
X3060390Y582056D01*
X3061700Y583223D01*
X3063446Y583514D01*
X3064974Y583223D01*
X3066285Y582056D01*
X3066940Y580015D01*
Y571848D01*
G01X3098228Y589348D02*
Y571848D01*
G01X3095171Y583514D02*
X3101285D01*
G01X3112016Y571848D02*
Y589348D01*
G01Y580890D02*
X3113108Y582348D01*
X3114200Y583223D01*
X3115946Y583514D01*
X3117256Y583223D01*
X3118785Y582056D01*
X3119440Y580306D01*
Y571848D01*
G01X3133228Y583514D02*
Y571848D01*
G01Y588181D02*
X3132791Y588473D01*
Y589056D01*
X3133228Y589348D01*
X3133665Y589056D01*
Y588473D01*
X3133228Y588181D01*
G01X3147453Y573889D02*
X3148545Y572723D01*
X3150073Y571848D01*
X3151383D01*
X3152693Y572431D01*
X3153566Y573306D01*
X3154003Y574472D01*
X3153785Y576223D01*
X3152911Y577098D01*
X3148981Y578848D01*
X3148108Y580890D01*
X3148545Y582348D01*
X3149418Y583223D01*
X3150728Y583514D01*
X3152038Y583223D01*
X3153348Y582348D01*
G01X3185728Y571848D02*
Y589348D01*
G01X3207158Y571848D02*
Y583514D01*
G01Y581473D02*
X3206285Y582639D01*
X3204974Y583223D01*
X3203446Y583514D01*
X3201918Y582931D01*
X3200608Y581765D01*
X3199734Y580015D01*
X3199298Y577681D01*
X3199734Y575348D01*
X3200608Y573598D01*
X3201918Y572431D01*
X3203446Y571848D01*
X3204974Y572140D01*
X3206285Y573014D01*
X3207158Y574181D01*
G01X3216143Y566598D02*
X3217453Y566015D01*
X3219200Y566598D01*
X3220291Y567764D01*
X3221165Y569223D01*
X3222474Y573889D01*
X3225313Y583514D01*
G01X3218326D02*
X3222474Y573889D01*
G01X3234953Y579723D02*
X3241940D01*
X3241285Y581765D01*
X3240193Y582931D01*
X3238665Y583514D01*
X3237136Y583223D01*
X3235826Y582348D01*
X3234953Y580306D01*
X3234516Y578556D01*
Y576806D01*
X3234953Y575056D01*
X3236045Y573306D01*
X3237355Y572140D01*
X3238883Y571848D01*
X3240411Y572431D01*
X3241940Y574181D01*
G01X3252671Y571848D02*
Y583514D01*
G01Y581181D02*
X3253763Y582348D01*
X3254855Y583223D01*
X3256383Y583514D01*
X3257474Y583223D01*
X3258785Y582348D01*
G01X2760925Y605915D02*
X2770531Y618748D01*
G01X2765728Y621081D02*
Y603581D01*
G01X2770531Y605915D02*
X2760925Y618748D01*
G01X2759178Y612331D02*
X2772278D01*
G01X2797890D02*
X2803566D01*
G01X2830925Y606498D02*
Y623998D01*
X2835291D01*
X2837038Y623123D01*
X2838348Y621956D01*
X2839440Y620207D01*
X2840313Y618164D01*
X2840531Y615248D01*
X2840313Y612331D01*
X2839440Y610289D01*
X2838348Y608539D01*
X2837038Y607373D01*
X2835291Y606498D01*
X2830925D01*
G01X2849953Y614373D02*
X2856940D01*
X2856285Y616415D01*
X2855193Y617581D01*
X2853665Y618164D01*
X2852136Y617873D01*
X2850826Y616998D01*
X2849953Y614956D01*
X2849516Y613206D01*
Y611456D01*
X2849953Y609706D01*
X2851045Y607956D01*
X2852355Y606790D01*
X2853883Y606498D01*
X2855411Y607081D01*
X2856940Y608831D01*
G01X2867016Y606498D02*
Y618164D01*
G01Y615248D02*
X2867890Y616706D01*
X2869200Y617873D01*
X2870946Y618164D01*
X2872474Y617873D01*
X2873785Y616706D01*
X2874440Y614665D01*
Y606498D01*
G01X2888228D02*
X2886918Y606790D01*
X2885608Y607956D01*
X2884734Y609998D01*
X2884298Y612331D01*
X2884734Y614665D01*
X2885608Y616706D01*
X2886918Y617873D01*
X2888228Y618164D01*
X2889538Y617873D01*
X2890848Y616706D01*
X2891721Y614665D01*
X2891940Y612331D01*
X2891721Y609998D01*
X2890848Y607956D01*
X2889538Y606790D01*
X2888228Y606498D01*
G01X2905728Y623998D02*
Y606498D01*
G01X2902671Y618164D02*
X2908785D01*
G01X2919953Y614373D02*
X2926940D01*
X2926285Y616415D01*
X2925193Y617581D01*
X2923665Y618164D01*
X2922136Y617873D01*
X2920826Y616998D01*
X2919953Y614956D01*
X2919516Y613206D01*
Y611456D01*
X2919953Y609706D01*
X2921045Y607956D01*
X2922355Y606790D01*
X2923883Y606498D01*
X2925411Y607081D01*
X2926940Y608831D01*
G01X2937453Y608539D02*
X2938545Y607373D01*
X2940073Y606498D01*
X2941383D01*
X2942693Y607081D01*
X2943566Y607956D01*
X2944003Y609122D01*
X2943785Y610873D01*
X2942911Y611748D01*
X2938981Y613498D01*
X2938108Y615540D01*
X2938545Y616998D01*
X2939418Y617873D01*
X2940728Y618164D01*
X2942038Y617873D01*
X2943348Y616998D01*
G01X2975728Y623998D02*
Y606498D01*
G01X2972671Y618164D02*
X2978785D01*
G01X2989516Y606498D02*
Y623998D01*
G01Y615540D02*
X2990608Y616998D01*
X2991700Y617873D01*
X2993446Y618164D01*
X2994756Y617873D01*
X2996285Y616706D01*
X2996940Y614956D01*
Y606498D01*
G01X3014658D02*
Y618164D01*
G01Y616123D02*
X3013785Y617289D01*
X3012474Y617873D01*
X3010946Y618164D01*
X3009418Y617581D01*
X3008108Y616415D01*
X3007234Y614665D01*
X3006798Y612331D01*
X3007234Y609998D01*
X3008108Y608248D01*
X3009418Y607081D01*
X3010946Y606498D01*
X3012474Y606790D01*
X3013785Y607664D01*
X3014658Y608831D01*
G01X3028228Y623998D02*
Y606498D01*
G01X3025171Y618164D02*
X3031285D01*
G01X3056678Y623998D02*
X3059734Y606498D01*
X3063228Y623998D01*
X3066721Y606498D01*
X3069778Y623998D01*
G01X3078108D02*
X3083348D01*
G01X3080728D02*
Y606498D01*
G01X3078108D02*
X3083348D01*
G01X3093425D02*
Y623998D01*
X3097791D01*
X3099538Y623123D01*
X3100848Y621956D01*
X3101940Y620207D01*
X3102813Y618164D01*
X3103031Y615248D01*
X3102813Y612331D01*
X3101940Y610289D01*
X3100848Y608539D01*
X3099538Y607373D01*
X3097791Y606498D01*
X3093425D01*
G01X3115728Y623998D02*
Y606498D01*
G01X3110706Y623998D02*
X3120750D01*
G01X3128643Y606498D02*
Y623998D01*
G01X3137813D02*
Y606498D01*
G01Y615248D02*
X3128643D01*
G01X-7874Y-31496D02*
X-19685D01*
G01X-7874D02*
X-19685D01*
G01D02*
G03X-23622Y-35433I0J-3937D01*
G01D02*
Y-59055D01*
G01Y-35433D02*
Y-59055D01*
G01X-19685Y-31496D02*
G03X-23622Y-35433I0J-3937D01*
G01Y-59055D02*
G03X-19685Y-62992I3937J0D01*
G01D02*
X1972441D01*
G01X-19685D02*
X1972441D01*
G01X-23622Y-59055D02*
G03X-19685Y-62992I3937J0D01*
G01Y-23622D02*
X1972441D01*
G01X-19685D02*
X1972441D01*
G01X-19685D02*
X1972441D01*
G01X-19685D02*
X1972441D01*
G01X-23622Y622441D02*
Y-19685D01*
G01Y622441D02*
Y-19685D01*
G01Y622441D02*
Y-19685D01*
G01Y622441D02*
Y-19685D01*
G01D02*
G03X-19685Y-23622I3937J0D01*
G01X-23622Y-19685D02*
G03X-19685Y-23622I3937J0D01*
G01X-23622Y-19685D02*
G03X-19685Y-23622I3937J0D01*
G01X-23622Y-19685D02*
G03X-19685Y-23622I3937J0D01*
G01X1972441Y626378D02*
X-19685D01*
G01X1972441D02*
X-19685D01*
G01X1972441D02*
X-19685D01*
G01X1972441D02*
X-19685D01*
G01D02*
G03X-23622Y622441I0J-3937D01*
G01X-19685Y626378D02*
G03X-23622Y622441I0J-3937D01*
G01X-19685Y626378D02*
G03X-23622Y622441I0J-3937D01*
G01X-19685Y626378D02*
G03X-23622Y622441I0J-3937D01*
G01X-19685Y634252D02*
X-7874D01*
G01X-19685D02*
X-7874D01*
G01X-23622Y661811D02*
Y638189D01*
G01Y661811D02*
Y638189D01*
G01D02*
G03X-19685Y634252I3937J0D01*
G01X-23622Y638189D02*
G03X-19685Y634252I3937J0D01*
G01X1972441Y665748D02*
X-19685D01*
G01X1972441D02*
X-19685D01*
G01D02*
G03X-23622Y661811I0J-3937D01*
G01X-19685Y665748D02*
G03X-23622Y661811I0J-3937D01*
G01X-7874Y-31496D02*
G03Y-23622I0J3937D01*
G01Y-31496D02*
G03Y-23622I0J3937D01*
G01X22835D02*
G03Y-31496I0J-3937D01*
G01X137795D02*
X22835D01*
G01X137795D02*
X22835D01*
G01Y-23622D02*
G03Y-31496I0J-3937D01*
G01X0Y616535D02*
G03Y604724I0J-5905D01*
G01Y616535D02*
G03Y604724I0J-5905D01*
G01Y616535D02*
X2646D01*
G01X2644D02*
X0D01*
G01Y604724D02*
X2644D01*
G01X2646D02*
X0D01*
G01X2646D02*
X0D01*
G01D02*
X2644D01*
G01Y616535D02*
X0D01*
G01D02*
X2646D01*
G01X0D02*
G03Y604724I0J-5905D01*
G01Y616535D02*
G03Y604724I0J-5905D01*
G01X2646Y616535D02*
G03X7595Y618285I0J7874D01*
G01X2644Y616535D02*
G03X7593Y618285I0J7874D01*
G01X2644Y616535D02*
G03X7593Y618285I0J7874D01*
G01X7595Y602975D02*
G03X2646Y604724I-4948J-6125D01*
G01X7593Y602975D02*
G03X2644Y604724I-4948J-6125D01*
G01X7593Y602975D02*
G03X2644Y604724I-4948J-6125D01*
G01X7593Y602975D02*
G03X2644Y604724I-4948J-6125D01*
G01X7593Y602975D02*
G03X2644Y604724I-4948J-6125D01*
G01X7595Y602975D02*
G03X2646Y604724I-4948J-6125D01*
G01X2644Y616535D02*
G03X7593Y618285I0J7874D01*
G01X2644Y616535D02*
G03X7593Y618285I0J7874D01*
G01X2646Y616535D02*
G03X7595Y618285I0J7874D01*
G01Y602975D02*
G03Y618285I6186J7655D01*
G01X7593Y602975D02*
G03Y618285I6187J7655D01*
G01Y602975D02*
G03Y618285I6187J7655D01*
G01Y602975D02*
G03Y618285I6187J7655D01*
G01Y602975D02*
G03Y618285I6187J7655D01*
G01X7595Y602975D02*
G03Y618285I6186J7655D01*
G01X-7874Y626378D02*
G03Y634252I0J3937D01*
G01Y626378D02*
G03Y634252I0J3937D01*
G01X22835D02*
G03Y626378I0J-3937D01*
G01Y634252D02*
X137795D01*
G01X22835D02*
X137795D01*
G01X22835D02*
G03Y626378I0J-3937D01*
G01X168504Y-23622D02*
G03Y-31496I0J-3937D01*
G01X137795D02*
G03Y-23622I0J3937D01*
G01X341732Y-31496D02*
X168504D01*
G01X341732D02*
X168504D01*
G01X137795D02*
G03Y-23622I0J3937D01*
G01X168504D02*
G03Y-31496I0J-3937D01*
G01Y634252D02*
G03Y626378I0J-3937D01*
G01X137795D02*
G03Y634252I0J3937D01*
G01X168504D02*
X341732D01*
G01X168504D02*
X341732D01*
G01X137795Y626378D02*
G03Y634252I0J3937D01*
G01X168504D02*
G03Y626378I0J-3937D01*
G01X341732Y-31496D02*
G03Y-23622I0J3937D01*
G01Y-31496D02*
G03Y-23622I0J3937D01*
G01Y626378D02*
G03Y634252I0J3937D01*
G01Y626378D02*
G03Y634252I0J3937D01*
G01X372441Y-23622D02*
G03Y-31496I0J-3937D01*
G01X529921D02*
X372441D01*
G01X529921D02*
X372441D01*
G01Y-23622D02*
G03Y-31496I0J-3937D01*
G01Y634252D02*
G03Y626378I0J-3937D01*
G01Y634252D02*
X529921D01*
G01X372441D02*
X529921D01*
G01X372441D02*
G03Y626378I0J-3937D01*
G01X529921Y-31496D02*
G03Y-23622I0J3937D01*
G01Y-31496D02*
G03Y-23622I0J3937D01*
G01Y626378D02*
G03Y634252I0J3937D01*
G01Y626378D02*
G03Y634252I0J3937D01*
G01X560630Y-23622D02*
G03Y-31496I0J-3937D01*
G01X788976D02*
X560630D01*
G01X788976D02*
X560630D01*
G01Y-23622D02*
G03Y-31496I0J-3937D01*
G01Y634252D02*
G03Y626378I0J-3937D01*
G01Y634252D02*
X788976D01*
G01X560630D02*
X788976D01*
G01X560630D02*
G03Y626378I0J-3937D01*
G01X684760Y-15529D02*
G03Y-219I6187J7655D01*
G01X684759Y-15529D02*
G03X679809Y-13780I-4948J-6125D01*
G01X679811Y-1969D02*
G03X684760Y-219I0J7874D01*
G01X677165Y-1969D02*
X679811D01*
G01X677165D02*
G03Y-13780I0J-5906D01*
G01D02*
X679809D01*
G01X684760Y602975D02*
G03Y618285I6187J7655D01*
G01X684759Y602975D02*
G03Y618285I6186J7655D01*
G01Y602975D02*
G03Y618285I6186J7655D01*
G01Y602975D02*
G03Y618285I6186J7655D01*
G01Y602975D02*
G03Y618285I6186J7655D01*
G01X684760Y602975D02*
G03Y618285I6187J7655D01*
G01X679811Y616535D02*
G03X684760Y618285I0J7874D01*
G01X679809Y616535D02*
G03X684759Y618285I0J7874D01*
G01X679809Y616535D02*
G03X684759Y618285I0J7874D01*
G01X684760Y602975D02*
G03X679811Y604724I-4948J-6125D01*
G01X684759Y602975D02*
G03X679809Y604724I-4948J-6125D01*
G01X684759Y602975D02*
G03X679809Y604724I-4948J-6125D01*
G01X684759Y602975D02*
G03X679809Y604724I-4948J-6125D01*
G01X684759Y602975D02*
G03X679809Y604724I-4948J-6125D01*
G01X684760Y602975D02*
G03X679811Y604724I-4948J-6125D01*
G01X679809Y616535D02*
G03X684759Y618285I0J7874D01*
G01X679809Y616535D02*
G03X684759Y618285I0J7874D01*
G01X679811Y616535D02*
G03X684760Y618285I0J7874D01*
G01X677165Y616535D02*
X679811D01*
G01X677165D02*
G03Y604724I0J-5905D01*
G01D02*
X679809D01*
G01X788976Y-31496D02*
G03Y-23622I0J3937D01*
G01Y-31496D02*
G03Y-23622I0J3937D01*
G01X819685D02*
G03Y-31496I0J-3937D01*
G01X975591D02*
X819685D01*
G01X975591D02*
X819685D01*
G01Y-23622D02*
G03Y-31496I0J-3937D01*
G01X788976Y626378D02*
G03Y634252I0J3937D01*
G01Y626378D02*
G03Y634252I0J3937D01*
G01X819685D02*
G03Y626378I0J-3937D01*
G01Y634252D02*
X975591D01*
G01X819685D02*
X975591D01*
G01X819685D02*
G03Y626378I0J-3937D01*
G01X975591Y-31496D02*
G03Y-23622I0J3937D01*
G01Y-31496D02*
G03Y-23622I0J3937D01*
G01X1006299D02*
G03Y-31496I0J-3937D01*
G01X1162205D02*
X1006299D01*
G01X1162205D02*
X1006299D01*
G01Y-23622D02*
G03Y-31496I0J-3937D01*
G01Y634252D02*
X1162205D01*
G01X1006299D02*
X1162205D01*
G01X975591Y626378D02*
G03Y634252I0J3937D01*
G01Y626378D02*
G03Y634252I0J3937D01*
G01X1006299D02*
G03Y626378I0J-3937D01*
G01Y634252D02*
G03Y626378I0J-3937D01*
G01X1162205Y-31496D02*
G03Y-23622I0J3937D01*
G01Y-31496D02*
G03Y-23622I0J3937D01*
G01X1192913D02*
G03Y-31496I0J-3937D01*
G01X1398425D02*
X1192913D01*
G01X1398425D02*
X1192913D01*
G01Y-23622D02*
G03Y-31496I0J-3937D01*
G01Y634252D02*
X1394488D01*
G01X1192913D02*
X1394488D01*
G01X1162205Y626378D02*
G03Y634252I0J3937D01*
G01Y626378D02*
G03Y634252I0J3937D01*
G01X1192913D02*
G03Y626378I0J-3937D01*
G01Y634252D02*
G03Y626378I0J-3937D01*
G01X1398425Y-31496D02*
G03Y-23622I0J3937D01*
G01Y-31496D02*
G03Y-23622I0J3937D01*
G01X1405512Y-1968D02*
G03Y-13779I0J-5906D01*
G01Y-1968D02*
G03Y-13779I0J-5906D01*
G01Y-1968D02*
G03Y-13779I0J-5906D01*
G01Y-1968D02*
G03Y-13779I0J-5906D01*
G01X1394488Y626378D02*
G03Y634252I0J3937D01*
G01Y626378D02*
G03Y634252I0J3937D01*
G01X1405512Y616535D02*
G03Y604724I0J-5905D01*
G01Y616535D02*
G03Y604724I0J-5905D01*
G01Y616535D02*
G03Y604724I0J-5905D01*
G01Y616535D02*
G03Y604724I0J-5905D01*
G01X1429134Y-23622D02*
G03Y-31496I0J-3937D01*
G01X1851181D02*
X1429134D01*
G01X1851181D02*
X1429134D01*
G01Y-23622D02*
G03Y-31496I0J-3937D01*
G01X1413107Y-15529D02*
G03Y-218I6186J7655D01*
G01X1413105Y-15529D02*
G03Y-218I6186J7655D01*
G01Y-15529D02*
G03Y-218I6186J7655D01*
G01Y-15529D02*
G03Y-218I6186J7655D01*
G01Y-15529D02*
G03Y-218I6186J7655D01*
G01X1413107Y-15529D02*
G03Y-218I6186J7655D01*
G01X1408157Y-1968D02*
G03X1413107Y-218I1J7874D01*
G01X1408156Y-1968D02*
G03X1413105Y-218I0J7874D01*
G01X1408156Y-1968D02*
G03X1413105Y-218I0J7874D01*
G01X1408156Y-1968D02*
G03X1413105Y-218I0J7874D01*
G01X1408156Y-1968D02*
G03X1413105Y-218I0J7874D01*
G01X1408157Y-1968D02*
G03X1413107Y-218I1J7874D01*
G01Y-15529D02*
G03X1408157Y-13779I-4949J-6124D01*
G01X1413105Y-15529D02*
G03X1408156Y-13779I-4949J-6124D01*
G01X1413105Y-15529D02*
G03X1408156Y-13779I-4949J-6124D01*
G01X1413105Y-15529D02*
G03X1408156Y-13779I-4949J-6124D01*
G01X1413105Y-15529D02*
G03X1408156Y-13779I-4949J-6124D01*
G01X1413107Y-15529D02*
G03X1408157Y-13779I-4949J-6124D01*
G01X1405512D02*
X1408156D01*
G01X1408157D02*
X1405512D01*
G01X1408157D02*
X1405512D01*
G01D02*
X1408156D01*
G01X1405512Y-1968D02*
X1408157D01*
G01X1408156D02*
X1405512D01*
G01X1408156D02*
X1405512D01*
G01D02*
X1408157D01*
G01X1425197Y634252D02*
X1851181D01*
G01X1425197D02*
X1851181D01*
G01X1425197D02*
G03Y626378I0J-3937D01*
G01Y634252D02*
G03Y626378I0J-3937D01*
G01X1408157Y616535D02*
G03X1413107Y618285I1J7874D01*
G01X1408156Y616535D02*
G03X1413105Y618285I0J7874D01*
G01X1408156Y616535D02*
G03X1413105Y618285I0J7874D01*
G01X1413107Y602975D02*
G03Y618285I6186J7655D01*
G01X1413105Y602975D02*
G03Y618285I6187J7655D01*
G01Y602975D02*
G03Y618285I6187J7655D01*
G01X1413107Y602975D02*
G03X1408157Y604724I-4948J-6125D01*
G01X1413105Y602975D02*
G03X1408156Y604724I-4948J-6125D01*
G01X1413105Y602975D02*
G03X1408156Y604724I-4948J-6125D01*
G01X1413105Y602975D02*
G03X1408156Y604724I-4948J-6125D01*
G01X1413105Y602975D02*
G03X1408156Y604724I-4948J-6125D01*
G01X1413107Y602975D02*
G03X1408157Y604724I-4948J-6125D01*
G01X1413105Y602975D02*
G03Y618285I6187J7655D01*
G01Y602975D02*
G03Y618285I6187J7655D01*
G01X1413107Y602975D02*
G03Y618285I6186J7655D01*
G01X1408156Y616535D02*
G03X1413105Y618285I0J7874D01*
G01X1408156Y616535D02*
G03X1413105Y618285I0J7874D01*
G01X1408157Y616535D02*
G03X1413107Y618285I1J7874D01*
G01X1405512Y616535D02*
X1408157D01*
G01X1408156D02*
X1405512D01*
G01Y604724D02*
X1408156D01*
G01X1408157D02*
X1405512D01*
G01X1408157D02*
X1405512D01*
G01D02*
X1408156D01*
G01Y616535D02*
X1405512D01*
G01D02*
X1408157D01*
G01X1685866Y267244D02*
X1883780D01*
G01X1685866D02*
X1883780D01*
G01X1685866D02*
X1883780D01*
G01X1685866D02*
X1883780D01*
G01X1681929Y271181D02*
G03X1685866Y267244I3937J0D01*
G01X1681929Y271181D02*
G03X1685866Y267244I3937J0D01*
G01X1681929Y271181D02*
G03X1685866Y267244I3937J0D01*
G01X1681929Y271181D02*
G03X1685866Y267244I3937J0D01*
G01X1681929Y428661D02*
Y271181D01*
G01Y428661D02*
Y271181D01*
G01Y428661D02*
Y271181D01*
G01Y428661D02*
Y271181D01*
G01X1685866Y432598D02*
G03X1681929Y428661I0J-3937D01*
G01X1685866Y432598D02*
G03X1681929Y428661I0J-3937D01*
G01X1972441Y432598D02*
X1685866D01*
G01X1972441D02*
X1685866D01*
G01X1972441D02*
X1685866D01*
G01X1972441D02*
X1685866D01*
G01D02*
G03X1681929Y428661I0J-3937D01*
G01X1685866Y432598D02*
G03X1681929Y428661I0J-3937D01*
G01X1851181Y-31496D02*
G03Y-23622I0J3937D01*
G01Y-31496D02*
G03Y-23622I0J3937D01*
G01X1881890D02*
G03Y-31496I0J-3937D01*
G01X1972441D02*
X1881890D01*
G01X1972441D02*
X1881890D01*
G01Y-23622D02*
G03Y-31496I0J-3937D01*
G01X1861926Y-15529D02*
G03X1856976Y-13780I-4948J-6125D01*
G01X1861924Y-15529D02*
G03X1856975Y-13780I-4948J-6125D01*
G01X1861924Y-15529D02*
G03X1856975Y-13780I-4948J-6125D01*
G01X1861924Y-15529D02*
G03X1856975Y-13780I-4948J-6125D01*
G01X1861924Y-15529D02*
G03X1856975Y-13780I-4948J-6125D01*
G01X1861926Y-15529D02*
G03X1856976Y-13780I-4948J-6125D01*
G01Y-1969D02*
G03X1861926Y-219I0J7874D01*
G01X1856975Y-1969D02*
G03X1861924Y-219I0J7874D01*
G01X1856975Y-1969D02*
G03X1861924Y-219I0J7874D01*
G01X1861926Y-15529D02*
G03Y-219I6186J7655D01*
G01X1861924Y-15529D02*
G03Y-219I6186J7655D01*
G01Y-15529D02*
G03Y-219I6186J7655D01*
G01Y-15529D02*
G03Y-219I6186J7655D01*
G01Y-15529D02*
G03Y-219I6186J7655D01*
G01X1861926Y-15529D02*
G03Y-219I6186J7655D01*
G01X1856975Y-1969D02*
G03X1861924Y-219I0J7874D01*
G01X1856975Y-1969D02*
G03X1861924Y-219I0J7874D01*
G01X1856976Y-1969D02*
G03X1861926Y-219I0J7874D01*
G01X1854331Y-1969D02*
G03Y-13780I0J-5906D01*
G01Y-1969D02*
G03Y-13780I0J-5906D01*
G01D02*
X1856975D01*
G01X1856976D02*
X1854331D01*
G01X1856976D02*
X1854331D01*
G01D02*
X1856975D01*
G01X1854331Y-1969D02*
G03Y-13780I0J-5906D01*
G01Y-1969D02*
G03Y-13780I0J-5906D01*
G01Y-1969D02*
X1856976D01*
G01X1856975D02*
X1854331D01*
G01X1856975D02*
X1854331D01*
G01D02*
X1856976D01*
G01X1891654Y246772D02*
X1972441D01*
G01X1891654D02*
X1972441D01*
G01X1891654D02*
X1972441D01*
G01X1891654D02*
X1972441D01*
G01X1887717Y250709D02*
G03X1891654Y246772I3937J0D01*
G01X1887717Y250709D02*
G03X1891654Y246772I3937J0D01*
G01X1887717Y263307D02*
Y250709D01*
G01Y263307D02*
Y250709D01*
G01Y263307D02*
Y250709D01*
G01Y263307D02*
Y250709D01*
G01D02*
G03X1891654Y246772I3937J0D01*
G01X1887717Y250709D02*
G03X1891654Y246772I3937J0D01*
G01X1887717Y263307D02*
G03X1883780Y267244I-3937J0D01*
G01X1887717Y263307D02*
G03X1883780Y267244I-3937J0D01*
G01X1887717Y263307D02*
G03X1883780Y267244I-3937J0D01*
G01X1887717Y263307D02*
G03X1883780Y267244I-3937J0D01*
G01X1881890Y634252D02*
G03Y626378I0J-3937D01*
G01Y634252D02*
X1972441D01*
G01X1881890D02*
X1972441D01*
G01X1881890D02*
G03Y626378I0J-3937D01*
G01X1851181D02*
G03Y634252I0J3937D01*
G01Y626378D02*
G03Y634252I0J3937D01*
G01X1856976Y616535D02*
G03X1861926Y618285I0J7874D01*
G01X1856975Y616535D02*
G03X1861924Y618285I0J7874D01*
G01X1856975Y616535D02*
G03X1861924Y618285I0J7874D01*
G01X1861926Y602975D02*
G03Y618285I6186J7655D01*
G01X1861924Y602975D02*
G03Y618285I6186J7655D01*
G01Y602975D02*
G03Y618285I6186J7655D01*
G01Y602975D02*
G03Y618285I6186J7655D01*
G01Y602975D02*
G03Y618285I6186J7655D01*
G01X1861926Y602975D02*
G03Y618285I6186J7655D01*
G01X1856975Y616535D02*
G03X1861924Y618285I0J7874D01*
G01X1856975Y616535D02*
G03X1861924Y618285I0J7874D01*
G01X1856976Y616535D02*
G03X1861926Y618285I0J7874D01*
G01Y602975D02*
G03X1856976Y604724I-4948J-6125D01*
G01X1861924Y602975D02*
G03X1856975Y604724I-4948J-6125D01*
G01X1861924Y602975D02*
G03X1856975Y604724I-4948J-6125D01*
G01X1861924Y602975D02*
G03X1856975Y604724I-4948J-6125D01*
G01X1861924Y602975D02*
G03X1856975Y604724I-4948J-6125D01*
G01X1861926Y602975D02*
G03X1856976Y604724I-4948J-6125D01*
G01X1854331Y616535D02*
G03Y604724I0J-5905D01*
G01Y616535D02*
G03Y604724I0J-5905D01*
G01D02*
X1856975D01*
G01X1856976D02*
X1854331D01*
G01X1856976D02*
X1854331D01*
G01D02*
X1856975D01*
G01X1854331Y616535D02*
G03Y604724I0J-5905D01*
G01Y616535D02*
G03Y604724I0J-5905D01*
G01Y616535D02*
X1856976D01*
G01X1856975D02*
X1854331D01*
G01X1856975D02*
X1854331D01*
G01D02*
X1856976D01*
G01X1972441Y-11811D02*
X1906890D01*
G01X1904921Y-9843D02*
G03X1906890Y-11811I1969J1D01*
G01X1904921Y53150D02*
Y-9843D01*
G01X1972441Y-11811D02*
X1906890D01*
G01X1904921Y-9843D02*
G03X1906890Y-11811I1969J1D01*
G01X1904921Y53150D02*
Y-9843D01*
G01X1923071Y53150D02*
Y-9843D01*
G01X1940787Y-3937D02*
X1972441D01*
G01X1940787D02*
G03X1938819Y-5906I0J-1968D01*
G01Y-9843D02*
Y-5906D01*
G01Y-9843D02*
G03X1940787Y-11811I1968J0D01*
G01X1921102D02*
G03X1923071Y-9843I0J1969D01*
G01X1906890Y55118D02*
G03X1904921Y53150I0J-1969D01*
G01X1972441Y55118D02*
X1906890D01*
G01X1972441D02*
X1906890D01*
G01X1972441D02*
X1906890D01*
G01X1972441D02*
X1906890D01*
G01D02*
G03X1904921Y53150I0J-1969D01*
G01X1923071D02*
G03X1921102Y55118I-1969J-1D01*
G01X1940787D02*
G03X1938819Y53150I0J-1968D01*
G01Y49213D02*
Y53150D01*
G01Y49213D02*
G03X1940787Y47244I1968J-1D01*
G01X1972441D02*
X1940787D01*
G01X1976378Y-35433D02*
G03X1972441Y-31496I-3937J0D01*
G01X1976378Y-59055D02*
Y-35433D01*
G01Y-59055D02*
Y-35433D01*
G01D02*
G03X1972441Y-31496I-3937J0D01*
G01Y-62992D02*
G03X1976378Y-59055I0J3937D01*
G01X1972441Y-62992D02*
G03X1976378Y-59055I0J3937D01*
G01X1972441Y-23622D02*
G03X1976378Y-19685I0J3937D01*
G01X1972441Y-23622D02*
G03X1976378Y-19685I0J3937D01*
G01X1972441Y-23622D02*
G03X1976378Y-19685I0J3937D01*
G01X1972441Y-23622D02*
G03X1976378Y-19685I0J3937D01*
G01D02*
Y-15748D01*
G01Y-19685D02*
Y-15748D01*
G01Y-19685D02*
Y-15748D01*
G01Y-19685D02*
Y-15748D01*
G01D02*
G03X1972441Y-11811I-3937J0D01*
G01X1976378Y-15748D02*
G03X1972441Y-11811I-3937J0D01*
G01X1976378Y-15748D02*
G03X1972441Y-11811I-3937J0D01*
G01X1976378Y-15748D02*
G03X1972441Y-11811I-3937J0D01*
G01X1976378Y0D02*
Y43307D01*
G01X1972441Y-3937D02*
G03X1976378Y0I0J3937D01*
G01X1972441Y55118D02*
G03X1976378Y59055I0J3937D01*
G01X1972441Y55118D02*
G03X1976378Y59055I0J3937D01*
G01X1972441Y55118D02*
G03X1976378Y59055I0J3937D01*
G01X1972441Y55118D02*
G03X1976378Y59055I0J3937D01*
G01D02*
Y242835D01*
G01Y59055D02*
Y242835D01*
G01Y59055D02*
Y242835D01*
G01Y59055D02*
Y242835D01*
G01Y43307D02*
G03X1972441Y47244I-3937J0D01*
G01X1976378Y242835D02*
G03X1972441Y246772I-3937J0D01*
G01X1976378Y242835D02*
G03X1972441Y246772I-3937J0D01*
G01X1976378Y242835D02*
G03X1972441Y246772I-3937J0D01*
G01X1976378Y242835D02*
G03X1972441Y246772I-3937J0D01*
G01Y432598D02*
G03X1976378Y436535I0J3937D01*
G01X1972441Y432598D02*
G03X1976378Y436535I0J3937D01*
G01X1972441Y432598D02*
G03X1976378Y436535I0J3937D01*
G01X1972441Y432598D02*
G03X1976378Y436535I0J3937D01*
G01D02*
Y622441D01*
G01Y436535D02*
Y622441D01*
G01Y436535D02*
Y622441D01*
G01Y436535D02*
Y622441D01*
G01D02*
G03X1972441Y626378I-3937J0D01*
G01X1976378Y622441D02*
G03X1972441Y626378I-3937J0D01*
G01X1976378Y622441D02*
G03X1972441Y626378I-3937J0D01*
G01X1976378Y622441D02*
G03X1972441Y626378I-3937J0D01*
G01Y634252D02*
G03X1976378Y638189I0J3937D01*
G01X1972441Y634252D02*
G03X1976378Y638189I0J3937D01*
G01D02*
Y661811D01*
G01Y638189D02*
Y661811D01*
G01D02*
G03X1972441Y665748I-3937J0D01*
G01X1976378Y661811D02*
G03X1972441Y665748I-3937J0D01*
G54D12*
G01X144165Y-45915D02*
X140500Y-42250D01*
G01X439822Y-45915D02*
X144165D01*
G01X146394Y-42265D02*
X439822D01*
G01X163777Y11814D02*
X163477Y12114D01*
G01X163777Y4023D02*
Y11814D01*
G01X150391Y4024D02*
Y12114D01*
G01X150392Y4023D02*
X150391Y4024D01*
G01X147045Y22133D02*
Y17157D01*
G01X132959Y10133D02*
Y12114D01*
G01X133659Y9433D02*
X132959Y10133D01*
G01X133659Y4023D02*
Y9433D01*
G01X130313Y22133D02*
Y17157D01*
G01X160431Y22133D02*
Y17157D01*
G01X126966Y11814D02*
Y4023D01*
G01X126666Y12114D02*
X126966Y11814D01*
G01X157084Y4023D02*
Y12114D01*
G01X170470Y9433D02*
X169770Y10133D01*
G01X123620Y22133D02*
Y17157D01*
G01X153738Y22133D02*
Y17157D01*
G01X167124Y22133D02*
Y17157D01*
G01X126966Y87414D02*
X126666Y87714D01*
G01X126966Y79623D02*
Y87414D01*
G01X147045Y59933D02*
Y54957D01*
G01X167124Y92757D02*
Y97733D01*
G01X163777Y87414D02*
X163477Y87714D01*
G01X163777Y79623D02*
Y87414D01*
G01X123620Y92757D02*
Y97733D01*
G01X163777Y49614D02*
X163477Y49914D01*
G01X163777Y41823D02*
Y49614D01*
G01X170470Y47123D02*
X169770Y47823D01*
G01X123620Y59933D02*
Y54957D01*
G01X130313Y92757D02*
Y97733D01*
G01X153738Y92757D02*
Y97733D01*
G01Y59933D02*
Y54957D01*
G01X157084Y41823D02*
Y49914D01*
G01X150391Y79624D02*
Y87714D01*
G01X150392Y79623D02*
X150391Y79624D01*
G01X126666Y47827D02*
Y49914D01*
G01X126966Y47527D02*
X126666Y47827D01*
G01X126966Y41823D02*
Y47527D01*
G01X130313Y54957D02*
Y59933D01*
G01X132959Y47933D02*
Y49914D01*
G01X133659Y47233D02*
X132959Y47933D01*
G01X133659Y41823D02*
Y47233D01*
G01X132959Y85733D02*
Y87714D01*
G01X133659Y85033D02*
X132959Y85733D01*
G01X133659Y79623D02*
Y85033D01*
G01X160431Y92757D02*
Y97733D01*
G01X157084Y87714D02*
Y79623D01*
G01X167124Y59933D02*
Y54957D01*
G01X147045Y92757D02*
Y97733D01*
G01X160431Y59933D02*
Y54957D01*
G01X170470Y85033D02*
X169770Y85733D01*
G01X150391Y43744D02*
Y49914D01*
G01X150392Y43743D02*
X150391Y43744D01*
G01X150392Y41823D02*
Y43743D01*
G01X153738Y523134D02*
Y518157D01*
G01X160431Y523134D02*
Y518157D01*
G01X130313Y523134D02*
Y518157D01*
G01X163777Y512814D02*
X163477Y513114D01*
G01X163777Y505024D02*
Y512814D01*
G01X123620Y523134D02*
Y518157D01*
G01X132959Y511133D02*
Y513114D01*
G01X133659Y510433D02*
X132959Y511133D01*
G01X133659Y505024D02*
Y510433D01*
G01X157084Y505024D02*
Y513114D01*
G01X150391Y505024D02*
Y513114D01*
G01X150392Y505024D02*
X150391D01*
G01X147045Y523134D02*
Y518157D01*
G01X126966Y512814D02*
X126666Y513114D01*
G01X126966Y505024D02*
Y512814D01*
G01X170470Y510433D02*
X169770Y511133D01*
G01X167124Y523134D02*
Y518157D01*
G01X170470Y586033D02*
X169770Y586733D01*
G01X123620Y560934D02*
Y555957D01*
G01X132959Y586733D02*
Y588714D01*
G01X133659Y586033D02*
X132959Y586733D01*
G01X133659Y580624D02*
Y586033D01*
G01X157084Y580624D02*
Y588714D01*
G01X170470Y548233D02*
X169770Y548933D01*
G01X147045Y560934D02*
Y555957D01*
G01X167124Y560934D02*
Y555957D01*
G01X132959Y548933D02*
Y550914D01*
G01X133659Y548233D02*
X132959Y548933D01*
G01X133659Y542824D02*
Y548233D01*
G01X150391Y580624D02*
Y588714D01*
G01X150392Y580624D02*
X150391D01*
G01X160431Y560934D02*
Y555957D01*
G01X163777Y580624D02*
Y588414D01*
G01X126966Y580624D02*
Y588414D01*
G01X163777Y550614D02*
X163477Y550914D01*
G01X163777Y542824D02*
Y550614D01*
G01X130313Y560934D02*
Y555957D01*
G01X153738Y560934D02*
Y555957D01*
G01X157084Y542824D02*
Y550914D01*
G01X150391Y542824D02*
Y550914D01*
G01X150392Y542824D02*
X150391D01*
G01X126966Y550614D02*
X126666Y550914D01*
G01X126966Y542824D02*
Y550614D01*
G01X160431Y598734D02*
Y593757D01*
G01X167124Y598734D02*
Y593757D01*
G01X123620Y598734D02*
Y593757D01*
G01X153738Y598734D02*
Y593757D01*
G01X163777Y588414D02*
X163477Y588714D01*
G01X130313Y598734D02*
Y593757D01*
G01X147045Y598734D02*
Y593757D01*
G01X126966Y588414D02*
X126666Y588714D01*
G01X193895Y4024D02*
Y12114D01*
G01X193896Y4023D02*
X193895Y4024D01*
G01X203935Y22133D02*
Y17157D01*
G01X190549Y22133D02*
Y17157D01*
G01X227360Y22133D02*
Y17157D01*
G01X183856Y22133D02*
Y17157D01*
G01X200588Y11814D02*
X200288Y12114D01*
G01X200588Y4023D02*
Y11814D01*
G01X224013Y4024D02*
Y12114D01*
G01X224014Y4023D02*
X224013Y4024D01*
G01X230706D02*
Y12114D01*
G01X230707Y4023D02*
X230706Y4024D01*
G01X197242Y22133D02*
Y17157D01*
G01X169770Y10133D02*
Y12114D01*
G01X170470Y4023D02*
Y9433D01*
G01X220667Y22133D02*
Y17157D01*
G01X206581Y10133D02*
Y12114D01*
G01X207281Y9433D02*
X206581Y10133D01*
G01X207281Y4023D02*
Y9433D01*
G01X187202Y4024D02*
Y12114D01*
G01X187203Y4023D02*
X187202Y4024D01*
G01X227360Y92757D02*
Y97733D01*
G01X230706Y79624D02*
Y87714D01*
G01X230707Y79623D02*
X230706Y79624D01*
G01X190549Y92757D02*
Y97733D01*
G01X197242Y92757D02*
Y97733D01*
G01X230706Y42844D02*
Y49914D01*
G01X230707Y42843D02*
X230706Y42844D01*
G01X230707Y41823D02*
Y42843D01*
G01X206581Y47933D02*
Y49914D01*
G01X207281Y47233D02*
X206581Y47933D01*
G01X207281Y41823D02*
Y47233D01*
G01X224013Y79624D02*
Y87714D01*
G01X224014Y79623D02*
X224013Y79624D01*
G01X193895D02*
Y87714D01*
G01X193896Y79623D02*
X193895Y79624D01*
G01X169770Y47823D02*
Y49914D01*
G01X170470Y41823D02*
Y47123D01*
G01X203935Y92757D02*
Y97733D01*
G01X197242Y59933D02*
Y54957D01*
G01X224013Y43744D02*
Y49914D01*
G01X224014Y43743D02*
X224013Y43744D01*
G01X224014Y41823D02*
Y43743D01*
G01X200588Y49614D02*
X200288Y49914D01*
G01X200588Y41823D02*
Y49614D01*
G01X193895Y42544D02*
Y49914D01*
G01X193896Y42543D02*
X193895Y42544D01*
G01X193896Y41823D02*
Y42543D01*
G01X190549Y59933D02*
Y54957D01*
G01X183856Y59933D02*
Y54957D01*
G01X187202Y79624D02*
Y87714D01*
G01X187203Y79623D02*
X187202Y79624D01*
G01X220667Y92761D02*
Y97733D01*
G01Y59933D02*
Y54957D01*
G01X206581Y85733D02*
Y87714D01*
G01X207281Y85033D02*
X206581Y85733D01*
G01X207281Y79623D02*
Y85033D01*
G01X200588Y87414D02*
X200288Y87714D01*
G01X200588Y79623D02*
Y87414D01*
G01X187202Y42444D02*
Y49914D01*
G01X187203Y42443D02*
X187202Y42444D01*
G01X187203Y41823D02*
Y42443D01*
G01X203935Y59933D02*
Y54957D01*
G01X183856Y92757D02*
Y97733D01*
G01X169770Y85733D02*
Y87714D01*
G01X170470Y79623D02*
Y85033D01*
G01X227360Y59933D02*
Y54957D01*
G01X197242Y523134D02*
Y518157D01*
G01X193895Y505024D02*
Y513114D01*
G01X193896Y505024D02*
X193895D01*
G01X200588Y512814D02*
X200288Y513114D01*
G01X200588Y505024D02*
Y512814D01*
G01X206581Y511133D02*
Y513114D01*
G01X207281Y510433D02*
X206581Y511133D01*
G01X207281Y505024D02*
Y510433D01*
G01X203935Y523134D02*
Y518157D01*
G01X227360Y523134D02*
Y518157D01*
G01X190549Y523134D02*
Y518157D01*
G01X183856Y523134D02*
Y518157D01*
G01X230706Y505024D02*
Y513114D01*
G01X230707Y505024D02*
X230706D01*
G01X220667Y523134D02*
Y518161D01*
G01X187202Y505024D02*
Y513114D01*
G01X187203Y505024D02*
X187202D01*
G01X224013D02*
Y513114D01*
G01X224014Y505024D02*
X224013D01*
G01X169770Y511133D02*
Y513114D01*
G01X170470Y505024D02*
Y510433D01*
G01X169770Y586733D02*
Y588714D01*
G01X170470Y580624D02*
Y586033D01*
G01X206581Y586733D02*
Y588714D01*
G01X207281Y586033D02*
X206581Y586733D01*
G01X207281Y580624D02*
Y586033D01*
G01X200588Y550614D02*
X200288Y550914D01*
G01X200588Y542824D02*
Y550614D01*
G01X187202Y580624D02*
Y588714D01*
G01X187203Y580624D02*
X187202D01*
G01X206581Y548933D02*
Y550914D01*
G01X207281Y548233D02*
X206581Y548933D01*
G01X207281Y542824D02*
Y548233D01*
G01X169770Y548933D02*
Y550914D01*
G01X170470Y542824D02*
Y548233D01*
G01X224013Y542824D02*
Y550914D01*
G01X224014Y542824D02*
X224013D01*
G01X187202D02*
Y550914D01*
G01X187203Y542824D02*
X187202D01*
G01X227360Y560934D02*
Y555957D01*
G01X197242Y560934D02*
Y555957D01*
G01X203935Y560934D02*
Y555957D01*
G01X200588Y580624D02*
Y588414D01*
G01X230706Y542824D02*
Y550914D01*
G01X230707Y542824D02*
X230706D01*
G01X220667Y560934D02*
Y555961D01*
G01X193895Y542824D02*
Y550914D01*
G01X193896Y542824D02*
X193895D01*
G01X190549Y560934D02*
Y555957D01*
G01X224013Y580624D02*
Y588714D01*
G01X224014Y580624D02*
X224013D01*
G01X183856Y560934D02*
Y555957D01*
G01X193895Y580624D02*
Y588714D01*
G01X193896Y580624D02*
X193895D01*
G01X230706D02*
Y588714D01*
G01X230707Y580624D02*
X230706D01*
G01X227360Y598734D02*
Y593757D01*
G01X190549Y598734D02*
Y593757D01*
G01X200588Y588414D02*
X200288Y588714D01*
G01X197242Y598734D02*
Y593757D01*
G01X183856Y598734D02*
Y593757D01*
G01X203935Y598734D02*
Y593757D01*
G01X220667Y598734D02*
Y593761D01*
G01X237399Y11814D02*
X237099Y12114D01*
G01X237399Y4023D02*
Y11814D01*
G01X267517Y4024D02*
Y12114D01*
G01X267518Y4023D02*
X267517Y4024D01*
G01X260824D02*
Y12114D01*
G01X260825Y4023D02*
X260824Y4024D01*
G01X240746Y22133D02*
Y17157D01*
G01X277557Y22133D02*
Y17157D01*
G01X234053Y22133D02*
Y17157D01*
G01X270864Y22133D02*
Y17157D01*
G01X274210Y11814D02*
X273910Y12114D01*
G01X274210Y4023D02*
Y11814D01*
G01X264171Y22133D02*
Y17157D01*
G01X280203Y10133D02*
Y12114D01*
G01X280903Y9433D02*
X280203Y10133D01*
G01X280903Y4023D02*
Y9433D01*
G01X243392Y10133D02*
Y12114D01*
G01X244092Y9433D02*
X243392Y10133D01*
G01X244092Y4023D02*
Y9433D01*
G01X257478Y22133D02*
Y17157D01*
G01X237399Y87414D02*
X237099Y87714D01*
G01X237399Y79623D02*
Y87414D01*
G01X280203Y85733D02*
Y87714D01*
G01X280903Y85033D02*
X280203Y85733D01*
G01X280903Y79623D02*
Y85033D01*
G01X257478Y92757D02*
Y97733D01*
G01X260824Y41823D02*
Y49914D01*
G01X260825Y41823D02*
X260824D01*
G01X237399Y49614D02*
X237099Y49914D01*
G01X237399Y41823D02*
Y49614D01*
G01X277557Y59933D02*
Y54957D01*
G01X270864Y59933D02*
Y54957D01*
G01X240746Y59933D02*
Y54957D01*
G01X274210Y49614D02*
X273910Y49914D01*
G01X274210Y41823D02*
Y49614D01*
G01X257478Y59933D02*
Y54957D01*
G01X240746Y92757D02*
Y97733D01*
G01X264171Y59933D02*
Y54957D01*
G01Y92757D02*
Y97733D01*
G01X280203Y47933D02*
Y49914D01*
G01X280903Y47233D02*
X280203Y47933D01*
G01X280903Y41823D02*
Y47233D01*
G01X234053Y59933D02*
Y54957D01*
G01X260824Y79624D02*
Y87714D01*
G01X260825Y79623D02*
X260824Y79624D01*
G01X274210Y87414D02*
X273910Y87714D01*
G01X274210Y79623D02*
Y87414D01*
G01X267517Y42344D02*
Y49914D01*
G01X267518Y42343D02*
X267517Y42344D01*
G01X267518Y41823D02*
Y42343D01*
G01X234053Y92757D02*
Y97733D01*
G01X267517Y79624D02*
Y87714D01*
G01X267518Y79623D02*
X267517Y79624D01*
G01X277557Y92757D02*
Y97733D01*
G01X243392Y85733D02*
Y87714D01*
G01X244092Y85033D02*
X243392Y85733D01*
G01X244092Y79623D02*
Y85033D01*
G01X270864Y92757D02*
Y97733D01*
G01X243392Y47933D02*
Y49914D01*
G01X244092Y47233D02*
X243392Y47933D01*
G01X244092Y41823D02*
Y47233D01*
G01X267517Y505024D02*
Y513114D01*
G01X267518Y505024D02*
X267517D01*
G01X234053Y523134D02*
Y518157D01*
G01X237399Y512814D02*
X237099Y513114D01*
G01X237399Y505024D02*
Y512814D01*
G01X240746Y523134D02*
Y518157D01*
G01X260824Y505024D02*
Y513114D01*
G01X260825Y505024D02*
X260824D01*
G01X280203Y511133D02*
Y513114D01*
G01X280903Y510433D02*
X280203Y511133D01*
G01X280903Y505024D02*
Y510433D01*
G01X274210Y512814D02*
X273910Y513114D01*
G01X274210Y505024D02*
Y512814D01*
G01X264171Y523134D02*
Y518157D01*
G01X257478Y523134D02*
Y518157D01*
G01X277557Y523134D02*
Y518157D01*
G01X243392Y511133D02*
Y513114D01*
G01X244092Y510433D02*
X243392Y511133D01*
G01X244092Y505024D02*
Y510433D01*
G01X270864Y523134D02*
Y518157D01*
G01X260824Y580624D02*
Y588714D01*
G01X260825Y580624D02*
X260824D01*
G01X264171Y560934D02*
Y555957D01*
G01X280203Y548933D02*
Y550914D01*
G01X280903Y548233D02*
X280203Y548933D01*
G01X280903Y542824D02*
Y548233D01*
G01X257478Y560934D02*
Y555957D01*
G01X277557Y560934D02*
Y555957D01*
G01X274210Y550614D02*
X273910Y550914D01*
G01X274210Y542824D02*
Y550614D01*
G01X270864Y560934D02*
Y555957D01*
G01X267517Y580624D02*
Y588714D01*
G01X267518Y580624D02*
X267517D01*
G01X260824Y542824D02*
Y550914D01*
G01X260825Y542824D02*
X260824D01*
G01X243392Y548933D02*
Y550914D01*
G01X244092Y548233D02*
X243392Y548933D01*
G01X244092Y542824D02*
Y548233D01*
G01X243392Y586733D02*
Y588714D01*
G01X244092Y586033D02*
X243392Y586733D01*
G01X244092Y580624D02*
Y586033D01*
G01X267517Y542824D02*
Y550914D01*
G01X267518Y542824D02*
X267517D01*
G01X274210Y580624D02*
Y588414D01*
G01X237399Y580624D02*
Y588414D01*
G01X240746Y560934D02*
Y555957D01*
G01X234053Y560934D02*
Y555957D01*
G01X280203Y586733D02*
Y588714D01*
G01X280903Y586033D02*
X280203Y586733D01*
G01X280903Y580624D02*
Y586033D01*
G01X237399Y550614D02*
X237099Y550914D01*
G01X237399Y542824D02*
Y550614D01*
G01X234053Y598734D02*
Y593757D01*
G01X277557Y598734D02*
Y593757D01*
G01X270864Y598734D02*
Y593757D01*
G01X257478Y598734D02*
Y593757D01*
G01X274210Y588414D02*
X273910Y588714D01*
G01X237399Y588414D02*
X237099Y588714D01*
G01X240746Y598734D02*
Y593757D01*
G01X264171Y598734D02*
Y593757D01*
G01X324407Y22133D02*
Y17057D01*
G01X327754Y4023D02*
Y9114D01*
G01X321061Y22133D02*
Y17057D01*
G01X300982Y22133D02*
Y17157D01*
G01X334447Y9113D02*
X334446Y9114D01*
G01X334447Y4023D02*
Y9113D01*
G01X304328Y4024D02*
Y12114D01*
G01X304329Y4023D02*
X304328Y4024D01*
G01X331100Y22133D02*
Y17057D01*
G01X344486Y22133D02*
Y17057D01*
G01X354525Y9122D02*
Y4023D01*
G01X347833D02*
Y9122D01*
G01X334447Y22133D02*
Y17057D01*
G01X294289Y22133D02*
Y17157D01*
G01X344486Y4023D02*
Y9122D01*
G01X341140Y22133D02*
Y17057D01*
G01X297635Y4024D02*
Y12114D01*
G01X297636Y4023D02*
X297635Y4024D01*
G01X337793Y4023D02*
Y9114D01*
G01X311021D02*
Y4023D01*
G01X354526Y17157D02*
Y17057D01*
G01X354525Y17158D02*
X354526Y17157D01*
G01X354525Y22133D02*
Y17158D01*
G01X324407Y4023D02*
Y9114D01*
G01X314368Y22133D02*
Y17057D01*
G01X351179Y22133D02*
Y17057D01*
G01X297635Y43744D02*
Y49914D01*
G01X297636Y43743D02*
X297635Y43744D01*
G01X297636Y41823D02*
Y43743D01*
G01X324407Y79623D02*
Y84599D01*
G01X351179Y89964D02*
Y97733D01*
G01X344486Y41823D02*
Y46922D01*
G01X334447Y92757D02*
Y97733D01*
G01X304328Y82574D02*
Y87714D01*
G01X304329Y82573D02*
X304328Y82574D01*
G01X304329Y79623D02*
Y82573D01*
G01X354525Y46922D02*
Y41823D01*
G01X337793D02*
Y46914D01*
G01X331100Y59933D02*
Y54857D01*
G01X341140Y92757D02*
Y97733D01*
G01X324407Y41823D02*
Y46914D01*
G01X314368Y92657D02*
Y97733D01*
G01X344486Y79623D02*
Y84714D01*
G01X321061Y92757D02*
Y97733D01*
G01X334447Y59933D02*
Y54857D01*
G01X300982Y92757D02*
Y97733D01*
G01X354525Y92867D02*
X354415Y92757D01*
G01X354525Y97733D02*
Y92867D01*
G01X344486Y89964D02*
Y97733D01*
G01X354525Y87282D02*
X354415Y87392D01*
G01X354525Y79623D02*
Y87282D01*
G01X314368Y59933D02*
Y54857D01*
G01X331100Y89964D02*
Y97733D01*
G01X334447Y46913D02*
X334446Y46914D01*
G01X334447Y41823D02*
Y46913D01*
G01X337793Y79623D02*
Y84599D01*
G01X327754Y87392D02*
Y79623D01*
G01X297635Y79624D02*
Y87714D01*
G01X297636Y79623D02*
X297635Y79624D01*
G01X294289Y92757D02*
Y97733D01*
G01X324407Y89964D02*
Y97733D01*
G01X347833Y41823D02*
Y46922D01*
G01X311021Y46914D02*
Y41823D01*
G01X351179Y59933D02*
Y54857D01*
G01X304328Y41824D02*
Y49914D01*
G01X304329Y41823D02*
X304328Y41824D01*
G01X347833Y87392D02*
Y79623D01*
G01X354526Y54957D02*
Y54857D01*
G01X354525Y54958D02*
X354526Y54957D01*
G01X354525Y59933D02*
Y54958D01*
G01X341140Y59933D02*
Y54857D01*
G01X327754Y41823D02*
Y46914D01*
G01X300982Y59933D02*
Y54957D01*
G01X324407Y59933D02*
Y54857D01*
G01X311021Y84714D02*
Y79623D01*
G01X344486Y59933D02*
Y54857D01*
G01X334447Y87392D02*
Y79623D01*
G01X321061Y59933D02*
Y54857D01*
G01X294289Y59933D02*
Y54957D01*
G01X354557Y245928D02*
X356450D01*
G01X352924Y244295D02*
X354557Y245928D01*
G01X351324Y244295D02*
X352924D01*
G01X349691Y245928D02*
X351324Y244295D01*
G01X348262Y245928D02*
X349691D01*
G01X346311Y247879D02*
X348262Y245928D01*
G01X344428Y247879D02*
X346311D01*
G01X342933Y246384D02*
X344428Y247879D01*
G01X341503Y246384D02*
X342933D01*
G01X339770Y248117D02*
X341503Y246384D01*
G01X337907Y248117D02*
X339770D01*
G01X336008Y250016D02*
X337907Y248117D01*
G01X334609Y250016D02*
X336008D01*
G01X332934Y248341D02*
X334609Y250016D01*
G01X330898Y248341D02*
X332934D01*
G01X328949Y250290D02*
X330898Y248341D01*
G01X327520Y250290D02*
X328949D01*
G01X325742Y252068D02*
X327520Y250290D01*
G01X324320Y252068D02*
X325742D01*
G01X322654Y253734D02*
X324320Y252068D01*
G01X320585Y253734D02*
X322654D01*
G01X319851Y253000D02*
X320585Y253734D01*
G01X316500Y253000D02*
X319851D01*
G01X322450Y257829D02*
X319816D01*
G01X324600Y255679D02*
X322450Y257829D01*
G01X326031Y255679D02*
X324600D01*
G01X327523Y254187D02*
X326031Y255679D01*
G01X327827Y253884D02*
X327523Y254187D01*
G01X329255Y253884D02*
X327827D01*
G01X331009Y252130D02*
X329255Y253884D01*
G01X332680Y252130D02*
X331009D01*
G01X334278Y253728D02*
X332680Y252130D01*
G01X336432Y253728D02*
X334278D01*
G01X338375Y251785D02*
X336432Y253728D01*
G01X339553Y251785D02*
X338375D01*
G01X341054Y250284D02*
X339553Y251785D01*
G01X342933Y250284D02*
X341054D01*
G01X344434Y251785D02*
X342933Y250284D01*
G01X346313Y251785D02*
X344434D01*
G01X348270Y249828D02*
X346313Y251785D01*
G01X349691Y249828D02*
X348270D01*
G01X351184Y248335D02*
X349691Y249828D01*
G01X353072Y248335D02*
X351184D01*
G01X354565Y249828D02*
X353072Y248335D01*
G01X356450Y249828D02*
X354565D01*
G01X318487Y256500D02*
X319816Y257829D01*
G01X316500Y256500D02*
X318487D01*
G01X324407Y505024D02*
Y509999D01*
G01X337793Y505024D02*
Y509999D01*
G01X300982Y523134D02*
Y518157D01*
G01X321061Y523134D02*
Y518157D01*
G01X314368Y523134D02*
Y518057D01*
G01X334447Y523134D02*
Y518157D01*
G01X347833Y505024D02*
Y512792D01*
G01X344486Y505024D02*
Y510114D01*
G01X297635Y505024D02*
Y513114D01*
G01X297636Y505024D02*
X297635D01*
G01X331100Y523134D02*
Y515364D01*
G01X324407Y523134D02*
Y515364D01*
G01X341140Y523134D02*
Y518157D01*
G01X344486Y523134D02*
Y515364D01*
G01X334447Y505024D02*
Y512792D01*
G01X304328Y507974D02*
Y513114D01*
G01X304329Y507973D02*
X304328Y507974D01*
G01X304329Y505024D02*
Y507973D01*
G01X354525Y512574D02*
X354307Y512792D01*
G01X354525Y505024D02*
Y512574D01*
G01X327754Y505024D02*
Y512792D01*
G01X311021Y510114D02*
Y505024D01*
G01X354525Y518158D02*
X354526Y518157D01*
G01X354525Y523134D02*
Y518158D01*
G01X351179Y523134D02*
Y515364D01*
G01X294289Y523134D02*
Y518157D01*
G01X327754Y585714D02*
Y580624D01*
G01X334447Y560934D02*
Y555857D01*
G01X304328Y583574D02*
Y588714D01*
G01X304329Y583573D02*
X304328Y583574D01*
G01X304329Y580624D02*
Y583573D01*
G01X304328Y545774D02*
Y550914D01*
G01X304329Y545773D02*
X304328Y545774D01*
G01X304329Y542824D02*
Y545773D01*
G01X324407Y560934D02*
Y555857D01*
G01Y547914D02*
Y542824D01*
G01X344486Y585722D02*
Y580624D01*
G01X341140Y560934D02*
Y555857D01*
G01X351179Y560934D02*
Y555857D01*
G01X344486Y560934D02*
Y555857D01*
G01X327754Y547914D02*
Y542824D01*
G01X334447Y547913D02*
X334446Y547914D01*
G01X334447Y542824D02*
Y547913D01*
G01X294289Y560934D02*
Y555957D01*
G01X334447Y585713D02*
X334446Y585714D01*
G01X334447Y580624D02*
Y585713D01*
G01X321061Y560934D02*
Y555857D01*
G01X347833Y585722D02*
Y580624D01*
G01Y547922D02*
Y542824D01*
G01X314368Y560934D02*
Y555857D01*
G01X337793Y547914D02*
Y542824D01*
G01X324407Y585714D02*
Y580624D01*
G01X354526Y555957D02*
Y555857D01*
G01X354525Y555958D02*
X354526Y555957D01*
G01X354525Y560934D02*
Y555958D01*
G01Y580624D02*
Y585722D01*
G01X297635Y542824D02*
Y550914D01*
G01X297636Y542824D02*
X297635D01*
G01X337793Y585714D02*
Y580624D01*
G01X300982Y560934D02*
Y555957D01*
G01X311021Y542824D02*
Y547914D01*
G01X297635Y580624D02*
Y588714D01*
G01X297636Y580624D02*
X297635D01*
G01X331100Y560934D02*
Y555857D01*
G01X354525Y542824D02*
Y547922D01*
G01X311021Y580624D02*
Y585714D01*
G01X344486Y547922D02*
Y542824D01*
G01X341140Y598734D02*
Y593657D01*
G01X334447Y598734D02*
Y593657D01*
G01X351179Y598734D02*
Y593657D01*
G01X324407Y598734D02*
Y593657D01*
G01X344486Y598734D02*
Y593657D01*
G01X354526Y593757D02*
Y593657D01*
G01X354525Y593758D02*
X354526Y593757D01*
G01X354525Y598734D02*
Y593758D01*
G01X331100Y598734D02*
Y593657D01*
G01X321061Y598734D02*
Y593657D01*
G01X294289Y598734D02*
Y593757D01*
G01X314368Y598734D02*
Y593657D01*
G01X300982Y598734D02*
Y593757D01*
G01X414762Y9121D02*
X414763Y9122D01*
G01X414762Y4023D02*
Y9121D01*
G01Y17058D02*
Y22133D01*
G01X404722Y4023D02*
Y9121D01*
G01X394683Y11791D02*
X394682Y11792D01*
G01X394683Y4023D02*
Y11791D01*
G01X398029Y22133D02*
Y17042D01*
G01X404722Y17058D02*
X404723Y17057D01*
G01X404722Y22133D02*
Y17058D01*
G01X401376Y4023D02*
Y9121D01*
G01X408069Y22133D02*
Y17042D01*
G01X398029Y59933D02*
Y54842D01*
G01X404722Y54858D02*
X404723Y54857D01*
G01X404722Y59933D02*
Y54858D01*
G01Y46921D02*
X404723Y46922D01*
G01X404722Y41823D02*
Y46921D01*
G01X414762Y54858D02*
X414763Y54857D01*
G01X414762Y59933D02*
Y54858D01*
G01Y92758D02*
X414761Y92757D01*
G01X414762Y97733D02*
Y92758D01*
G01X404722Y79623D02*
Y84599D01*
G01X414761Y79624D02*
Y87392D01*
G01X414762Y79623D02*
X414761Y79624D01*
G01X401376Y87391D02*
X401375Y87392D01*
G01X401376Y79623D02*
Y87391D01*
G01X408069Y92758D02*
X408068Y92757D01*
G01X408069Y97733D02*
Y92758D01*
G01X394683Y87391D02*
X394682Y87392D01*
G01X394683Y79623D02*
Y87391D01*
G01X394682Y41824D02*
Y49592D01*
G01X394683Y41823D02*
X394682Y41824D01*
G01X401376Y46921D02*
X401377Y46922D01*
G01X401376Y41823D02*
Y46921D01*
G01X408069Y59933D02*
Y54842D01*
G01X414762Y46921D02*
X414763Y46922D01*
G01X414762Y41823D02*
Y46921D01*
G01X398029Y89964D02*
Y97733D01*
G01X404722Y89964D02*
Y97733D01*
G01X399185Y244209D02*
X407706D01*
G01X397460Y242484D02*
X399185Y244209D01*
G01X395580Y242484D02*
X397460D01*
G01X393631Y240535D02*
X395580Y242484D01*
G01X391751Y240535D02*
X393631D01*
G01X389913Y242373D02*
X391751Y240535D01*
G01X388710Y242373D02*
X389913D01*
G01X386872Y240535D02*
X388710Y242373D01*
G01X384991Y240535D02*
X386872D01*
G01X383347Y242179D02*
X384991Y240535D01*
G01X381756Y242179D02*
X383347D01*
G01X379766Y240189D02*
X381756Y242179D01*
G01X378569Y240189D02*
X379766D01*
G01X376548Y242210D02*
X378569Y240189D01*
G01X375127Y242210D02*
X376548D01*
G01X373352Y243985D02*
X375127Y242210D01*
G01X371465Y243985D02*
X373352D01*
G01X369939Y242459D02*
X371465Y243985D01*
G01X368118Y242459D02*
X369939D01*
G01X366592Y243985D02*
X368118Y242459D01*
G01X365162Y243985D02*
X366592D01*
G01X363667Y242490D02*
X365162Y243985D01*
G01X361327Y242490D02*
X363667D01*
G01X359832Y243985D02*
X361327Y242490D01*
G01X358393Y243985D02*
X359832D01*
G01X356450Y245928D02*
X358393Y243985D01*
G01X358159Y248119D02*
X356450Y249828D01*
G01X359952Y248119D02*
X358159D01*
G01X362034Y246037D02*
X359952Y248119D01*
G01X363216Y246037D02*
X362034D01*
G01X365064Y247885D02*
X363216Y246037D01*
G01X366592Y247885D02*
X365064D01*
G01X368409Y246068D02*
X366592Y247885D01*
G01X369656Y246068D02*
X368409D01*
G01X371490Y247902D02*
X369656Y246068D01*
G01X373335Y247902D02*
X371490D01*
G01X375264Y245973D02*
X373335Y247902D01*
G01X376693Y245973D02*
X375264D01*
G01X378231Y244435D02*
X376693Y245973D01*
G01X380112Y244435D02*
X378231D01*
G01X381611Y245934D02*
X380112Y244435D01*
G01X383492Y245934D02*
X381611D01*
G01X384991Y244435D02*
X383492Y245934D01*
G01X386872Y244435D02*
X384991D01*
G01X388597Y246160D02*
X386872Y244435D01*
G01X390026Y246160D02*
X388597D01*
G01X391751Y244435D02*
X390026Y246160D01*
G01X393632Y244435D02*
X391751D01*
G01X395357Y246160D02*
X393632Y244435D01*
G01X399676Y246160D02*
X395357D01*
G01X401376Y512791D02*
X401375Y512792D01*
G01X401376Y505024D02*
Y512791D01*
G01X394683D02*
X394682Y512792D01*
G01X394683Y505024D02*
Y512791D01*
G01X404722Y523134D02*
Y515364D01*
G01X414762Y518158D02*
X414761Y518157D01*
G01X414762Y523134D02*
Y518158D01*
G01X398029Y523134D02*
Y515364D01*
G01X414761Y505024D02*
X414762D01*
G01X414761Y512792D02*
Y505024D01*
G01X408069Y518158D02*
X408068Y518157D01*
G01X408069Y523134D02*
Y518158D01*
G01X404722Y505024D02*
Y509999D01*
G01X414762Y585721D02*
X414763Y585722D01*
G01X414762Y580624D02*
Y585721D01*
G01X394683Y550591D02*
X394682Y550592D01*
G01X394683Y542824D02*
Y550591D01*
G01X404722Y585721D02*
X404723Y585722D01*
G01X404722Y580624D02*
Y585721D01*
G01X414762Y547921D02*
X414763Y547922D01*
G01X414762Y542824D02*
Y547921D01*
G01X404722D02*
X404723Y547922D01*
G01X404722Y542824D02*
Y547921D01*
G01X394682Y580624D02*
Y588392D01*
G01X394683Y580624D02*
X394682D01*
G01X398029Y560934D02*
Y555842D01*
G01X404722Y555858D02*
X404723Y555857D01*
G01X404722Y560934D02*
Y555858D01*
G01X401376Y585721D02*
X401377Y585722D01*
G01X401376Y580624D02*
Y585721D01*
G01X414762Y555858D02*
X414763Y555857D01*
G01X414762Y560934D02*
Y555858D01*
G01X401376Y542824D02*
Y547922D01*
G01X408069Y560934D02*
Y555842D01*
G01X414762Y593658D02*
X414763Y593657D01*
G01X414762Y598734D02*
Y593658D01*
G01X408069Y598734D02*
Y593642D01*
G01X398029Y598734D02*
Y593642D01*
G01X404722Y593658D02*
X404723Y593657D01*
G01X404722Y598734D02*
Y593658D01*
G01X439822Y-42265D02*
G02Y-45915I0J-1825D01*
G01X444880Y9122D02*
Y4023D01*
G01X431494Y22133D02*
Y17042D01*
G01X438187Y22133D02*
Y17059D01*
G01X458266Y22133D02*
Y17157D01*
G01X474998Y22133D02*
Y17157D01*
G01X451573Y22133D02*
Y17157D01*
G01X438187Y9120D02*
Y4023D01*
G01X424801Y22133D02*
Y17042D01*
G01X444880Y22133D02*
Y17059D01*
G01X434840Y9120D02*
Y4023D01*
G01X460912Y10133D02*
Y12114D01*
G01X461612Y9433D02*
X460912Y10133D01*
G01X461612Y4023D02*
Y9433D01*
G01X428147Y4023D02*
Y9120D01*
G01X454619Y9273D02*
Y12114D01*
G01X454919Y8973D02*
X454619Y9273D01*
G01X454919Y4023D02*
Y8973D01*
G01X451573Y92757D02*
Y97733D01*
G01X454919Y49264D02*
X454619Y49564D01*
G01X454919Y41823D02*
Y49264D01*
G01X434840Y46920D02*
X434842Y46922D01*
G01X434840Y41823D02*
Y46920D01*
G01Y87392D02*
Y79623D01*
G01X424801Y59933D02*
Y54842D01*
G01X460912Y47933D02*
Y49914D01*
G01X461612Y47233D02*
X460912Y47933D01*
G01X461612Y41823D02*
Y47233D01*
G01X458266Y92757D02*
Y97733D01*
G01X444880Y46922D02*
Y41823D01*
G01X458266Y59933D02*
Y54957D01*
G01X438187Y59933D02*
Y54859D01*
G01X474998Y92757D02*
Y97733D01*
G01X454919Y87414D02*
X454619Y87714D01*
G01X454919Y79623D02*
Y87414D01*
G01X438187Y89964D02*
Y97733D01*
G01X424801Y89964D02*
Y97733D01*
G01X428147Y87392D02*
Y79623D01*
G01X431494Y89964D02*
Y97733D01*
G01X444880Y84714D02*
Y79623D01*
G01Y89964D02*
Y97733D01*
G01X431494Y59933D02*
Y54842D01*
G01X451573Y59933D02*
Y54957D01*
G01X474998Y59933D02*
Y54957D01*
G01X428147Y46920D02*
X428149Y46922D01*
G01X428147Y41823D02*
Y46920D01*
G01X444880Y59933D02*
Y54859D01*
G01X438187Y79623D02*
Y84714D01*
G01X421455Y92758D02*
X421454Y92757D01*
G01X421455Y97733D02*
Y92758D01*
G01X460912Y85733D02*
Y87714D01*
G01X461612Y85033D02*
X460912Y85733D01*
G01X461612Y79623D02*
Y85033D01*
G01X474998Y523134D02*
Y518157D01*
G01X454919Y512814D02*
X454619Y513114D01*
G01X454919Y505024D02*
Y512814D01*
G01X431494Y523134D02*
Y515364D01*
G01X424801Y523134D02*
Y515364D01*
G01X458266Y523134D02*
Y518157D01*
G01X428147Y505024D02*
Y512792D01*
G01X444880Y523134D02*
Y515364D01*
G01X451573Y523134D02*
Y518157D01*
G01X438187Y523134D02*
Y515364D01*
G01Y505024D02*
Y510114D01*
G01X460912Y511133D02*
Y513114D01*
G01X461612Y510433D02*
X460912Y511133D01*
G01X461612Y505024D02*
Y510433D01*
G01X434840Y505024D02*
Y512792D01*
G01X421455Y518158D02*
X421454Y518157D01*
G01X421455Y523134D02*
Y518158D01*
G01X444880Y510114D02*
Y505024D01*
G01X434840Y547920D02*
X434842Y547922D01*
G01X434840Y542824D02*
Y547920D01*
G01X431494Y560934D02*
Y555842D01*
G01X428147Y585720D02*
X428149Y585722D01*
G01X428147Y580624D02*
Y585720D01*
G01X438187Y560934D02*
Y555859D01*
G01X428147Y547920D02*
X428149Y547922D01*
G01X428147Y542824D02*
Y547920D01*
G01X458266Y560934D02*
Y555957D01*
G01X460912Y548933D02*
Y550914D01*
G01X461612Y548233D02*
X460912Y548933D01*
G01X461612Y542824D02*
Y548233D01*
G01X434840Y585720D02*
X434842Y585722D01*
G01X434840Y580624D02*
Y585720D01*
G01X474998Y560934D02*
Y555957D01*
G01X438187Y547920D02*
X438189Y547922D01*
G01X438187Y542824D02*
Y547920D01*
G01X451573Y560934D02*
Y555957D01*
G01X444880Y560934D02*
Y555859D01*
G01Y542824D02*
Y547922D01*
G01X460912Y586733D02*
Y588714D01*
G01X461612Y586033D02*
X460912Y586733D01*
G01X461612Y580624D02*
Y586033D01*
G01X424801Y560934D02*
Y555842D01*
G01X454919Y580624D02*
Y588414D01*
G01X444880Y580624D02*
Y585722D01*
G01X454919Y550614D02*
X454619Y550914D01*
G01X454919Y542824D02*
Y550614D01*
G01X444880Y598734D02*
Y593659D01*
G01X458266Y598734D02*
Y593757D01*
G01X431494Y598734D02*
Y593642D01*
G01X424801Y598734D02*
Y593642D01*
G01X451573Y598734D02*
Y593757D01*
G01X438187Y598734D02*
Y593659D01*
G01X474998Y598734D02*
Y593757D01*
G01X454919Y588414D02*
X454619Y588714D01*
G01X495077Y22133D02*
Y17157D01*
G01X515155Y4023D02*
Y12114D01*
G01X531888Y22133D02*
Y17157D01*
G01X488384Y22133D02*
Y17157D01*
G01X478344Y4023D02*
Y12114D01*
G01X521848Y4023D02*
Y12114D01*
G01X534534Y10133D02*
Y12114D01*
G01X535234Y9433D02*
X534534Y10133D01*
G01X535234Y4023D02*
Y9433D01*
G01X511809Y22133D02*
Y17157D01*
G01X528541Y11814D02*
X528241Y12114D01*
G01X528541Y4023D02*
Y11814D01*
G01X497723Y10133D02*
Y12114D01*
G01X498423Y9433D02*
X497723Y10133D01*
G01X498423Y4023D02*
Y9433D01*
G01X485037Y4023D02*
Y12114D01*
G01X518502Y22133D02*
Y17157D01*
G01X491730Y11814D02*
X491430Y12114D01*
G01X491730Y4023D02*
Y11814D01*
G01X481691Y22133D02*
Y17157D01*
G01X525195Y22133D02*
Y17157D01*
G01X534534Y85733D02*
Y87714D01*
G01X535234Y85033D02*
X534534Y85733D01*
G01X535234Y79623D02*
Y85033D01*
G01X491730Y49614D02*
X491430Y49914D01*
G01X491730Y41823D02*
Y49614D01*
G01X511809Y59933D02*
Y54957D01*
G01X478344Y87714D02*
Y79623D01*
G01X497723Y85733D02*
Y87714D01*
G01X498423Y85033D02*
X497723Y85733D01*
G01X498423Y79623D02*
Y85033D01*
G01X488384Y59933D02*
Y54957D01*
G01X518502Y59933D02*
Y54957D01*
G01X497723Y47933D02*
Y49914D01*
G01X498423Y47233D02*
X497723Y47933D01*
G01X498423Y41823D02*
Y47233D01*
G01X515155Y41823D02*
Y49914D01*
G01X525195Y92757D02*
Y97733D01*
G01X534534Y47933D02*
Y49914D01*
G01X535234Y47233D02*
X534534Y47933D01*
G01X535234Y41823D02*
Y47233D01*
G01X481691Y59933D02*
Y54957D01*
G01X528541Y87414D02*
X528241Y87714D01*
G01X528541Y79623D02*
Y87414D01*
G01X521848Y41823D02*
Y49914D01*
G01X481691Y92757D02*
Y97733D01*
G01X531888Y59933D02*
Y54957D01*
G01X495077Y59933D02*
Y54957D01*
G01X491730Y87414D02*
X491430Y87714D01*
G01X491730Y79623D02*
Y87414D01*
G01X478344Y41823D02*
Y49914D01*
G01X488384Y92757D02*
Y97733D01*
G01X525195Y59933D02*
Y54957D01*
G01X485037Y41823D02*
Y49914D01*
G01X518502Y92757D02*
Y97733D01*
G01X521848Y87714D02*
Y79623D01*
G01X531888Y92757D02*
Y97733D01*
G01X511809Y92757D02*
Y97733D01*
G01X485037Y87714D02*
Y79623D01*
G01X515155Y87714D02*
Y79623D01*
G01X528541Y49614D02*
X528241Y49914D01*
G01X528541Y41823D02*
Y49614D01*
G01X495077Y92757D02*
Y97733D01*
G01X511809Y523134D02*
Y518157D01*
G01X525195Y523134D02*
Y518157D01*
G01X491730Y512814D02*
X491430Y513114D01*
G01X491730Y505024D02*
Y512814D01*
G01X534534Y511133D02*
Y513114D01*
G01X535234Y510433D02*
X534534Y511133D01*
G01X535234Y505024D02*
Y510433D01*
G01X518502Y523134D02*
Y518157D01*
G01X485037Y505024D02*
Y513114D01*
G01X515155Y505024D02*
Y513114D01*
G01X488384Y523134D02*
Y518157D01*
G01X481691Y523134D02*
Y518157D01*
G01X528541Y512814D02*
X528241Y513114D01*
G01X528541Y505024D02*
Y512814D01*
G01X531888Y523134D02*
Y518157D01*
G01X495077Y523134D02*
Y518157D01*
G01X497723Y511133D02*
Y513114D01*
G01X498423Y510433D02*
X497723Y511133D01*
G01X498423Y505024D02*
Y510433D01*
G01X478344Y505024D02*
Y513114D01*
G01X521848Y505024D02*
Y513114D01*
G01X478344Y542824D02*
Y550914D01*
G01X491730Y550614D02*
X491430Y550914D01*
G01X491730Y542824D02*
Y550614D01*
G01X515155Y542824D02*
Y550914D01*
G01X518502Y560934D02*
Y555957D01*
G01X528541Y580624D02*
Y588414D01*
G01X497723Y548933D02*
Y550914D01*
G01X498423Y548233D02*
X497723Y548933D01*
G01X498423Y542824D02*
Y548233D01*
G01X495077Y560934D02*
Y555957D01*
G01X528541Y550614D02*
X528241Y550914D01*
G01X528541Y542824D02*
Y550614D01*
G01X478344Y580624D02*
Y588714D01*
G01X497723Y586733D02*
Y588714D01*
G01X498423Y586033D02*
X497723Y586733D01*
G01X498423Y580624D02*
Y586033D01*
G01X521848Y542824D02*
Y550914D01*
G01X515155Y580624D02*
Y588714D01*
G01X488384Y560934D02*
Y555957D01*
G01X531888Y560934D02*
Y555957D01*
G01X525195Y560934D02*
Y555957D01*
G01X491730Y580624D02*
Y588414D01*
G01X485037Y542824D02*
Y550914D01*
G01X511809Y560934D02*
Y555957D01*
G01X481691Y560934D02*
Y555957D01*
G01X534534Y548933D02*
Y550914D01*
G01X535234Y548233D02*
X534534Y548933D01*
G01X535234Y542824D02*
Y548233D01*
G01X485037Y580624D02*
Y588714D01*
G01X534534Y586733D02*
Y588714D01*
G01X535234Y586033D02*
X534534Y586733D01*
G01X535234Y580624D02*
Y586033D01*
G01X521848Y580624D02*
Y588714D01*
G01X518502Y598734D02*
Y593757D01*
G01X528541Y588414D02*
X528241Y588714D01*
G01X531888Y598734D02*
Y593757D01*
G01X511809Y598734D02*
Y593757D01*
G01X491730Y588414D02*
X491430Y588714D01*
G01X488384Y598734D02*
Y593757D01*
G01X525195Y598734D02*
Y593757D01*
G01X481691Y598734D02*
Y593757D01*
G01X495077Y598734D02*
Y593757D01*
G01X592124Y22133D02*
Y17157D01*
G01X571345Y10133D02*
Y12114D01*
G01X572045Y9433D02*
X571345Y10133D01*
G01X572045Y4023D02*
Y9433D01*
G01X548620Y22133D02*
Y17157D01*
G01X568699Y22133D02*
Y17157D01*
G01X595470Y4023D02*
Y12114D01*
G01X565352Y11814D02*
X565052Y12114D01*
G01X565352Y4023D02*
Y11814D01*
G01X598817Y22133D02*
Y17057D01*
G01X551966Y4023D02*
Y12114D01*
G01X562006Y17157D02*
X561868Y17019D01*
G01X562006Y22133D02*
Y17157D01*
G01X585431Y22133D02*
Y17157D01*
G01X555313Y22133D02*
Y17157D01*
G01X588777Y4023D02*
Y12114D01*
G01X558659Y4023D02*
Y12114D01*
G01X595470Y87714D02*
Y79623D01*
G01X555313Y59933D02*
Y54957D01*
G01X588777Y87714D02*
Y79623D01*
G01X555313Y92757D02*
Y97733D01*
G01X548620D02*
Y92757D01*
G01X568699D02*
Y97733D01*
G01X571345Y47933D02*
Y49914D01*
G01X572045Y47233D02*
X571345Y47933D01*
G01X572045Y41823D02*
Y47233D01*
G01X595470Y41823D02*
Y49914D01*
G01X551966Y87714D02*
Y79623D01*
G01X592124Y59933D02*
Y54957D01*
G01Y92757D02*
Y97733D01*
G01X562006Y92757D02*
Y97733D01*
G01X551966Y41823D02*
Y49914D01*
G01X598817Y97733D02*
Y92657D01*
G01X588777Y41823D02*
Y49914D01*
G01X558659Y87714D02*
Y79623D01*
G01X585431Y92757D02*
Y97733D01*
G01X562006Y59933D02*
Y54957D01*
G01X565352Y87288D02*
X565266Y87374D01*
G01X565352Y79623D02*
Y87288D01*
G01Y49614D02*
X565052Y49914D01*
G01X565352Y41823D02*
Y49614D01*
G01X548620Y59933D02*
Y54957D01*
G01X571345Y85733D02*
Y87714D01*
G01X572045Y85033D02*
X571345Y85733D01*
G01X572045Y79623D02*
Y85033D01*
G01X558659Y41823D02*
Y49914D01*
G01X585431Y59933D02*
Y54957D01*
G01X568699Y59933D02*
Y54957D01*
G01X558659Y505024D02*
Y513114D01*
G01X562006Y523134D02*
Y518157D01*
G01X595470Y505024D02*
Y513114D01*
G01X588777Y505024D02*
Y513114D01*
G01X585431Y523134D02*
Y518157D01*
G01X592124Y523134D02*
Y518157D01*
G01X571345Y511133D02*
Y513114D01*
G01X572045Y510433D02*
X571345Y511133D01*
G01X572045Y505024D02*
Y510433D01*
G01X555313Y523134D02*
Y518157D01*
G01X551966Y505024D02*
Y513114D01*
G01X565352Y512688D02*
X565266Y512774D01*
G01X565352Y505024D02*
Y512688D01*
G01X548620Y523134D02*
Y518157D01*
G01X568699Y523134D02*
Y518157D01*
G01X571345Y548933D02*
Y550914D01*
G01X572045Y548233D02*
X571345Y548933D01*
G01X572045Y542824D02*
Y548233D01*
G01X592124Y560934D02*
Y555957D01*
G01X558659Y580624D02*
Y588714D01*
G01X555313Y560934D02*
Y555957D01*
G01X588777Y580624D02*
Y588714D01*
G01X585431Y560934D02*
Y555957D01*
G01X558659Y542824D02*
Y550914D01*
G01X551966Y542824D02*
Y550914D01*
G01X548620Y560934D02*
Y555957D01*
G01X568699Y560934D02*
Y555957D01*
G01X565352Y550488D02*
X565266Y550574D01*
G01X565352Y542824D02*
Y550488D01*
G01Y588288D02*
X565052Y588588D01*
G01X565352Y580624D02*
Y588288D01*
G01X571345Y586733D02*
Y588714D01*
G01X572045Y586033D02*
X571345Y586733D01*
G01X572045Y580624D02*
Y586033D01*
G01X595470Y580624D02*
Y588714D01*
G01Y542824D02*
Y550914D01*
G01X562006Y560934D02*
Y555957D01*
G01X588777Y542824D02*
Y550914D01*
G01X551966Y580624D02*
Y588714D01*
G01X555313Y598734D02*
Y593757D01*
G01X562006Y598734D02*
Y593757D01*
G01X548620Y598734D02*
Y593757D01*
G01X565052Y588588D02*
Y588714D01*
G01X592124Y598734D02*
Y593757D01*
G01X568699Y598734D02*
Y593757D01*
G01X585431Y598734D02*
Y593757D01*
G01X779921Y22133D02*
Y17157D01*
G01X779923Y22133D02*
X779921D01*
G01X782567Y10133D02*
Y12114D01*
G01X783267Y9433D02*
X782567Y10133D01*
G01X783267Y4023D02*
Y9433D01*
G01X783269Y4023D02*
X783267D01*
G01X773228Y22133D02*
Y17157D01*
G01X773230Y22133D02*
X773228D01*
G01X776574Y11814D02*
X776274Y12114D01*
G01X776574Y4023D02*
Y11814D01*
G01X776576Y4023D02*
X776574D01*
G01X779921Y97733D02*
Y92757D01*
G01X782567Y85733D02*
Y87714D01*
G01X783267Y85033D02*
X782567Y85733D01*
G01X783267Y79623D02*
Y85033D01*
G01X783269Y79623D02*
X783267D01*
G01X776574Y87414D02*
X776274Y87714D01*
G01X776574Y79623D02*
Y87414D01*
G01X776576Y79623D02*
X776574D01*
G01X776274Y47827D02*
Y49914D01*
G01X776574Y47527D02*
X776274Y47827D01*
G01X776574Y41823D02*
Y47527D01*
G01X776576Y41823D02*
X776574D01*
G01X779921Y59933D02*
Y54957D01*
G01X779923Y59933D02*
X779921D01*
G01X773228D02*
Y54957D01*
G01X773230Y59933D02*
X773228D01*
G01Y97733D02*
Y92757D01*
G01X782567Y47933D02*
Y49914D01*
G01X783267Y47233D02*
X782567Y47933D01*
G01X783267Y41823D02*
Y47233D01*
G01X783269Y41823D02*
X783267D01*
G01X779923Y97733D02*
X779921D01*
G01X773230D02*
X773228D01*
G01X776574Y512814D02*
X776274Y513114D01*
G01X776574Y505024D02*
Y512814D01*
G01X776576Y505024D02*
X776574D01*
G01X782567Y511133D02*
Y513114D01*
G01X783267Y510433D02*
X782567Y511133D01*
G01X783267Y505024D02*
Y510433D01*
G01X783269Y505024D02*
X783267D01*
G01X779921Y523133D02*
Y518157D01*
G01X779923Y523134D02*
X779921Y523133D01*
G01X773228D02*
Y518157D01*
G01X773230Y523134D02*
X773228Y523133D01*
G01X782567Y548933D02*
Y550914D01*
G01X783267Y548233D02*
X782567Y548933D01*
G01X783267Y542824D02*
Y548233D01*
G01X783269Y542824D02*
X783267D01*
G01X776574Y550614D02*
X776274Y550914D01*
G01X776574Y542824D02*
Y550614D01*
G01X776576Y542824D02*
X776574D01*
G01X773228Y560933D02*
Y555957D01*
G01X773230Y560934D02*
X773228Y560933D01*
G01X776574Y580624D02*
Y588414D01*
G01X776576Y580624D02*
X776574D01*
G01X782567Y586733D02*
Y588714D01*
G01X783267Y586033D02*
X782567Y586733D01*
G01X783267Y580624D02*
Y586033D01*
G01X783269Y580624D02*
X783267D01*
G01X779921Y560933D02*
Y555957D01*
G01X779923Y560934D02*
X779921Y560933D01*
G01Y598733D02*
Y593757D01*
G01X779923Y598734D02*
X779921Y598733D01*
G01X776574Y588414D02*
X776274Y588714D01*
G01X773228Y598733D02*
Y593757D01*
G01X773230Y598734D02*
X773228Y598733D01*
G01X816732Y22133D02*
Y17157D01*
G01X816734Y22133D02*
X816732D01*
G01X796653D02*
Y17157D01*
G01X796655Y22133D02*
X796653D01*
G01X806692Y4023D02*
Y12114D01*
G01X806694Y4023D02*
X806692D01*
G01X836813Y12111D02*
X836810Y12114D01*
G01X836813Y4023D02*
Y12111D01*
G01X813385Y11814D02*
X813085Y12114D01*
G01X813385Y4023D02*
Y11814D01*
G01X813387Y4023D02*
X813385D01*
G01X843506Y12111D02*
X843503Y12114D01*
G01X843506Y4023D02*
Y12111D01*
G01X819378Y10133D02*
Y12114D01*
G01X820078Y9433D02*
X819378Y10133D01*
G01X820078Y4023D02*
Y9433D01*
G01X820080Y4023D02*
X820078D01*
G01X810039Y22133D02*
Y17157D01*
G01X810041Y22133D02*
X810039D01*
G01X846850D02*
Y17157D01*
G01X846852Y22133D02*
X846850D01*
G01X833464D02*
Y17157D01*
G01X833466Y22133D02*
X833464D01*
G01X800002Y12111D02*
X799999Y12114D01*
G01X800002Y4023D02*
Y12111D01*
G01X803346Y22133D02*
Y17157D01*
G01X803348Y22133D02*
X803346D01*
G01X840157D02*
Y17157D01*
G01X840159Y22133D02*
X840157D01*
G01X819378Y47823D02*
Y49914D01*
G01X820078Y47123D02*
X819378Y47823D01*
G01X820078Y41823D02*
Y47123D01*
G01X820080Y41823D02*
X820078D01*
G01X796653Y59933D02*
Y54957D01*
G01X796655Y59933D02*
X796653D01*
G01X833464Y97733D02*
Y92757D01*
G01X806692Y79623D02*
Y87714D01*
G01X806694Y79623D02*
X806692D01*
G01X799999Y43744D02*
Y49914D01*
G01X800000Y43743D02*
X799999Y43744D01*
G01X800000Y41823D02*
Y43743D01*
G01X800002Y41823D02*
X800000D01*
G01X819378Y85733D02*
Y87714D01*
G01X820078Y85033D02*
X819378Y85733D01*
G01X820078Y79623D02*
Y85033D01*
G01X820080Y79623D02*
X820078D01*
G01X840157Y59933D02*
Y54957D01*
G01X840159Y59933D02*
X840157D01*
G01X846850Y97733D02*
Y92757D01*
G01X810039Y59933D02*
Y54957D01*
G01X810041Y59933D02*
X810039D01*
G01X836810Y42444D02*
Y49914D01*
G01X836811Y42443D02*
X836810Y42444D01*
G01X836811Y41823D02*
Y42443D01*
G01X836813Y41823D02*
X836811D01*
G01X803346Y59933D02*
Y54957D01*
G01X803348Y59933D02*
X803346D01*
G01X806692Y41823D02*
Y49914D01*
G01X806694Y41823D02*
X806692D01*
G01X843503Y42544D02*
Y49914D01*
G01X843504Y42543D02*
X843503Y42544D01*
G01X843504Y41823D02*
Y42543D01*
G01X843506Y41823D02*
X843504D01*
G01X796653Y97733D02*
Y92757D01*
G01X843506Y87711D02*
X843503Y87714D01*
G01X843506Y79623D02*
Y87711D01*
G01X813385Y49614D02*
X813085Y49914D01*
G01X813385Y41823D02*
Y49614D01*
G01X813387Y41823D02*
X813385D01*
G01X810039Y97733D02*
Y92757D01*
G01X803346Y97733D02*
Y92757D01*
G01X816732Y97733D02*
Y92757D01*
G01X840157Y97733D02*
Y92757D01*
G01X816732Y59933D02*
Y54957D01*
G01X816734Y59933D02*
X816732D01*
G01X846850D02*
Y54957D01*
G01X846852Y59933D02*
X846850D01*
G01X800002Y87711D02*
X799999Y87714D01*
G01X800002Y79623D02*
Y87711D01*
G01X833464Y59933D02*
Y54957D01*
G01X833466Y59933D02*
X833464D01*
G01X813385Y87414D02*
X813085Y87714D01*
G01X813385Y79623D02*
Y87414D01*
G01X813387Y79623D02*
X813385D01*
G01X836813Y87711D02*
X836810Y87714D01*
G01X836813Y79623D02*
Y87711D01*
G01X833466Y97733D02*
X833464D01*
G01X846852D02*
X846850D01*
G01X796655D02*
X796653D01*
G01X810041D02*
X810039D01*
G01X803348D02*
X803346D01*
G01X816734D02*
X816732D01*
G01X840159D02*
X840157D01*
G01X833464Y523133D02*
Y518157D01*
G01X833466Y523134D02*
X833464Y523133D01*
G01X813385Y505024D02*
X813387D01*
G01X813385Y512814D02*
Y505024D01*
G01X813085Y513114D02*
X813385Y512814D01*
G01X796653Y523133D02*
Y518157D01*
G01X796655Y523134D02*
X796653Y523133D01*
G01X836813Y513111D02*
X836810Y513114D01*
G01X836813Y505024D02*
Y513111D01*
G01X840157Y523133D02*
Y518157D01*
G01X840159Y523134D02*
X840157Y523133D01*
G01X806692Y505024D02*
Y513114D01*
G01X806694Y505024D02*
X806692D01*
G01X810039Y523133D02*
Y518157D01*
G01X810041Y523134D02*
X810039Y523133D01*
G01X846850D02*
Y518157D01*
G01X846852Y523134D02*
X846850Y523133D01*
G01X816732D02*
Y518157D01*
G01X816734Y523134D02*
X816732Y523133D01*
G01X843503Y505024D02*
X843506D01*
G01X843503Y513114D02*
Y505024D01*
G01X799999D02*
Y513114D01*
G01X800002Y505024D02*
X799999D01*
G01X819378Y511133D02*
Y513114D01*
G01X820078Y510433D02*
X819378Y511133D01*
G01X820078Y505024D02*
Y510433D01*
G01X820080Y505024D02*
X820078D01*
G01X803346Y523133D02*
Y518157D01*
G01X803348Y523134D02*
X803346Y523133D01*
G01X843503Y580624D02*
Y588714D01*
G01X843506Y580624D02*
X843503D01*
G01Y542824D02*
Y550914D01*
G01X843506Y542824D02*
X843503D01*
G01X796653Y560933D02*
Y555957D01*
G01X796655Y560934D02*
X796653Y560933D01*
G01X836813Y580624D02*
Y588711D01*
G01X803346Y560933D02*
Y555957D01*
G01X803348Y560934D02*
X803346Y560933D01*
G01X813385Y550614D02*
X813085Y550914D01*
G01X813385Y542824D02*
Y550614D01*
G01X813387Y542824D02*
X813385D01*
G01X840157Y560933D02*
Y555957D01*
G01X840159Y560934D02*
X840157Y560933D01*
G01X813385Y580624D02*
Y588414D01*
G01X813387Y580624D02*
X813385D01*
G01X799999D02*
Y588714D01*
G01X800002Y580624D02*
X799999D01*
G01X833464Y560933D02*
Y555957D01*
G01X833466Y560934D02*
X833464Y560933D01*
G01X846850D02*
Y555957D01*
G01X846852Y560934D02*
X846850Y560933D01*
G01X806692Y542824D02*
Y550914D01*
G01X806694Y542824D02*
X806692D01*
G01X819378Y548933D02*
Y550914D01*
G01X820078Y548233D02*
X819378Y548933D01*
G01X820078Y542824D02*
Y548233D01*
G01X820080Y542824D02*
X820078D01*
G01X810039Y560933D02*
Y555957D01*
G01X810041Y560934D02*
X810039Y560933D01*
G01X819378Y586733D02*
Y588714D01*
G01X820078Y586033D02*
X819378Y586733D01*
G01X820078Y580624D02*
Y586033D01*
G01X820080Y580624D02*
X820078D01*
G01X799999Y542824D02*
Y550914D01*
G01X800002Y542824D02*
X799999D01*
G01X836813Y550911D02*
X836810Y550914D01*
G01X836813Y542824D02*
Y550911D01*
G01X816732Y560933D02*
Y555957D01*
G01X816734Y560934D02*
X816732Y560933D01*
G01X806692Y580624D02*
Y588714D01*
G01X806694Y580624D02*
X806692D01*
G01X836813Y588711D02*
X836810Y588714D01*
G01X840157Y598733D02*
Y593757D01*
G01X840159Y598734D02*
X840157Y598733D01*
G01X796653D02*
Y593757D01*
G01X796655Y598734D02*
X796653Y598733D01*
G01X833464D02*
Y593757D01*
G01X833466Y598734D02*
X833464Y598733D01*
G01X803346D02*
Y593757D01*
G01X803348Y598734D02*
X803346Y598733D01*
G01X813385Y588414D02*
X813085Y588714D01*
G01X810039Y598733D02*
Y593757D01*
G01X810041Y598734D02*
X810039Y598733D01*
G01X846850D02*
Y593757D01*
G01X846852Y598734D02*
X846850Y598733D01*
G01X816732D02*
Y593757D01*
G01X816734Y598734D02*
X816732Y598733D01*
G01X880317Y12111D02*
X880314Y12114D01*
G01X880317Y4023D02*
Y12111D01*
G01X887007Y11814D02*
X886707Y12114D01*
G01X887007Y4023D02*
Y11814D01*
G01X887009Y4023D02*
X887007D01*
G01X907086Y22133D02*
Y17157D01*
G01X907088Y22133D02*
X907086D01*
G01X853543D02*
Y17157D01*
G01X853545Y22133D02*
X853543D01*
G01X850196Y11814D02*
X849896Y12114D01*
G01X850196Y4023D02*
Y11814D01*
G01X850198Y4023D02*
X850196D01*
G01X856189Y10133D02*
Y12114D01*
G01X856889Y9433D02*
X856189Y10133D01*
G01X856889Y4023D02*
Y9433D01*
G01X856891Y4023D02*
X856889D01*
G01X870275Y22133D02*
Y17157D01*
G01X870277Y22133D02*
X870275D01*
G01X883661D02*
Y17157D01*
G01X883663Y22133D02*
X883661D01*
G01X893000Y10133D02*
Y12114D01*
G01X893700Y9433D02*
X893000Y10133D01*
G01X893700Y4023D02*
Y9433D01*
G01X893702Y4023D02*
X893700D01*
G01X873624Y12111D02*
X873621Y12114D01*
G01X873624Y4023D02*
Y12111D01*
G01X876968Y22133D02*
Y17157D01*
G01X876970Y22133D02*
X876968D01*
G01X890354D02*
Y17157D01*
G01X890356Y22133D02*
X890354D01*
G01X856189Y47933D02*
Y49914D01*
G01X856889Y47233D02*
X856189Y47933D01*
G01X856889Y41823D02*
Y47233D01*
G01X856891Y41823D02*
X856889D01*
G01X873621Y79626D02*
X873624Y79623D01*
G01X873621Y87714D02*
Y79626D01*
G01X870275Y97733D02*
Y92761D01*
G01X880314Y42844D02*
Y49914D01*
G01X880315Y42843D02*
X880314Y42844D01*
G01X880315Y41823D02*
Y42843D01*
G01X880317Y41823D02*
X880315D01*
G01X853543Y59933D02*
Y54957D01*
G01X853545Y59933D02*
X853543D01*
G01Y97733D02*
Y92757D01*
G01X850196Y87414D02*
X849896Y87714D01*
G01X850196Y79623D02*
Y87414D01*
G01X850198Y79623D02*
X850196D01*
G01X890354Y59933D02*
Y54957D01*
G01X890356Y59933D02*
X890354D01*
G01X876968Y97733D02*
Y92757D01*
G01X873621Y43744D02*
Y49914D01*
G01X873622Y43743D02*
X873621Y43744D01*
G01X873622Y41823D02*
Y43743D01*
G01X873624Y41823D02*
X873622D01*
G01X856189Y85733D02*
Y87714D01*
G01X856889Y85033D02*
X856189Y85733D01*
G01X856889Y79623D02*
Y85033D01*
G01X856891Y79623D02*
X856889D01*
G01X883661Y97733D02*
Y92757D01*
G01X893000Y47933D02*
Y49914D01*
G01X893700Y47233D02*
X893000Y47933D01*
G01X893700Y41823D02*
Y47233D01*
G01X893702Y41823D02*
X893700D01*
G01X893000Y85733D02*
Y87714D01*
G01X893700Y85033D02*
X893000Y85733D01*
G01X893700Y79623D02*
Y85033D01*
G01X893702Y79623D02*
X893700D01*
G01X887007Y87414D02*
X886707Y87714D01*
G01X887007Y79623D02*
Y87414D01*
G01X887009Y79623D02*
X887007D01*
G01X870275Y59933D02*
Y54957D01*
G01X870277Y59933D02*
X870275D01*
G01X876970Y54959D02*
X876968Y54957D01*
G01X876970Y59933D02*
Y54959D01*
G01X883661Y59933D02*
Y54957D01*
G01X883663Y59933D02*
X883661D01*
G01X907086D02*
Y54957D01*
G01X907088Y59933D02*
X907086D01*
G01X887007Y49614D02*
X886707Y49914D01*
G01X887007Y41823D02*
Y49614D01*
G01X887009Y41823D02*
X887007D01*
G01X880317Y87711D02*
X880314Y87714D01*
G01X880317Y79623D02*
Y87711D01*
G01X907086Y97733D02*
Y92757D01*
G01X890354Y97733D02*
Y92757D01*
G01X850196Y49614D02*
X849896Y49914D01*
G01X850196Y41823D02*
Y49614D01*
G01X850198Y41823D02*
X850196D01*
G01X870277Y97733D02*
X870275D01*
G01X853545D02*
X853543D01*
G01X876970D02*
X876968D01*
G01X883663D02*
X883661D01*
G01X907088D02*
X907086D01*
G01X890356D02*
X890354D01*
G01X850196Y512814D02*
X849896Y513114D01*
G01X850196Y505024D02*
Y512814D01*
G01X850198Y505024D02*
X850196D01*
G01X893000Y511133D02*
Y513114D01*
G01X893700Y510433D02*
X893000Y511133D01*
G01X893700Y505024D02*
Y510433D01*
G01X893702Y505024D02*
X893700D01*
G01X870275Y523133D02*
Y518161D01*
G01X870277Y523134D02*
X870275Y523133D01*
G01X880317Y513111D02*
X880314Y513114D01*
G01X880317Y505024D02*
Y513111D01*
G01X907086Y523133D02*
Y518157D01*
G01X907088Y523134D02*
X907086Y523133D01*
G01X890354D02*
Y518157D01*
G01X890356Y523134D02*
X890354Y523133D01*
G01X856189Y511133D02*
Y513114D01*
G01X856889Y510433D02*
X856189Y511133D01*
G01X856889Y505024D02*
Y510433D01*
G01X856891Y505024D02*
X856889D01*
G01X887007Y512814D02*
X886707Y513114D01*
G01X887007Y505024D02*
Y512814D01*
G01X887009Y505024D02*
X887007D01*
G01X873621D02*
Y513114D01*
G01X873624Y505024D02*
X873621D01*
G01X876968Y523133D02*
Y518157D01*
G01X876970Y523134D02*
X876968Y523133D01*
G01X853543D02*
Y518157D01*
G01X853545Y523134D02*
X853543Y523133D01*
G01X883661D02*
Y518157D01*
G01X883663Y523134D02*
X883661Y523133D01*
G01X887007Y550614D02*
X886707Y550914D01*
G01X887007Y542824D02*
Y550614D01*
G01X887009Y542824D02*
X887007D01*
G01X856189Y586733D02*
Y588714D01*
G01X856889Y586033D02*
X856189Y586733D01*
G01X856889Y580624D02*
Y586033D01*
G01X856891Y580624D02*
X856889D01*
G01X880317Y550911D02*
X880314Y550914D01*
G01X880317Y542824D02*
Y550911D01*
G01X907086Y560933D02*
Y555957D01*
G01X907088Y560934D02*
X907086Y560933D01*
G01X856189Y548933D02*
Y550914D01*
G01X856889Y548233D02*
X856189Y548933D01*
G01X856889Y542824D02*
Y548233D01*
G01X856891Y542824D02*
X856889D01*
G01X873621D02*
Y550914D01*
G01X873624Y542824D02*
X873621D01*
G01X883661Y560933D02*
Y555957D01*
G01X883663Y560934D02*
X883661Y560933D01*
G01X876968D02*
Y555957D01*
G01X876970Y560934D02*
X876968Y560933D01*
G01X873621Y580624D02*
Y588714D01*
G01X873624Y580624D02*
X873621D01*
G01X853543Y560933D02*
Y555957D01*
G01X853545Y560934D02*
X853543Y560933D01*
G01X880317Y580624D02*
Y588711D01*
G01X870275Y560933D02*
Y555961D01*
G01X870277Y560934D02*
X870275Y560933D01*
G01X893000Y548933D02*
Y550914D01*
G01X893700Y548233D02*
X893000Y548933D01*
G01X893700Y542824D02*
Y548233D01*
G01X893702Y542824D02*
X893700D01*
G01X887007Y580624D02*
Y588414D01*
G01X887009Y580624D02*
X887007D01*
G01X893000Y586733D02*
Y588714D01*
G01X893700Y586033D02*
X893000Y586733D01*
G01X893700Y580624D02*
Y586033D01*
G01X893702Y580624D02*
X893700D01*
G01X850196Y550614D02*
X849896Y550914D01*
G01X850196Y542824D02*
Y550614D01*
G01X850198Y542824D02*
X850196D01*
G01Y580624D02*
X850198D01*
G01X850196Y588414D02*
Y580624D01*
G01X890354Y560933D02*
Y555957D01*
G01X890356Y560934D02*
X890354Y560933D01*
G01X870275Y598733D02*
Y593761D01*
G01X870277Y598734D02*
X870275Y598733D01*
G01X880317Y588711D02*
X880314Y588714D01*
G01X887007Y588414D02*
X886707Y588714D01*
G01X853543Y598733D02*
Y593757D01*
G01X853545Y598734D02*
X853543Y598733D01*
G01X849896Y588714D02*
X850196Y588414D01*
G01X883661Y598733D02*
Y593757D01*
G01X883663Y598734D02*
X883661Y598733D01*
G01X907086D02*
Y593757D01*
G01X907088Y598734D02*
X907086Y598733D01*
G01X876968D02*
Y593757D01*
G01X876970Y598734D02*
X876968Y598733D01*
G01X890354D02*
Y593757D01*
G01X890356Y598734D02*
X890354Y598733D01*
G01X910435Y12111D02*
X910432Y12114D01*
G01X910435Y4023D02*
Y12111D01*
G01X920472Y22133D02*
Y17157D01*
G01X920474Y22133D02*
X920472D01*
G01X929811Y10133D02*
Y12114D01*
G01X930511Y9433D02*
X929811Y10133D01*
G01X930511Y4023D02*
Y9433D01*
G01X930513Y4023D02*
X930511D01*
G01X950590Y22133D02*
Y17157D01*
G01X950592Y22133D02*
X950590D01*
G01X963976D02*
Y17057D01*
G01X963978Y22133D02*
X963976D01*
G01X943897D02*
Y17157D01*
G01X943899Y22133D02*
X943897D01*
G01X923818Y11814D02*
X923518Y12114D01*
G01X923818Y4023D02*
Y11814D01*
G01X923820Y4023D02*
X923818D01*
G01X960629D02*
Y9114D01*
G01X960631Y4023D02*
X960629D01*
G01X970669Y22133D02*
Y17057D01*
G01X970671Y22133D02*
X970669D01*
G01X917128Y12111D02*
X917125Y12114D01*
G01X917128Y4023D02*
Y12111D01*
G01X927165Y22133D02*
Y17157D01*
G01X927167Y22133D02*
X927165D01*
G01X947246Y12111D02*
X947243Y12114D01*
G01X947246Y4023D02*
Y12111D01*
G01X953939D02*
X953936Y12114D01*
G01X953939Y4023D02*
Y12111D01*
G01X913779Y22133D02*
Y17157D01*
G01X913781Y22133D02*
X913779D01*
G01X943897Y59933D02*
Y54957D01*
G01X943899Y59933D02*
X943897D01*
G01X913779Y97733D02*
Y92757D01*
G01X963976Y97733D02*
Y92657D01*
G01X950590Y97733D02*
Y92757D01*
G01X910432Y41823D02*
Y49914D01*
G01X910435Y41823D02*
X910432D01*
G01X913779Y59933D02*
Y54957D01*
G01X913781Y59933D02*
X913779D01*
G01X953939Y49911D02*
X953936Y49914D01*
G01X953939Y41823D02*
Y49911D01*
G01X920472Y59933D02*
Y54957D01*
G01X920474Y59933D02*
X920472D01*
G01X950592Y54959D02*
X950590Y54957D01*
G01X950592Y59933D02*
Y54959D01*
G01X917128Y87711D02*
X917125Y87714D01*
G01X917128Y79623D02*
Y87711D01*
G01X960629Y41823D02*
Y46914D01*
G01X960631Y41823D02*
X960629D01*
G01X920472Y97733D02*
Y92757D01*
G01X917125Y42344D02*
Y49914D01*
G01X917126Y42343D02*
X917125Y42344D01*
G01X917126Y41823D02*
Y42343D01*
G01X917128Y41823D02*
X917126D01*
G01X963976Y59933D02*
Y54857D01*
G01X963978Y59933D02*
X963976D01*
G01X923818Y49614D02*
X923518Y49914D01*
G01X923818Y41823D02*
Y49614D01*
G01X923820Y41823D02*
X923818D01*
G01X970669Y97733D02*
Y92757D01*
G01X960629Y79623D02*
Y84714D01*
G01X960631Y79623D02*
X960629D01*
G01X927165Y59933D02*
Y54957D01*
G01X927167Y59933D02*
X927165D01*
G01X953936Y82574D02*
Y87714D01*
G01X953937Y82573D02*
X953936Y82574D01*
G01X953937Y79623D02*
Y82573D01*
G01X953939Y79623D02*
X953937D01*
G01X947243Y43744D02*
Y49914D01*
G01X947244Y43743D02*
X947243Y43744D01*
G01X947244Y41823D02*
Y43743D01*
G01X947246Y41823D02*
X947244D01*
G01X927165Y97733D02*
Y92757D01*
G01X929811Y47933D02*
Y49914D01*
G01X930511Y47233D02*
X929811Y47933D01*
G01X930511Y41823D02*
Y47233D01*
G01X930513Y41823D02*
X930511D01*
G01X970669Y59933D02*
Y54857D01*
G01X970671Y59933D02*
X970669D01*
G01X923818Y87414D02*
X923518Y87714D01*
G01X923818Y79623D02*
Y87414D01*
G01X923820Y79623D02*
X923818D01*
G01X910435Y87711D02*
X910432Y87714D01*
G01X910435Y79623D02*
Y87711D01*
G01X943897Y97733D02*
Y92757D01*
G01X929811Y85733D02*
Y87714D01*
G01X930511Y85033D02*
X929811Y85733D01*
G01X930511Y79623D02*
Y85033D01*
G01X930513Y79623D02*
X930511D01*
G01X947246Y87711D02*
X947243Y87714D01*
G01X947246Y79623D02*
Y87711D01*
G01X913781Y97733D02*
X913779D01*
G01X963978D02*
X963976D01*
G01X950592D02*
X950590D01*
G01X920474D02*
X920472D01*
G01X970671D02*
X970669D01*
G01X927167D02*
X927165D01*
G01X943899D02*
X943897D01*
G01X966724Y253100D02*
X964639D01*
G01X968218Y254594D02*
X966724Y253100D01*
G01X964639Y258404D02*
Y256600D01*
G01X966328Y260093D02*
X964639Y258404D01*
G01X967589Y260093D02*
X966328D01*
G01X927165Y523133D02*
Y518157D01*
G01X927167Y523134D02*
X927165Y523133D01*
G01X947243Y505024D02*
Y513114D01*
G01X947246Y505024D02*
X947243D01*
G01X953937D02*
X953939D01*
G01X953937Y507973D02*
Y505024D01*
G01X953936Y507974D02*
X953937Y507973D01*
G01X953936Y513114D02*
Y507974D01*
G01X960629Y505024D02*
Y510114D01*
G01X960631Y505024D02*
X960629D01*
G01X920472Y523133D02*
Y518157D01*
G01X920474Y523134D02*
X920472Y523133D01*
G01X963976D02*
Y518057D01*
G01X963978Y523134D02*
X963976Y523133D01*
G01X913779D02*
Y518157D01*
G01X913781Y523134D02*
X913779Y523133D01*
G01X970669D02*
Y518157D01*
G01X970671Y523134D02*
X970669Y523133D01*
G01X943897D02*
Y518157D01*
G01X943899Y523134D02*
X943897Y523133D01*
G01X929811Y511133D02*
Y513114D01*
G01X930511Y510433D02*
X929811Y511133D01*
G01X930511Y505024D02*
Y510433D01*
G01X930513Y505024D02*
X930511D01*
G01X910435Y513111D02*
X910432Y513114D01*
G01X910435Y505024D02*
Y513111D01*
G01X923818Y512814D02*
X923518Y513114D01*
G01X923818Y505024D02*
Y512814D01*
G01X923820Y505024D02*
X923818D01*
G01X917125D02*
Y513114D01*
G01X917128Y505024D02*
X917125D01*
G01X950590Y523133D02*
Y518157D01*
G01X950592Y523134D02*
X950590Y523133D01*
G01X960629Y542824D02*
Y547914D01*
G01X960631Y542824D02*
X960629D01*
G01X953936Y583574D02*
Y588714D01*
G01X953937Y583573D02*
X953936Y583574D01*
G01X953937Y580624D02*
Y583573D01*
G01X953939Y580624D02*
X953937D01*
G01X943897Y560933D02*
Y555957D01*
G01X943899Y560934D02*
X943897Y560933D01*
G01X923818Y580624D02*
X923820D01*
G01X923818Y588414D02*
Y580624D01*
G01X917125D02*
Y588714D01*
G01X917128Y580624D02*
X917125D01*
G01X950590Y560933D02*
Y555957D01*
G01X950592Y560934D02*
X950590Y560933D01*
G01X913779D02*
Y555957D01*
G01X913781Y560934D02*
X913779Y560933D01*
G01X923818Y550614D02*
X923518Y550914D01*
G01X923818Y542824D02*
Y550614D01*
G01X923820Y542824D02*
X923818D01*
G01X927165Y560933D02*
Y555957D01*
G01X927167Y560934D02*
X927165Y560933D01*
G01X960629Y580624D02*
Y585714D01*
G01X960631Y580624D02*
X960629D01*
G01X930511D02*
X930513D01*
G01X930511Y586033D02*
Y580624D01*
G01X929811Y586733D02*
X930511Y586033D01*
G01X929811Y588714D02*
Y586733D01*
G01X970669Y560933D02*
Y555857D01*
G01X970671Y560934D02*
X970669Y560933D01*
G01X910435Y580624D02*
Y588711D01*
G01X917125Y542824D02*
X917128D01*
G01X917125Y550914D02*
Y542824D01*
G01X947243Y580624D02*
Y588714D01*
G01X947246Y580624D02*
X947243D01*
G01Y542824D02*
X947246D01*
G01X947243Y550914D02*
Y542824D01*
G01X953936Y545774D02*
Y550914D01*
G01X953937Y545773D02*
X953936Y545774D01*
G01X953937Y542824D02*
Y545773D01*
G01X953939Y542824D02*
X953937D01*
G01X920472Y560933D02*
Y555957D01*
G01X920474Y560934D02*
X920472Y560933D01*
G01X910435Y550911D02*
X910432Y550914D01*
G01X910435Y542824D02*
Y550911D01*
G01X929811Y548933D02*
Y550914D01*
G01X930511Y548233D02*
X929811Y548933D01*
G01X930511Y542824D02*
Y548233D01*
G01X930513Y542824D02*
X930511D01*
G01X963976Y560933D02*
Y555857D01*
G01X963978Y560934D02*
X963976Y560933D01*
G01X923518Y588714D02*
X923818Y588414D01*
G01X963976Y598733D02*
Y593657D01*
G01X963978Y598734D02*
X963976Y598733D01*
G01X920472D02*
Y593757D01*
G01X920474Y598734D02*
X920472Y598733D01*
G01X910435Y588711D02*
X910432Y588714D01*
G01X943897Y598733D02*
Y593757D01*
G01X943899Y598734D02*
X943897Y598733D01*
G01X970669D02*
Y593657D01*
G01X970671Y598734D02*
X970669Y598733D01*
G01X927165D02*
Y593757D01*
G01X927167Y598734D02*
X927165Y598733D01*
G01X913779D02*
Y593757D01*
G01X913781Y598734D02*
X913779Y598733D01*
G01X950590D02*
Y593757D01*
G01X950592Y598734D02*
X950590Y598733D01*
G01X997441Y4023D02*
Y9122D01*
G01X997443Y4023D02*
X997441D01*
G01X1004133D02*
Y9122D01*
G01X1004135Y4023D02*
X1004133D01*
G01X984055Y9113D02*
X984054Y9114D01*
G01X984055Y4023D02*
Y9113D01*
G01X984057Y4023D02*
X984055D01*
G01X974015D02*
Y9114D01*
G01X974017Y4023D02*
X974015D01*
G01X994094Y22133D02*
Y17057D01*
G01X994096Y22133D02*
X994094D01*
G01X990748D02*
Y17057D01*
G01X990750Y22133D02*
X990748D01*
G01X994094Y4023D02*
Y9122D01*
G01X994096Y4023D02*
X994094D01*
G01X987401D02*
Y9114D01*
G01X987403Y4023D02*
X987401D01*
G01X1004134Y17157D02*
Y17057D01*
G01X1004133Y17158D02*
X1004134Y17157D01*
G01X1004133Y22133D02*
Y17158D01*
G01X1004135Y22133D02*
X1004133D01*
G01X980708D02*
Y17057D01*
G01X980710Y22133D02*
X980708D01*
G01X984055D02*
Y17057D01*
G01X984057Y22133D02*
X984055D01*
G01X977362Y4023D02*
Y9114D01*
G01X977364Y4023D02*
X977362D01*
G01X1000787Y22133D02*
Y17057D01*
G01X1000789Y22133D02*
X1000787D01*
G01X974015D02*
Y17057D01*
G01X974017Y22133D02*
X974015D01*
G01X1004133Y41823D02*
Y46922D01*
G01X1004135Y41823D02*
X1004133D01*
G01X974015Y79623D02*
Y84599D01*
G01X974017Y79623D02*
X974015D01*
G01X980708Y59933D02*
Y54857D01*
G01X980710Y59933D02*
X980708D01*
G01X994094Y97733D02*
Y89964D01*
G01X980708Y97733D02*
Y89964D01*
G01X984055Y59933D02*
Y54857D01*
G01X984057Y59933D02*
X984055D01*
G01X994094Y41823D02*
Y46922D01*
G01X994096Y41823D02*
X994094D01*
G01X984055Y46913D02*
X984054Y46914D01*
G01X984055Y41823D02*
Y46913D01*
G01X984057Y41823D02*
X984055D01*
G01X1004133Y92867D02*
X1004023Y92757D01*
G01X1004133Y97733D02*
Y92867D01*
G01X987401Y79623D02*
Y84599D01*
G01X987403Y79623D02*
X987401D01*
G01X984055D02*
Y87392D01*
G01X984057Y79623D02*
X984055D01*
G01Y97733D02*
Y92757D01*
G01X990748Y97733D02*
Y92757D01*
G01X997441Y79623D02*
Y87392D01*
G01X997443Y79623D02*
X997441D01*
G01X990748Y59933D02*
Y54857D01*
G01X990750Y59933D02*
X990748D01*
G01X977362Y41823D02*
Y46914D01*
G01X977364Y41823D02*
X977362D01*
G01X987401D02*
Y46914D01*
G01X987403Y41823D02*
X987401D01*
G01X974015D02*
Y46914D01*
G01X974017Y41823D02*
X974015D01*
G01X997441D02*
Y46922D01*
G01X997443Y41823D02*
X997441D01*
G01X1000787Y97733D02*
Y89964D01*
G01X1004134Y54957D02*
Y54857D01*
G01X1004133Y54958D02*
X1004134Y54957D01*
G01X1004133Y59933D02*
Y54958D01*
G01X1004135Y59933D02*
X1004133D01*
G01X1000787D02*
Y54857D01*
G01X1000789Y59933D02*
X1000787D01*
G01X974015D02*
Y54857D01*
G01X974017Y59933D02*
X974015D01*
G01Y97733D02*
Y89964D01*
G01X1004133Y87282D02*
X1004023Y87392D01*
G01X1004133Y79623D02*
Y87282D01*
G01X1004135Y79623D02*
X1004133D01*
G01X977362D02*
Y87392D01*
G01X977364Y79623D02*
X977362D01*
G01X994094Y59933D02*
Y54857D01*
G01X994096Y59933D02*
X994094D01*
G01Y79623D02*
Y84714D01*
G01X994096Y79623D02*
X994094D01*
G01X994096Y97733D02*
X994094D01*
G01X980710D02*
X980708D01*
G01X1004135D02*
X1004133D01*
G01X984057D02*
X984055D01*
G01X990750D02*
X990748D01*
G01X1000789D02*
X1000787D01*
G01X974017D02*
X974015D01*
G01X997441Y505024D02*
Y512792D01*
G01X997443Y505024D02*
X997441D01*
G01X977362D02*
Y512792D01*
G01X977364Y505024D02*
X977362D01*
G01X994094D02*
Y510114D01*
G01X994096Y505024D02*
X994094D01*
G01X1000787Y523133D02*
Y515364D01*
G01X1000789Y523134D02*
X1000787Y523133D01*
G01X974015Y505024D02*
Y509999D01*
G01X974017Y505024D02*
X974015D01*
G01X990748Y523133D02*
Y518157D01*
G01X990750Y523134D02*
X990748Y523133D01*
G01X1004133Y512574D02*
X1003915Y512792D01*
G01X1004133Y505024D02*
Y512574D01*
G01X1004135Y505024D02*
X1004133D01*
G01X987401D02*
Y509999D01*
G01X987403Y505024D02*
X987401D01*
G01X984055D02*
Y512792D01*
G01X984057Y505024D02*
X984055D01*
G01Y523133D02*
Y518157D01*
G01X984057Y523134D02*
X984055Y523133D01*
G01X974015D02*
Y515364D01*
G01X974017Y523134D02*
X974015Y523133D01*
G01X980708D02*
Y515364D01*
G01X980710Y523134D02*
X980708Y523133D01*
G01X994094D02*
Y515364D01*
G01X994096Y523134D02*
X994094Y523133D01*
G01X1004133Y518158D02*
X1004134Y518157D01*
G01X1004133Y523133D02*
Y518158D01*
G01X1004135Y523134D02*
X1004133Y523133D01*
G01Y580624D02*
Y585722D01*
G01X1004135Y580624D02*
X1004133D01*
G01X994094Y560933D02*
Y555857D01*
G01X994096Y560934D02*
X994094Y560933D01*
G01X984055D02*
Y555857D01*
G01X984057Y560934D02*
X984055Y560933D01*
G01X1004133Y542824D02*
Y547922D01*
G01X1004135Y542824D02*
X1004133D01*
G01X977362D02*
Y547914D01*
G01X977364Y542824D02*
X977362D01*
G01X994094Y580624D02*
Y585722D01*
G01X994096Y580624D02*
X994094D01*
G01X997441D02*
Y585722D01*
G01X997443Y580624D02*
X997441D01*
G01X987401Y542824D02*
Y547914D01*
G01X987403Y542824D02*
X987401D01*
G01X1000787Y560933D02*
Y555857D01*
G01X1000789Y560934D02*
X1000787Y560933D01*
G01X994094Y542824D02*
X994096D01*
G01X994094Y547922D02*
Y542824D01*
G01X977362Y580624D02*
Y585714D01*
G01X977364Y580624D02*
X977362D01*
G01X980708Y560933D02*
Y555857D01*
G01X980710Y560934D02*
X980708Y560933D01*
G01X997441Y542824D02*
Y547922D01*
G01X997443Y542824D02*
X997441D01*
G01X974015D02*
Y547914D01*
G01X974017Y542824D02*
X974015D01*
G01X984055Y585713D02*
X984054Y585714D01*
G01X984055Y580624D02*
Y585713D01*
G01X984057Y580624D02*
X984055D01*
G01Y547913D02*
X984054Y547914D01*
G01X984055Y542824D02*
Y547913D01*
G01X984057Y542824D02*
X984055D01*
G01X974015Y580624D02*
Y585714D01*
G01X974017Y580624D02*
X974015D01*
G01X990748Y560933D02*
Y555857D01*
G01X990750Y560934D02*
X990748Y560933D01*
G01X987401Y580624D02*
Y585714D01*
G01X987403Y580624D02*
X987401D01*
G01X974015Y560933D02*
Y555857D01*
G01X974017Y560934D02*
X974015Y560933D01*
G01X1004134Y555957D02*
Y555857D01*
G01X1004133Y555958D02*
X1004134Y555957D01*
G01X1004133Y560933D02*
Y555958D01*
G01X1004135Y560934D02*
X1004133Y560933D01*
G01X1004134Y593757D02*
Y593657D01*
G01X1004133Y593758D02*
X1004134Y593757D01*
G01X1004133Y598733D02*
Y593758D01*
G01X1004135Y598734D02*
X1004133Y598733D01*
G01X994094D02*
Y593657D01*
G01X994096Y598734D02*
X994094Y598733D01*
G01X984055D02*
Y593657D01*
G01X984057Y598734D02*
X984055Y598733D01*
G01X990748D02*
Y593657D01*
G01X990750Y598734D02*
X990748Y598733D01*
G01X1000787D02*
Y593657D01*
G01X1000789Y598734D02*
X1000787Y598733D01*
G01X980708D02*
Y593657D01*
G01X980710Y598734D02*
X980708Y598733D01*
G01X974015D02*
Y593657D01*
G01X974017Y598734D02*
X974015Y598733D01*
G01X1094488Y4023D02*
Y9122D01*
G01X1094490Y4023D02*
X1094488D01*
G01X1077755Y9120D02*
X1077757Y9122D01*
G01X1077755Y4023D02*
Y9120D01*
G01X1077757Y4023D02*
X1077755D01*
G01X1074409Y22133D02*
Y17042D01*
G01X1074411Y22133D02*
X1074409D01*
G01X1054330Y17058D02*
X1054331Y17057D01*
G01X1054330Y22133D02*
Y17058D01*
G01X1054332Y22133D02*
X1054330D01*
G01X1050984Y9121D02*
X1050985Y9122D01*
G01X1050984Y4023D02*
Y9121D01*
G01X1050986Y4023D02*
X1050984D01*
G01X1087795Y9120D02*
X1087797Y9122D01*
G01X1087795Y4023D02*
Y9120D01*
G01X1087797Y4023D02*
X1087795D01*
G01X1047637Y22133D02*
Y17042D01*
G01X1047639Y22133D02*
X1047637D01*
G01X1084448Y9120D02*
X1084450Y9122D01*
G01X1084448Y4023D02*
Y9120D01*
G01X1084450Y4023D02*
X1084448D01*
G01X1071065Y17058D02*
X1071064Y17057D01*
G01X1071065Y22133D02*
Y17058D01*
G01X1081102Y22133D02*
Y17042D01*
G01X1081104Y22133D02*
X1081102D01*
G01X1087795D02*
Y17059D01*
G01X1087797Y22133D02*
X1087795D01*
G01X1044293Y11789D02*
X1044290Y11792D01*
G01X1044293Y4023D02*
Y11789D01*
G01X1094488Y22133D02*
Y17059D01*
G01X1094490Y22133D02*
X1094488D01*
G01X1064370Y9121D02*
X1064371Y9122D01*
G01X1064370Y4023D02*
Y9121D01*
G01X1064372Y4023D02*
X1064370D01*
G01X1057677Y22133D02*
Y17042D01*
G01X1057679Y22133D02*
X1057677D01*
G01X1064370Y17058D02*
X1064371Y17057D01*
G01X1064370Y22133D02*
Y17058D01*
G01X1064372Y22133D02*
X1064370D01*
G01X1054330Y9121D02*
X1054331Y9122D01*
G01X1054330Y4023D02*
Y9121D01*
G01X1054332Y4023D02*
X1054330D01*
G01Y79623D02*
Y84599D01*
G01X1054332Y79623D02*
X1054330D01*
G01X1094488Y41823D02*
Y46922D01*
G01X1094490Y41823D02*
X1094488D01*
G01X1077755Y79623D02*
Y87392D01*
G01X1077757Y79623D02*
X1077755D01*
G01X1044291Y87391D02*
X1044290Y87392D01*
G01X1044291Y79623D02*
Y87391D01*
G01X1044293Y79623D02*
X1044291D01*
G01X1074409Y59933D02*
Y54842D01*
G01X1074411Y59933D02*
X1074409D01*
G01X1057677D02*
Y54842D01*
G01X1057679Y59933D02*
X1057677D01*
G01X1054330Y97733D02*
Y89964D01*
G01X1087795Y97733D02*
Y89964D01*
G01Y79623D02*
Y84714D01*
G01X1087797Y79623D02*
X1087795D01*
G01X1064370Y92758D02*
X1064369Y92757D01*
G01X1064370Y97733D02*
Y92758D01*
G01X1074409Y97733D02*
Y89964D01*
G01X1044290Y41826D02*
X1044293Y41823D01*
G01X1044290Y49592D02*
Y41826D01*
G01X1084448Y46920D02*
X1084450Y46922D01*
G01X1084448Y41823D02*
Y46920D01*
G01X1084450Y41823D02*
X1084448D01*
G01X1047637Y97733D02*
Y89964D01*
G01Y59933D02*
Y54842D01*
G01X1047639Y59933D02*
X1047637D01*
G01X1084448Y79623D02*
Y87392D01*
G01X1084450Y79623D02*
X1084448D01*
G01X1050984Y46921D02*
X1050985Y46922D01*
G01X1050984Y41823D02*
Y46921D01*
G01X1050986Y41823D02*
X1050984D01*
G01X1057677Y92758D02*
X1057676Y92757D01*
G01X1057677Y97733D02*
Y92758D01*
G01X1054330Y46921D02*
X1054331Y46922D01*
G01X1054330Y41823D02*
Y46921D01*
G01X1054332Y41823D02*
X1054330D01*
G01X1081102Y59933D02*
Y54842D01*
G01X1081104Y59933D02*
X1081102D01*
G01X1077755Y46920D02*
X1077757Y46922D01*
G01X1077755Y41823D02*
Y46920D01*
G01X1077757Y41823D02*
X1077755D01*
G01X1071063Y92758D02*
X1071062Y92757D01*
G01X1071063Y97733D02*
Y92758D01*
G01X1094488Y79623D02*
Y84714D01*
G01X1094490Y79623D02*
X1094488D01*
G01Y97733D02*
Y89964D01*
G01X1054330Y54858D02*
X1054331Y54857D01*
G01X1054330Y59933D02*
Y54858D01*
G01X1054332Y59933D02*
X1054330D01*
G01X1087795D02*
Y54859D01*
G01X1087797Y59933D02*
X1087795D01*
G01X1081102Y97733D02*
Y89964D01*
G01X1064370Y46921D02*
X1064371Y46922D01*
G01X1064370Y41823D02*
Y46921D01*
G01X1064372Y41823D02*
X1064370D01*
G01X1064372Y87389D02*
X1064369Y87392D01*
G01X1064372Y79623D02*
Y87389D01*
G01X1064370Y54858D02*
X1064371Y54857D01*
G01X1064370Y59933D02*
Y54858D01*
G01X1064372Y59933D02*
X1064370D01*
G01X1050984Y87391D02*
X1050983Y87392D01*
G01X1050984Y79623D02*
Y87391D01*
G01X1050986Y79623D02*
X1050984D01*
G01X1094488Y59933D02*
Y54859D01*
G01X1094490Y59933D02*
X1094488D01*
G01X1054332Y97733D02*
X1054330D01*
G01X1087797D02*
X1087795D01*
G01X1064372D02*
X1064370D01*
G01X1074411D02*
X1074409D01*
G01X1047639D02*
X1047637D01*
G01X1057679D02*
X1057677D01*
G01X1071065D02*
X1071063D01*
G01X1094490D02*
X1094488D01*
G01X1081104D02*
X1081102D01*
G01X1094488Y505024D02*
Y510114D01*
G01X1094490Y505024D02*
X1094488D01*
G01X1064370Y518158D02*
X1064369Y518157D01*
G01X1064370Y523133D02*
Y518158D01*
G01X1064372Y523134D02*
X1064370Y523133D01*
G01X1064369Y505024D02*
X1064372D01*
G01X1064369Y512792D02*
Y505024D01*
G01X1087795Y523133D02*
Y515364D01*
G01X1087797Y523134D02*
X1087795Y523133D01*
G01X1084448Y505024D02*
Y512792D01*
G01X1084450Y505024D02*
X1084448D01*
G01X1087795D02*
Y510114D01*
G01X1087797Y505024D02*
X1087795D01*
G01X1074409Y523133D02*
Y515364D01*
G01X1074411Y523134D02*
X1074409Y523133D01*
G01X1050984Y512791D02*
X1050983Y512792D01*
G01X1050984Y505024D02*
Y512791D01*
G01X1050986Y505024D02*
X1050984D01*
G01X1077755D02*
X1077757D01*
G01X1077755Y512792D02*
Y505024D01*
G01X1094488Y523133D02*
Y515364D01*
G01X1094490Y523134D02*
X1094488Y523133D01*
G01X1081102D02*
Y515364D01*
G01X1081104Y523134D02*
X1081102Y523133D01*
G01X1044291Y512791D02*
X1044290Y512792D01*
G01X1044291Y505024D02*
Y512791D01*
G01X1044293Y505024D02*
X1044291D01*
G01X1057677Y518158D02*
X1057676Y518157D01*
G01X1057677Y523133D02*
Y518158D01*
G01X1057679Y523134D02*
X1057677Y523133D01*
G01X1047637D02*
Y515364D01*
G01X1047639Y523134D02*
X1047637Y523133D01*
G01X1071063Y518158D02*
X1071062Y518157D01*
G01X1071063Y523133D02*
Y518158D01*
G01X1071065Y523134D02*
X1071063Y523133D01*
G01X1054330D02*
Y515364D01*
G01X1054332Y523134D02*
X1054330Y523133D01*
G01Y505024D02*
Y509999D01*
G01X1054332Y505024D02*
X1054330D01*
G01X1064370Y547921D02*
X1064371Y547922D01*
G01X1064370Y542824D02*
Y547921D01*
G01X1064372Y542824D02*
X1064370D01*
G01X1084448Y547920D02*
X1084450Y547922D01*
G01X1084448Y542824D02*
Y547920D01*
G01X1084450Y542824D02*
X1084448D01*
G01X1044291Y550591D02*
X1044290Y550592D01*
G01X1044291Y542824D02*
Y550591D01*
G01X1044293Y542824D02*
X1044291D01*
G01X1064370Y555858D02*
X1064371Y555857D01*
G01X1064370Y560933D02*
Y555858D01*
G01X1064372Y560934D02*
X1064370Y560933D01*
G01X1050984Y585721D02*
X1050985Y585722D01*
G01X1050984Y580624D02*
Y585721D01*
G01X1050986Y580624D02*
X1050984D01*
G01X1094488D02*
Y585722D01*
G01X1094490Y580624D02*
X1094488D01*
G01X1077755Y547920D02*
X1077757Y547922D01*
G01X1077755Y542824D02*
Y547920D01*
G01X1077757Y542824D02*
X1077755D01*
G01X1084448Y585720D02*
X1084450Y585722D01*
G01X1084448Y580624D02*
Y585720D01*
G01X1084450Y580624D02*
X1084448D01*
G01X1057677Y560933D02*
Y555842D01*
G01X1057679Y560934D02*
X1057677Y560933D01*
G01X1074409D02*
Y555842D01*
G01X1074411Y560934D02*
X1074409Y560933D01*
G01X1087795D02*
Y555859D01*
G01X1087797Y560934D02*
X1087795Y560933D01*
G01Y547920D02*
X1087797Y547922D01*
G01X1087795Y542824D02*
Y547920D01*
G01X1087797Y542824D02*
X1087795D01*
G01X1054330Y547921D02*
X1054331Y547922D01*
G01X1054330Y542824D02*
Y547921D01*
G01X1054332Y542824D02*
X1054330D01*
G01Y585721D02*
X1054331Y585722D01*
G01X1054330Y580624D02*
Y585721D01*
G01X1054332Y580624D02*
X1054330D01*
G01Y555858D02*
X1054331Y555857D01*
G01X1054330Y560933D02*
Y555858D01*
G01X1054332Y560934D02*
X1054330Y560933D01*
G01X1081102D02*
Y555842D01*
G01X1081104Y560934D02*
X1081102Y560933D01*
G01X1044293Y580624D02*
Y588389D01*
G01X1077755Y580624D02*
X1077757D01*
G01X1077755Y585720D02*
Y580624D01*
G01X1077757Y585722D02*
X1077755Y585720D01*
G01X1094488Y542824D02*
Y547922D01*
G01X1094490Y542824D02*
X1094488D01*
G01Y560933D02*
Y555859D01*
G01X1094490Y560934D02*
X1094488Y560933D01*
G01X1047637D02*
Y555842D01*
G01X1047639Y560934D02*
X1047637Y560933D01*
G01X1050984Y542824D02*
Y547922D01*
G01X1050986Y542824D02*
X1050984D01*
G01X1064370Y585721D02*
X1064371Y585722D01*
G01X1064370Y580624D02*
Y585721D01*
G01X1064372Y580624D02*
X1064370D01*
G01X1094488Y598733D02*
Y593659D01*
G01X1094490Y598734D02*
X1094488Y598733D01*
G01X1087795D02*
Y593659D01*
G01X1087797Y598734D02*
X1087795Y598733D01*
G01X1074409D02*
Y593642D01*
G01X1074411Y598734D02*
X1074409Y598733D01*
G01X1044293Y588389D02*
X1044290Y588392D01*
G01X1064370Y593658D02*
X1064371Y593657D01*
G01X1064370Y598733D02*
Y593658D01*
G01X1064372Y598734D02*
X1064370Y598733D01*
G01X1057677D02*
Y593642D01*
G01X1057679Y598734D02*
X1057677Y598733D01*
G01X1047637D02*
Y593642D01*
G01X1047639Y598734D02*
X1047637Y598733D01*
G01X1054330Y593658D02*
X1054331Y593657D01*
G01X1054330Y598733D02*
Y593658D01*
G01X1054332Y598734D02*
X1054330Y598733D01*
G01X1081102D02*
Y593642D01*
G01X1081104Y598734D02*
X1081102Y598733D01*
G01X1124606Y22133D02*
Y17157D01*
G01X1124608Y22133D02*
X1124606D01*
G01X1141338Y11814D02*
X1141038Y12114D01*
G01X1141338Y4023D02*
Y11814D01*
G01X1141340Y4023D02*
X1141338D01*
G01X1104227Y9273D02*
Y12114D01*
G01X1104527Y8973D02*
X1104227Y9273D01*
G01X1104527Y4023D02*
Y8973D01*
G01X1104529Y4023D02*
X1104527D01*
G01X1147331Y10133D02*
Y12114D01*
G01X1148031Y9433D02*
X1147331Y10133D01*
G01X1148031Y4023D02*
Y9433D01*
G01X1148033Y4023D02*
X1148031D01*
G01X1144685Y22133D02*
Y17157D01*
G01X1144687Y22133D02*
X1144685D01*
G01X1127952Y4023D02*
Y12114D01*
G01X1127954Y4023D02*
X1127952D01*
G01X1101181Y22133D02*
Y17157D01*
G01X1101183Y22133D02*
X1101181D01*
G01X1134645Y4023D02*
Y12114D01*
G01X1134647Y4023D02*
X1134645D01*
G01X1131299Y22133D02*
Y17157D01*
G01X1131301Y22133D02*
X1131299D01*
G01X1107874D02*
Y17157D01*
G01X1107876Y22133D02*
X1107874D01*
G01X1110520Y10133D02*
Y12114D01*
G01X1111220Y9433D02*
X1110520Y10133D01*
G01X1111220Y4023D02*
Y9433D01*
G01X1111222Y4023D02*
X1111220D01*
G01X1137992Y22133D02*
Y17157D01*
G01X1137994Y22133D02*
X1137992D01*
G01X1110520Y85733D02*
Y87714D01*
G01X1111220Y85033D02*
X1110520Y85733D01*
G01X1111220Y79623D02*
Y85033D01*
G01X1111222Y79623D02*
X1111220D01*
G01X1131299Y59933D02*
Y54957D01*
G01X1131301Y59933D02*
X1131299D01*
G01X1104527Y87414D02*
X1104227Y87714D01*
G01X1104527Y79623D02*
Y87414D01*
G01X1104529Y79623D02*
X1104527D01*
G01Y49264D02*
X1104227Y49564D01*
G01X1104527Y41823D02*
Y49264D01*
G01X1104529Y41823D02*
X1104527D01*
G01X1144685Y59933D02*
Y54957D01*
G01X1144687Y59933D02*
X1144685D01*
G01X1131299Y97733D02*
Y92757D01*
G01X1147331Y47933D02*
Y49914D01*
G01X1148031Y47233D02*
X1147331Y47933D01*
G01X1148031Y41823D02*
Y47233D01*
G01X1148033Y41823D02*
X1148031D01*
G01X1144685Y97733D02*
Y92757D01*
G01X1124606Y97733D02*
Y92757D01*
G01X1107874Y97733D02*
Y92757D01*
G01X1137992Y97733D02*
Y92757D01*
G01X1124606Y59933D02*
Y54957D01*
G01X1124608Y59933D02*
X1124606D01*
G01X1107874D02*
Y54957D01*
G01X1107876Y59933D02*
X1107874D01*
G01X1141338Y49614D02*
X1141038Y49914D01*
G01X1141338Y41823D02*
Y49614D01*
G01X1141340Y41823D02*
X1141338D01*
G01X1134645Y79623D02*
Y87714D01*
G01X1134647Y79623D02*
X1134645D01*
G01X1101181Y59933D02*
Y54957D01*
G01X1101183Y59933D02*
X1101181D01*
G01X1127952Y41823D02*
Y49914D01*
G01X1127954Y41823D02*
X1127952D01*
G01X1110520Y47933D02*
Y49914D01*
G01X1111220Y47233D02*
X1110520Y47933D01*
G01X1111220Y41823D02*
Y47233D01*
G01X1111222Y41823D02*
X1111220D01*
G01X1147331Y85733D02*
Y87714D01*
G01X1148031Y85033D02*
X1147331Y85733D01*
G01X1148031Y79623D02*
Y85033D01*
G01X1148033Y79623D02*
X1148031D01*
G01X1127952D02*
Y87714D01*
G01X1127954Y79623D02*
X1127952D01*
G01X1137992Y59933D02*
Y54957D01*
G01X1137994Y59933D02*
X1137992D01*
G01X1134645Y41823D02*
Y49914D01*
G01X1134647Y41823D02*
X1134645D01*
G01X1101181Y97733D02*
Y92757D01*
G01X1141338Y87414D02*
X1141038Y87714D01*
G01X1141338Y79623D02*
Y87414D01*
G01X1141340Y79623D02*
X1141338D01*
G01X1131301Y97733D02*
X1131299D01*
G01X1144687D02*
X1144685D01*
G01X1124608D02*
X1124606D01*
G01X1107876D02*
X1107874D01*
G01X1137994D02*
X1137992D01*
G01X1101183D02*
X1101181D01*
G01X1124606Y523133D02*
Y518157D01*
G01X1124608Y523134D02*
X1124606Y523133D01*
G01X1110520Y511133D02*
Y513114D01*
G01X1111220Y510433D02*
X1110520Y511133D01*
G01X1111220Y505024D02*
Y510433D01*
G01X1111222Y505024D02*
X1111220D01*
G01X1107874Y523133D02*
Y518157D01*
G01X1107876Y523134D02*
X1107874Y523133D01*
G01X1104527Y512814D02*
X1104227Y513114D01*
G01X1104527Y505024D02*
Y512814D01*
G01X1104529Y505024D02*
X1104527D01*
G01X1141338Y512814D02*
X1141038Y513114D01*
G01X1141338Y505024D02*
Y512814D01*
G01X1141340Y505024D02*
X1141338D01*
G01X1148031D02*
X1148033D01*
G01X1148031Y510433D02*
Y505024D01*
G01X1147331Y511133D02*
X1148031Y510433D01*
G01X1147331Y513114D02*
Y511133D01*
G01X1131299Y523133D02*
Y518157D01*
G01X1131301Y523134D02*
X1131299Y523133D01*
G01X1101181D02*
Y518157D01*
G01X1101183Y523134D02*
X1101181Y523133D01*
G01X1144685D02*
Y518157D01*
G01X1144687Y523134D02*
X1144685Y523133D01*
G01X1137992D02*
Y518157D01*
G01X1137994Y523134D02*
X1137992Y523133D01*
G01X1127952Y505024D02*
Y513114D01*
G01X1127954Y505024D02*
X1127952D01*
G01X1134645D02*
X1134647D01*
G01X1134645Y513114D02*
Y505024D01*
G01X1101181Y560933D02*
Y555957D01*
G01X1101183Y560934D02*
X1101181Y560933D01*
G01X1110520Y548933D02*
Y550914D01*
G01X1111220Y548233D02*
X1110520Y548933D01*
G01X1111220Y542824D02*
Y548233D01*
G01X1111222Y542824D02*
X1111220D01*
G01X1134645D02*
Y550914D01*
G01X1134647Y542824D02*
X1134645D01*
G01X1124606Y560933D02*
Y555957D01*
G01X1124608Y560934D02*
X1124606Y560933D01*
G01X1107874D02*
Y555957D01*
G01X1107876Y560934D02*
X1107874Y560933D01*
G01X1131299D02*
Y555957D01*
G01X1131301Y560934D02*
X1131299Y560933D01*
G01X1110520Y586733D02*
Y588714D01*
G01X1111220Y586033D02*
X1110520Y586733D01*
G01X1111220Y580624D02*
Y586033D01*
G01X1111222Y580624D02*
X1111220D01*
G01X1144685Y560933D02*
Y555957D01*
G01X1144687Y560934D02*
X1144685Y560933D01*
G01X1147331Y548933D02*
Y550914D01*
G01X1148031Y548233D02*
X1147331Y548933D01*
G01X1148031Y542824D02*
Y548233D01*
G01X1148033Y542824D02*
X1148031D01*
G01X1147331Y586733D02*
Y588714D01*
G01X1148031Y586033D02*
X1147331Y586733D01*
G01X1148031Y580624D02*
Y586033D01*
G01X1148033Y580624D02*
X1148031D01*
G01X1127952Y542824D02*
X1127954D01*
G01X1127952Y550914D02*
Y542824D01*
G01X1141338Y580624D02*
Y588414D01*
G01X1141340Y580624D02*
X1141338D01*
G01X1127952D02*
X1127954D01*
G01X1127952Y588714D02*
Y580624D01*
G01X1104527Y550614D02*
X1104227Y550914D01*
G01X1104527Y542824D02*
Y550614D01*
G01X1104529Y542824D02*
X1104527D01*
G01X1134645Y580624D02*
Y588714D01*
G01X1134647Y580624D02*
X1134645D01*
G01X1137992Y560933D02*
Y555957D01*
G01X1137994Y560934D02*
X1137992Y560933D01*
G01X1141338Y550614D02*
X1141038Y550914D01*
G01X1141338Y542824D02*
Y550614D01*
G01X1141340Y542824D02*
X1141338D01*
G01X1104527Y580624D02*
Y588414D01*
G01X1104529Y580624D02*
X1104527D01*
G01X1124606Y598733D02*
Y593757D01*
G01X1124608Y598734D02*
X1124606Y598733D01*
G01X1144685D02*
Y593757D01*
G01X1144687Y598734D02*
X1144685Y598733D01*
G01X1137992D02*
Y593757D01*
G01X1137994Y598734D02*
X1137992Y598733D01*
G01X1131299D02*
Y593757D01*
G01X1131301Y598734D02*
X1131299Y598733D01*
G01X1101181D02*
Y593757D01*
G01X1101183Y598734D02*
X1101181Y598733D01*
G01X1141338Y588414D02*
X1141038Y588714D01*
G01X1107874Y598733D02*
Y593757D01*
G01X1107876Y598734D02*
X1107874Y598733D01*
G01X1104527Y588414D02*
X1104227Y588714D01*
G01X1181496Y22133D02*
Y17157D01*
G01X1181498Y22133D02*
X1181496D01*
G01X1171456Y4023D02*
Y12114D01*
G01X1171458Y4023D02*
X1171456D01*
G01X1201574D02*
Y12114D01*
G01X1201576Y4023D02*
X1201574D01*
G01X1214960Y11814D02*
X1214660Y12114D01*
G01X1214960Y4023D02*
Y11814D01*
G01X1214962Y4023D02*
X1214960D01*
G01X1208267D02*
Y12114D01*
G01X1208269Y4023D02*
X1208267D01*
G01X1198228Y22133D02*
Y17157D01*
G01X1198230Y22133D02*
X1198228D01*
G01X1168110D02*
Y17157D01*
G01X1168112Y22133D02*
X1168110D01*
G01X1178149Y11814D02*
X1177849Y12114D01*
G01X1178149Y4023D02*
Y11814D01*
G01X1178151Y4023D02*
X1178149D01*
G01X1164763D02*
Y12114D01*
G01X1164765Y4023D02*
X1164763D01*
G01X1211614Y22133D02*
Y17157D01*
G01X1211616Y22133D02*
X1211614D01*
G01X1204921D02*
Y17157D01*
G01X1204923Y22133D02*
X1204921D01*
G01X1174803D02*
Y17157D01*
G01X1174805Y22133D02*
X1174803D01*
G01X1161417D02*
Y17157D01*
G01X1161419Y22133D02*
X1161417D01*
G01X1184142Y10133D02*
Y12114D01*
G01X1184842Y9433D02*
X1184142Y10133D01*
G01X1184842Y4023D02*
Y9433D01*
G01X1184844Y4023D02*
X1184842D01*
G01X1218307Y22133D02*
Y17157D01*
G01X1218309Y22133D02*
X1218307D01*
G01Y97733D02*
Y92757D01*
G01X1164763Y79623D02*
Y87714D01*
G01X1164765Y79623D02*
X1164763D01*
G01X1161417Y59933D02*
Y54957D01*
G01X1161419Y59933D02*
X1161417D01*
G01X1174803Y97733D02*
Y92757D01*
G01X1184142Y85733D02*
Y87714D01*
G01X1184842Y85033D02*
X1184142Y85733D01*
G01X1184842Y79623D02*
Y85033D01*
G01X1184844Y79623D02*
X1184842D01*
G01X1178149Y87414D02*
X1177849Y87714D01*
G01X1178149Y79623D02*
Y87414D01*
G01X1178151Y79623D02*
X1178149D01*
G01X1211614Y59933D02*
Y54957D01*
G01X1211616Y59933D02*
X1211614D01*
G01X1168110D02*
Y54957D01*
G01X1168112Y59933D02*
X1168110D01*
G01X1218307D02*
Y54957D01*
G01X1218309Y59933D02*
X1218307D01*
G01X1201574Y79623D02*
Y87714D01*
G01X1201576Y79623D02*
X1201574D01*
G01X1161417Y97733D02*
Y92757D01*
G01X1201574Y41823D02*
Y49914D01*
G01X1201576Y41823D02*
X1201574D01*
G01X1181496Y59933D02*
Y54957D01*
G01X1181498Y59933D02*
X1181496D01*
G01X1214960Y49614D02*
X1214660Y49914D01*
G01X1214960Y41823D02*
Y49614D01*
G01X1214962Y41823D02*
X1214960D01*
G01X1204921Y97733D02*
Y92757D01*
G01X1211614Y97733D02*
Y92757D01*
G01X1171456Y79623D02*
Y87714D01*
G01X1171458Y79623D02*
X1171456D01*
G01X1181496Y97733D02*
Y92757D01*
G01X1164763Y41823D02*
Y49914D01*
G01X1164765Y41823D02*
X1164763D01*
G01X1168110Y97733D02*
Y92757D01*
G01X1208267Y41823D02*
Y49914D01*
G01X1208269Y41823D02*
X1208267D01*
G01X1178149Y49614D02*
X1177849Y49914D01*
G01X1178149Y41823D02*
Y49614D01*
G01X1178151Y41823D02*
X1178149D01*
G01X1208267Y79623D02*
Y87714D01*
G01X1208269Y79623D02*
X1208267D01*
G01X1184142Y47933D02*
Y49914D01*
G01X1184842Y47233D02*
X1184142Y47933D01*
G01X1184842Y41823D02*
Y47233D01*
G01X1184844Y41823D02*
X1184842D01*
G01X1204921Y59933D02*
Y54957D01*
G01X1204923Y59933D02*
X1204921D01*
G01X1174803D02*
Y54957D01*
G01X1174805Y59933D02*
X1174803D01*
G01X1214960Y87288D02*
X1214874Y87374D01*
G01X1214960Y79623D02*
Y87288D01*
G01X1214962Y79623D02*
X1214960D01*
G01X1198228Y59933D02*
Y54957D01*
G01X1198230Y59933D02*
X1198228D01*
G01Y97733D02*
Y92757D01*
G01X1171456Y41823D02*
Y49914D01*
G01X1171458Y41823D02*
X1171456D01*
G01X1218309Y97733D02*
X1218307D01*
G01X1174805D02*
X1174803D01*
G01X1161419D02*
X1161417D01*
G01X1204923D02*
X1204921D01*
G01X1211616D02*
X1211614D01*
G01X1181498D02*
X1181496D01*
G01X1168112D02*
X1168110D01*
G01X1198230D02*
X1198228D01*
G01X1208267Y505024D02*
Y513114D01*
G01X1208269Y505024D02*
X1208267D01*
G01X1198228Y523133D02*
Y518157D01*
G01X1198230Y523134D02*
X1198228Y523133D01*
G01X1174803D02*
Y518157D01*
G01X1174805Y523134D02*
X1174803Y523133D01*
G01X1204921D02*
Y518157D01*
G01X1204923Y523134D02*
X1204921Y523133D01*
G01X1164763Y505024D02*
Y513114D01*
G01X1164765Y505024D02*
X1164763D01*
G01X1181496Y523133D02*
Y518157D01*
G01X1181498Y523134D02*
X1181496Y523133D01*
G01X1211614D02*
Y518157D01*
G01X1211616Y523134D02*
X1211614Y523133D01*
G01X1161417D02*
Y518157D01*
G01X1161419Y523134D02*
X1161417Y523133D01*
G01X1178149Y512814D02*
X1177849Y513114D01*
G01X1178149Y505024D02*
Y512814D01*
G01X1178151Y505024D02*
X1178149D01*
G01X1168110Y523133D02*
Y518157D01*
G01X1168112Y523134D02*
X1168110Y523133D01*
G01X1184842Y505024D02*
X1184844D01*
G01X1184842Y510433D02*
Y505024D01*
G01X1184142Y511133D02*
X1184842Y510433D01*
G01X1184142Y513114D02*
Y511133D01*
G01X1218307Y523133D02*
Y518157D01*
G01X1218309Y523134D02*
X1218307Y523133D01*
G01X1214960Y512688D02*
X1214874Y512774D01*
G01X1214960Y505024D02*
Y512688D01*
G01X1214962Y505024D02*
X1214960D01*
G01X1171456D02*
Y513114D01*
G01X1171458Y505024D02*
X1171456D01*
G01X1201574D02*
Y513114D01*
G01X1201576Y505024D02*
X1201574D01*
G01X1174803Y560933D02*
Y555957D01*
G01X1174805Y560934D02*
X1174803Y560933D01*
G01X1184142Y548933D02*
Y550914D01*
G01X1184842Y548233D02*
X1184142Y548933D01*
G01X1184842Y542824D02*
Y548233D01*
G01X1184844Y542824D02*
X1184842D01*
G01X1161417Y560933D02*
Y555957D01*
G01X1161419Y560934D02*
X1161417Y560933D01*
G01X1184842Y580624D02*
X1184844D01*
G01X1184842Y586033D02*
Y580624D01*
G01X1184142Y586733D02*
X1184842Y586033D01*
G01X1184142Y588714D02*
Y586733D01*
G01X1211614Y560933D02*
Y555957D01*
G01X1211616Y560934D02*
X1211614Y560933D01*
G01X1201574Y542824D02*
Y550914D01*
G01X1201576Y542824D02*
X1201574D01*
G01X1181496Y560933D02*
Y555957D01*
G01X1181498Y560934D02*
X1181496Y560933D01*
G01X1208267Y580624D02*
Y588714D01*
G01X1208269Y580624D02*
X1208267D01*
G01X1171456Y542824D02*
Y550914D01*
G01X1171458Y542824D02*
X1171456D01*
G01X1208267D02*
Y550914D01*
G01X1208269Y542824D02*
X1208267D01*
G01X1214960Y588288D02*
X1214660Y588588D01*
G01X1214960Y580624D02*
Y588288D01*
G01X1214962Y580624D02*
X1214960D01*
G01X1218307Y560933D02*
Y555957D01*
G01X1218309Y560934D02*
X1218307Y560933D01*
G01X1168110D02*
Y555957D01*
G01X1168112Y560934D02*
X1168110Y560933D01*
G01X1164763Y580624D02*
Y588714D01*
G01X1164765Y580624D02*
X1164763D01*
G01X1201574D02*
Y588714D01*
G01X1201576Y580624D02*
X1201574D01*
G01X1164763Y542824D02*
Y550914D01*
G01X1164765Y542824D02*
X1164763D01*
G01X1214960Y550488D02*
X1214874Y550574D01*
G01X1214960Y542824D02*
Y550488D01*
G01X1214962Y542824D02*
X1214960D01*
G01X1171456Y580624D02*
Y588714D01*
G01X1171458Y580624D02*
X1171456D01*
G01X1178149Y550614D02*
X1177849Y550914D01*
G01X1178149Y542824D02*
Y550614D01*
G01X1178151Y542824D02*
X1178149D01*
G01X1204921Y560933D02*
Y555957D01*
G01X1204923Y560934D02*
X1204921Y560933D01*
G01X1178149Y580624D02*
Y588414D01*
G01X1178151Y580624D02*
X1178149D01*
G01X1198228Y560933D02*
Y555957D01*
G01X1198230Y560934D02*
X1198228Y560933D01*
G01Y598733D02*
Y593757D01*
G01X1198230Y598734D02*
X1198228Y598733D01*
G01X1168110D02*
Y593757D01*
G01X1168112Y598734D02*
X1168110Y598733D01*
G01X1218307D02*
Y593757D01*
G01X1218309Y598734D02*
X1218307Y598733D01*
G01X1181496D02*
Y593757D01*
G01X1181498Y598734D02*
X1181496Y598733D01*
G01X1204921D02*
Y593757D01*
G01X1204923Y598734D02*
X1204921Y598733D01*
G01X1214660Y588588D02*
Y588714D01*
G01X1174803Y598733D02*
Y593757D01*
G01X1174805Y598734D02*
X1174803Y598733D01*
G01X1178149Y588414D02*
X1177849Y588714D01*
G01X1211616Y593759D02*
X1211614Y593757D01*
G01X1211616Y598734D02*
Y593759D01*
G01X1161417Y598733D02*
Y593757D01*
G01X1161419Y598734D02*
X1161417Y598733D01*
G01X1220953Y10133D02*
Y12114D01*
G01X1221653Y9433D02*
X1220953Y10133D01*
G01X1221653Y4023D02*
Y9433D01*
G01X1221655Y4023D02*
X1221653D01*
G01X1245078D02*
Y12114D01*
G01X1245080Y4023D02*
X1245078D01*
G01X1238385D02*
Y12114D01*
G01X1238387Y4023D02*
X1238385D01*
G01X1241732Y22133D02*
Y17157D01*
G01X1241734Y22133D02*
X1241732D01*
G01X1235039D02*
Y17157D01*
G01X1235041Y22133D02*
X1235039D01*
G01X1241732Y59933D02*
Y54957D01*
G01X1241734Y59933D02*
X1241732D01*
G01X1238385Y41823D02*
Y49914D01*
G01X1238387Y41823D02*
X1238385D01*
G01X1241734Y92759D02*
X1241732Y92757D01*
G01X1241734Y97733D02*
Y92759D01*
G01X1238387Y87712D02*
X1238385Y87714D01*
G01X1238387Y79623D02*
Y87712D01*
G01X1245078Y41823D02*
Y49914D01*
G01X1245080Y41823D02*
X1245078D01*
G01X1220953Y85733D02*
Y87714D01*
G01X1221653Y85033D02*
X1220953Y85733D01*
G01X1221653Y79623D02*
Y85033D01*
G01X1221655Y79623D02*
X1221653D01*
G01X1235039Y97733D02*
Y92757D01*
G01Y59933D02*
Y54957D01*
G01X1235041Y59933D02*
X1235039D01*
G01X1220953Y47933D02*
Y49914D01*
G01X1221653Y47233D02*
X1220953Y47933D01*
G01X1221653Y41823D02*
Y47233D01*
G01X1221655Y41823D02*
X1221653D01*
G01X1245080Y87712D02*
X1245078Y87714D01*
G01X1245080Y79623D02*
Y87712D01*
G01X1235041Y97733D02*
X1235039D01*
G01X1245080Y513112D02*
X1245078Y513114D01*
G01X1245080Y505024D02*
Y513112D01*
G01X1238385Y505024D02*
Y513114D01*
G01X1238387Y505024D02*
X1238385D01*
G01X1221653D02*
X1221655D01*
G01X1221653Y510433D02*
Y505024D01*
G01X1220953Y511133D02*
X1221653Y510433D01*
G01X1220953Y513114D02*
Y511133D01*
G01X1235039Y523133D02*
Y518157D01*
G01X1235041Y523134D02*
X1235039Y523133D01*
G01X1241734Y518159D02*
X1241732Y518157D01*
G01X1241734Y523134D02*
Y518159D01*
G01X1220953Y548933D02*
Y550914D01*
G01X1221653Y548233D02*
X1220953Y548933D01*
G01X1221653Y542824D02*
Y548233D01*
G01X1221655Y542824D02*
X1221653D01*
G01X1220953Y586733D02*
Y588714D01*
G01X1221653Y586033D02*
X1220953Y586733D01*
G01X1221653Y580624D02*
Y586033D01*
G01X1221655Y580624D02*
X1221653D01*
G01X1245078Y542824D02*
Y550914D01*
G01X1245080Y542824D02*
X1245078D01*
G01X1241732Y560933D02*
Y555957D01*
G01X1241734Y560934D02*
X1241732Y560933D01*
G01X1238385Y542824D02*
X1238387D01*
G01X1238385Y550914D02*
Y542824D01*
G01X1238387Y580624D02*
Y588712D01*
G01X1235039Y560933D02*
Y555957D01*
G01X1235041Y560934D02*
X1235039Y560933D01*
G01X1245078Y580624D02*
Y588714D01*
G01X1245080Y580624D02*
X1245078D01*
G01X1235039Y598733D02*
Y593757D01*
G01X1235041Y598734D02*
X1235039Y598733D01*
G01X1238387Y588712D02*
X1238385Y588714D01*
G01X1241732Y598733D02*
Y593757D01*
G01X1241734Y598734D02*
X1241732Y598733D01*
G54D13*
G01X-19624Y137806D02*
Y158386D01*
G01X-18592Y136774D02*
X-19624Y137806D01*
G01X7755Y136774D02*
X-18592D01*
G01X-21073Y137289D02*
Y163476D01*
G01X-19269Y135485D02*
X-21073Y137289D01*
G01X-13003Y135485D02*
X-19269D01*
G01X-16728Y160047D02*
X4905D01*
G01X-19210Y162529D02*
X-16728Y160047D01*
G01X-19199Y158811D02*
X4311D01*
G01X-19624Y158386D02*
X-19199Y158811D01*
G01X-18106Y164260D02*
X-15768Y161922D01*
G01X-20289Y164260D02*
X-18106D01*
G01X-21073Y163476D02*
X-20289Y164260D01*
G01X-15768Y161922D02*
X-15102Y161256D01*
G01X-16940Y481740D02*
X-12690D01*
G01X-19802Y478878D02*
X-16940Y481740D01*
G01X-19802Y476738D02*
Y478878D01*
G01X-16804Y506300D02*
X-13400D01*
G01X-17302Y506798D02*
X-16804Y506300D01*
G01X-16601Y497400D02*
X-13400Y500601D01*
G01X-16700Y497400D02*
X-16601D01*
G01X-14046Y521444D02*
X-16186Y519304D01*
G01X-17357Y478477D02*
X-12927D01*
G01X-17392Y478512D02*
X-17357Y478477D01*
G01X-16841Y484228D02*
X-11678D01*
G01X-19783Y481286D02*
X-16841Y484228D01*
G01X44542Y18751D02*
Y16578D01*
G01X43960Y19333D02*
X44542Y18751D01*
G01X43960Y20572D02*
Y19333D01*
G01X41542Y18160D02*
Y16578D01*
G01X40530Y19172D02*
X41542Y18160D01*
G01X40530Y20220D02*
Y19172D01*
G01X11811Y132718D02*
X7755Y136774D01*
G01X11811Y132717D02*
Y132718D01*
G01X-10236D02*
X-13003Y135485D01*
G01X-10236Y132717D02*
Y132718D01*
G01X34300Y163500D02*
X34900Y164100D01*
G01X6115Y163500D02*
X34300D01*
G01X3878Y165737D02*
X6115Y163500D01*
G01X3878Y167051D02*
Y165737D01*
G01X3453Y167476D02*
X3878Y167051D01*
G01X2378Y167476D02*
X3453D01*
G01X1953Y167051D02*
X2378Y167476D01*
G01X1953Y165737D02*
Y167051D01*
G01X1528Y165312D02*
X1953Y165737D01*
G01X453Y165312D02*
X1528D01*
G01X28Y165737D02*
X453Y165312D01*
G01X28Y167051D02*
Y165737D01*
G01X-397Y167476D02*
X28Y167051D01*
G01X-1472Y167476D02*
X-397D01*
G01X-1897Y167051D02*
X-1472Y167476D01*
G01X-1897Y165737D02*
Y167051D01*
G01X-2322Y165312D02*
X-1897Y165737D01*
G01X-3397Y165312D02*
X-2322D01*
G01X-3822Y165737D02*
X-3397Y165312D01*
G01X-3822Y167051D02*
Y165737D01*
G01X-4247Y167476D02*
X-3822Y167051D01*
G01X-5322Y167476D02*
X-4247D01*
G01X-5747Y167051D02*
X-5322Y167476D01*
G01X-5747Y165737D02*
Y167051D01*
G01X-6172Y165312D02*
X-5747Y165737D01*
G01X-7247Y165312D02*
X-6172D01*
G01X-7672Y165737D02*
X-7247Y165312D01*
G01X-7672Y167051D02*
Y165737D01*
G01X-8097Y167476D02*
X-7672Y167051D01*
G01X-9172Y167476D02*
X-8097D01*
G01X-9597Y167051D02*
X-9172Y167476D01*
G01X-9597Y165737D02*
Y167051D01*
G01X-10022Y165312D02*
X-9597Y165737D01*
G01X-10714Y165312D02*
X-10022D01*
G01X-12861Y163165D02*
X-10714Y165312D01*
G01X41407Y158247D02*
X46160Y163000D01*
G01X33155Y158247D02*
X41407D01*
G01X31578Y159824D02*
X33155Y158247D01*
G01X5128Y159824D02*
X31578D01*
G01X4905Y160047D02*
X5128Y159824D01*
G01X44900Y159500D02*
X51500D01*
G01X42347Y156947D02*
X44900Y159500D01*
G01X32325Y156947D02*
X42347D01*
G01X30272Y159000D02*
X32325Y156947D01*
G01X4500Y159000D02*
X30272D01*
G01X4311Y158811D02*
X4500Y159000D01*
G01X43600Y169300D02*
X57700D01*
G01X38400Y164100D02*
X43600Y169300D01*
G01X46000Y166500D02*
X62400D01*
G01X40148Y160648D02*
X46000Y166500D01*
G01X6352Y160648D02*
X40148D01*
G01X4299Y162701D02*
X6352Y160648D01*
G01X-8634Y162701D02*
X4299D01*
G01X-10079Y161256D02*
X-8634Y162701D01*
G01X-15102Y161256D02*
X-10079D01*
G01X41508Y402597D02*
X46100Y407189D01*
G01X27344Y385100D02*
X23228Y380984D01*
G01X29400Y385100D02*
X27344D01*
G01X31000Y386700D02*
X29400Y385100D01*
G01X31000Y392089D02*
Y386700D01*
G01X41508Y402597D02*
X31000Y392089D01*
G01X2450Y460000D02*
Y469550D01*
G01X-644Y463618D02*
X-1458Y462804D01*
G01X-644Y474034D02*
Y463618D01*
G01X-1458Y462472D02*
Y462804D01*
G01X-4850Y459080D02*
X-1458Y462472D01*
G01X-8265Y459080D02*
X-4850D01*
G01X-8690Y459505D02*
X-8265Y459080D01*
G01X-8690Y460640D02*
Y459505D01*
G01X-13690Y458325D02*
Y460640D01*
G01X-13265Y457900D02*
X-13690Y458325D01*
G01X-3010Y457900D02*
X-13265D01*
G01X523Y461433D02*
X-3010Y457900D01*
G01X523Y473753D02*
Y461433D01*
G01X46100Y407189D02*
Y413520D01*
G01X-4598Y473840D02*
X-5690D01*
G01X-2928Y475510D02*
X-4598Y473840D01*
G01X-2928Y477072D02*
Y475510D01*
G01X-1000Y479000D02*
X-2928Y477072D01*
G01X-5690Y477400D02*
Y473840D01*
G01X-6530Y478240D02*
X-5690Y477400D01*
G01X-9190Y478240D02*
X-6530D01*
G01X2450Y469550D02*
X2350Y469650D01*
G01X-500Y514910D02*
Y517500D01*
G01X-1706Y513704D02*
X-500Y514910D01*
G01X-2083Y513704D02*
X-1706D01*
G01X-3500Y515121D02*
X-2083Y513704D01*
G01X-3500Y517500D02*
Y515121D01*
G01X-13400Y500601D02*
Y502800D01*
G01X36458Y491058D02*
Y487879D01*
G01X37100Y491700D02*
X36458Y491058D01*
G01X43310Y491700D02*
X37100D01*
G01X43942Y492332D02*
X43310Y491700D01*
G01X43942Y495721D02*
Y492332D01*
G01Y495721D02*
X48021D01*
G01X31924Y487879D02*
X36458D01*
G01X28246Y491557D02*
X31924Y487879D01*
G01X2160Y476838D02*
X-644Y474034D01*
G01X2160Y479000D02*
Y476838D01*
G01X5100Y478330D02*
X523Y473753D01*
G01X-12454Y521444D02*
X-14046D01*
G01X-12210Y521200D02*
X-12454Y521444D01*
G01X-12010Y521000D02*
X-12210Y521200D01*
G01X-3500Y521000D02*
X-12010D01*
G01X-12927Y478477D02*
X-12690Y478240D01*
G01Y475040D02*
X-11490Y473840D01*
G01X-12690Y478240D02*
Y475040D01*
G01X-11490Y473840D02*
X-8690D01*
G01X-6676Y499695D02*
X-5602Y498621D01*
G01X-6676Y501800D02*
Y499695D01*
G01X-11678Y484228D02*
X-9190Y481740D01*
G01X30850Y482032D02*
X28700D01*
G01X31477Y482659D02*
X30850Y482032D01*
G01X31477Y482788D02*
Y482659D01*
G01X-10252Y515731D02*
X-6712D01*
G01X-10669Y516148D02*
X-10252Y515731D01*
G01X43942Y487879D02*
X47521D01*
G01X58316Y-10091D02*
Y-11754D01*
G01X58919Y-9488D02*
X58316Y-10091D01*
G01X58919Y-4188D02*
Y-9488D01*
G01X55887Y-1156D02*
X58919Y-4188D01*
G01X55887Y6708D02*
Y-1156D01*
G01X53786Y8809D02*
X55887Y6708D01*
G01X51819Y8809D02*
X53786D01*
G01X51090Y8080D02*
X51819Y8809D01*
G01X58308Y-12212D02*
Y-14773D01*
G01X58316Y-12204D02*
X58308Y-12212D01*
G01X58316Y-11754D02*
Y-12204D01*
G01X87700Y-9509D02*
Y92900D01*
G01X88777Y-10586D02*
X87700Y-9509D01*
G01X54816Y-8560D02*
X54307Y-8051D01*
G01X54816Y-11754D02*
Y-8560D01*
G01X86762Y-9810D02*
Y82356D01*
G01X86697Y-9875D02*
X86762Y-9810D01*
G01X86697Y-11197D02*
Y-9875D01*
G01X93500Y-18000D02*
X86697Y-11197D01*
G01X87700Y92900D02*
X86600Y94000D01*
G01X79781Y89337D02*
X76106D01*
G01X86762Y82356D02*
X79781Y89337D01*
G01X99980Y142344D02*
Y145531D01*
G01X95777Y138141D02*
X99980Y142344D01*
G01X95777Y129396D02*
Y138141D01*
G01X92000Y109436D02*
X87564Y105000D01*
G01X98636Y109436D02*
X92000D01*
G01X102400Y113200D02*
X98636Y109436D01*
G01X102400Y118500D02*
Y113200D01*
G01Y118500D02*
X105700D01*
G01X86702Y152374D02*
X87200D01*
G01X81181Y157895D02*
X86702Y152374D01*
G01X62744Y154848D02*
X60723Y156869D01*
G01X80663Y154848D02*
X62744D01*
G01X89980Y145531D02*
X80663Y154848D01*
G01X70980Y99900D02*
Y97166D01*
G01X69725Y101155D02*
X70980Y99900D01*
G01X69725Y106833D02*
Y101155D01*
G01X70555Y107663D02*
X69725Y106833D01*
G01X74763Y107663D02*
X70555D01*
G01X79600Y112500D02*
X74763Y107663D01*
G01X79600Y116000D02*
Y112500D01*
G01X83400Y119800D02*
X79600Y116000D01*
G01X83400Y130030D02*
Y119800D01*
G01X95700Y142330D02*
X83400Y130030D01*
G01X95700Y149800D02*
Y142330D01*
G01X89283Y156217D02*
X95700Y149800D01*
G01X97988Y123950D02*
X97214Y124724D01*
G01X101900Y123950D02*
X97988D01*
G01X104550Y126600D02*
X101900Y123950D01*
G01X104550Y127500D02*
Y126600D01*
G01X105300Y128250D02*
X104550Y127500D01*
G01X105300Y148700D02*
Y128250D01*
G01X100250Y153750D02*
X105300Y148700D01*
G01X94750Y153750D02*
X100250D01*
G01X91306Y157194D02*
X94750Y153750D01*
G01X97214Y123644D02*
Y124724D01*
G01X94000Y120430D02*
X97214Y123644D01*
G01X94000Y118500D02*
Y120430D01*
G01X87013Y116200D02*
X85350D01*
G01X89313Y118500D02*
X87013Y116200D01*
G01X94000Y118500D02*
X89313D01*
G01X79670Y135828D02*
Y132300D01*
G01X81600Y130370D02*
X79670Y132300D01*
G01X81600Y124700D02*
Y130370D01*
G01X46160Y163000D02*
X51500D01*
G01X79800Y169300D02*
X57700D01*
G01X86952Y176452D02*
X79800Y169300D01*
G01X86952Y181721D02*
Y176452D01*
G01X76899Y157895D02*
X81181D01*
G01X58549Y163000D02*
X55000D01*
G01X63654Y157895D02*
X58549Y163000D01*
G01X76899Y157895D02*
X63654D01*
G01X58092Y159500D02*
X55000D01*
G01X60723Y156869D02*
X58092Y159500D01*
G01X62400Y166500D02*
X66000D01*
G01X89283Y165471D02*
Y156217D01*
G01X111958Y188146D02*
X89283Y165471D01*
G01X104700Y211006D02*
X111958Y203748D01*
G01X104700Y285500D02*
Y211006D01*
G01X69500Y166500D02*
X76300D01*
G01X89685Y182338D02*
X87151Y184872D01*
G01X89685Y175875D02*
Y182338D01*
G01X80310Y166500D02*
X89685Y175875D01*
G01X76300Y166500D02*
X80310D01*
G01X69000Y341800D02*
Y338800D01*
G01X84600Y306000D02*
X84300Y305700D01*
G01X89000Y306000D02*
X84600D01*
G01X56300Y340800D02*
Y338500D01*
G01X57000Y341500D02*
X56300Y340800D01*
G01X102400Y309600D02*
X103500Y308500D01*
G01X102400Y313000D02*
Y309600D01*
G01X105100Y308500D02*
X106600Y307000D01*
G01X103500Y308500D02*
X105100D01*
G01X48700Y298100D02*
X46900D01*
G01X53250Y302650D02*
X48700Y298100D01*
G01X53250Y302800D02*
Y302650D01*
G01X80900Y307300D02*
X84300Y310700D01*
G01X80100Y307300D02*
X80900D01*
G01X88532Y332500D02*
X86750D01*
G01X90410Y330622D02*
X88532Y332500D01*
G01X94395Y330622D02*
X90410D01*
G01X94900Y331127D02*
X94395Y330622D01*
G01X94900Y332800D02*
Y331127D01*
G01X88400Y338200D02*
X87400Y337200D01*
G01X92000Y338200D02*
X88400D01*
G01X90570Y336770D02*
X92000Y338200D01*
G01X90570Y333771D02*
Y336770D01*
G01X91541Y332800D02*
X90570Y333771D01*
G01X94900Y332800D02*
X91541D01*
G01X64000Y319000D02*
Y319500D01*
G01X65600Y317400D02*
X64000Y319000D01*
G01X70900Y317400D02*
X65600D01*
G01X64000Y321530D02*
Y319500D01*
G01X63300Y322230D02*
X64000Y321530D01*
G01X63300Y325500D02*
Y322230D01*
G01X76300Y319500D02*
X67500D01*
G01X77600Y320800D02*
X76300Y319500D01*
G01X74631Y336150D02*
X68418D01*
G01X81544Y343063D02*
X74631Y336150D01*
G01X85500Y341000D02*
X83437Y343063D01*
G01X61100Y339200D02*
Y343150D01*
G01X61200Y339100D02*
X61100Y339200D01*
G01X61200Y337900D02*
Y339100D01*
G01X62250Y336850D02*
X61200Y337900D01*
G01X65550Y336850D02*
X62250D01*
G01X66250Y336150D02*
X65550Y336850D01*
G01X68418Y336150D02*
X66250D01*
G01X68418Y332500D02*
Y336150D01*
G01X87810Y341000D02*
X90280Y343470D01*
G01X85500Y341000D02*
X87810D01*
G01X72000Y341800D02*
Y338800D01*
G01X105001Y332800D02*
X103900D01*
G01X105800Y333599D02*
X105001Y332800D01*
G01X105800Y338200D02*
Y333599D01*
G01Y338200D02*
Y342100D01*
G01X102890Y332800D02*
X100550Y335140D01*
G01X103900Y332800D02*
X102890D01*
G01X109040Y289840D02*
X104700Y285500D01*
G01X102400Y316400D02*
Y317500D01*
G01X110470Y308330D02*
X102400Y316400D01*
G01X104710Y330190D02*
X107300Y327600D01*
G01X103200Y330190D02*
X104710D01*
G01X69300Y307200D02*
Y306000D01*
G01X69125Y307375D02*
X69300Y307200D01*
G01X69125Y310625D02*
Y307375D01*
G01X74800Y340200D02*
Y338850D01*
G01X76600Y342000D02*
X74800Y340200D01*
G01X82800Y382425D02*
X85609Y385234D01*
G01X82800Y377500D02*
Y382425D01*
G01X84900Y375400D02*
X82800Y377500D01*
G01X84900Y367900D02*
Y375400D01*
G01X80000Y363000D02*
X84900Y367900D01*
G01X80000Y357800D02*
Y363000D01*
G01X80250Y357550D02*
X80000Y357800D01*
G01X80250Y354750D02*
Y357550D01*
G01X54500Y351200D02*
Y351000D01*
G01X53000Y352700D02*
X54500Y351200D01*
G01X50900Y352700D02*
X53000D01*
G01X49100Y354500D02*
X50900Y352700D01*
G01X83437Y343063D02*
X81544D01*
G01X90280Y343470D02*
X94010D01*
G01X104430D02*
X103010D01*
G01X105800Y342100D02*
X104430Y343470D01*
G01X59500Y348300D02*
X60900D01*
G01X57000Y345800D02*
X59500Y348300D01*
G01X57000Y345000D02*
Y345800D01*
G01X69250Y367186D02*
Y364500D01*
G01X67130Y369306D02*
X69250Y367186D01*
G01X67130Y369550D02*
Y369306D01*
G01X73500Y363250D02*
X76500D01*
G01X72250Y364500D02*
X73500Y363250D01*
G01X69250Y364500D02*
X72250D01*
G01X74933Y525440D02*
X73567Y526806D01*
G01X80524Y525440D02*
X74933D01*
G01X85554Y520410D02*
X80524Y525440D01*
G01X85554Y509334D02*
Y520410D01*
G01X89435Y505453D02*
X85554Y509334D01*
G01X99888Y505453D02*
X89435D01*
G01X105464Y499877D02*
X99888Y505453D01*
G01X111961Y499877D02*
X105464D01*
G01X48550Y496250D02*
X51200D01*
G01X48021Y495721D02*
X48550Y496250D01*
G01X86761Y520910D02*
X81082Y526589D01*
G01X86761Y509834D02*
Y520910D01*
G01X89935Y506660D02*
X86761Y509834D01*
G01X100916Y506660D02*
X89935D01*
G01X101006Y506570D02*
X100916Y506660D01*
G01X101007Y506570D02*
X101006D01*
G01X106037Y501540D02*
X101007Y506570D01*
G01X112650Y501540D02*
X106037D01*
G01X82907Y528307D02*
X88855Y522359D01*
G01X47521Y487879D02*
X47800Y487600D01*
G01X91650Y522277D02*
Y522000D01*
G01X82566Y531361D02*
X91650Y522277D01*
G01X74395Y531361D02*
X75830D01*
G01X73567Y530533D02*
X74395Y531361D01*
G01X73567Y526806D02*
Y530533D01*
G01X75846Y527322D02*
Y528307D01*
G01X76579Y526589D02*
X75846Y527322D01*
G01X81082Y526589D02*
X76579D01*
G01X79346Y528307D02*
X82907D01*
G01X79330Y531361D02*
X82566D01*
G01X142098Y-53848D02*
X140500Y-52250D01*
G01X441680Y-53848D02*
X142098D01*
G01X148901Y-50423D02*
X441680D01*
G01X111958Y203748D02*
Y188146D01*
G01X109040Y303560D02*
Y289840D01*
G01X110470Y304990D02*
X109040Y303560D01*
G01X110470Y308170D02*
Y304990D01*
G01Y308170D02*
Y308330D01*
G01X149109Y424439D02*
X151341D01*
G01X148409Y423739D02*
X149109Y424439D01*
G01X148409Y422239D02*
Y423739D01*
G01X165489Y421680D02*
X201820D01*
G01X164830Y422339D02*
X165489Y421680D01*
G01X164670Y422499D02*
X164830Y422339D01*
G01X157858Y422499D02*
X164670D01*
G01X156313Y420954D02*
X157858Y422499D01*
G01X154861Y420954D02*
X156313D01*
G01X151254Y417554D02*
X148300Y414600D01*
G01X151254Y417659D02*
Y417554D01*
G01X148666Y420067D02*
Y417397D01*
G01X149553Y420954D02*
X148666Y420067D01*
G01X151361Y420954D02*
X149553D01*
G01X158061Y419810D02*
X200689D01*
G01X155910Y417659D02*
X158061Y419810D01*
G01X154754Y417659D02*
X155910D01*
G01X117821Y414201D02*
X115750Y412130D01*
G01X119016Y414201D02*
X117821D01*
G01X154841Y424439D02*
X170317D01*
G01X113624Y500566D02*
X112650Y501540D01*
G01X113624Y498422D02*
Y500566D01*
G01X112427Y497225D02*
X113624Y498422D01*
G01X201820Y421680D02*
X248600Y374900D01*
G01X200689Y419810D02*
X249499Y371000D01*
G01X226039Y400962D02*
X248301Y378700D01*
G01X203433Y423568D02*
X226039Y400962D01*
G01X171188Y423568D02*
X203433D01*
G01X170317Y424439D02*
X171188Y423568D01*
G01X259546Y358800D02*
X256300D01*
G01X261323Y357023D02*
X259546Y358800D01*
G01X271977Y357023D02*
X261323D01*
G01X273303Y355697D02*
X271977Y357023D01*
G01X275462Y355697D02*
X273303D01*
G01X277169Y357395D02*
X275462Y355697D01*
G01X278899Y357395D02*
X277169D01*
G01X280597Y355697D02*
X278899Y357395D01*
G01X282302Y355697D02*
X280597D01*
G01X284071Y357466D02*
X282302Y355697D01*
G01X285447Y357466D02*
X284071D01*
G01X287216Y355697D02*
X285447Y357466D01*
G01X288807Y355697D02*
X287216D01*
G01X290082Y356972D02*
X288807Y355697D01*
G01X292195Y356972D02*
X290082D01*
G01X293470Y355697D02*
X292195Y356972D01*
G01X256300Y358800D02*
X252700D01*
G01X262400Y364400D02*
X267400D01*
G01X260000Y366800D02*
X262400Y364400D01*
G01X251700Y366800D02*
X260000D01*
G01X292956Y364772D02*
X294231Y363497D01*
G01X290851Y364772D02*
X292956D01*
G01X289576Y363497D02*
X290851Y364772D01*
G01X287471Y363497D02*
X289576D01*
G01X286196Y364772D02*
X287471Y363497D01*
G01X284091Y364772D02*
X286196D01*
G01X282816Y363497D02*
X284091Y364772D01*
G01X280711Y363497D02*
X282816D01*
G01X279436Y364772D02*
X280711Y363497D01*
G01X277331Y364772D02*
X279436D01*
G01X276056Y363497D02*
X277331Y364772D01*
G01X270203Y363497D02*
X276056D01*
G01X269300Y364400D02*
X270203Y363497D01*
G01X267400Y364400D02*
X269300D01*
G01X262100Y349800D02*
X256300D01*
G01X262301Y349599D02*
X262100Y349800D01*
G01X265232Y349599D02*
X262301D01*
G01X266929Y347902D02*
X265232Y349599D01*
G01X268698Y347902D02*
X266929D01*
G01X270533Y349737D02*
X268698Y347902D01*
G01X271909Y349737D02*
X270533D01*
G01X273744Y347902D02*
X271909Y349737D01*
G01X276061Y347902D02*
X273744D01*
G01X277326Y349167D02*
X276061Y347902D01*
G01X278672Y349167D02*
X277326D01*
G01X279047Y348800D02*
X278672Y349167D01*
G01X279945Y347902D02*
X279047Y348800D01*
G01X282052Y347902D02*
X279945D01*
G01X283731Y349581D02*
X282052Y347902D01*
G01X285787Y349581D02*
X283731D01*
G01X287466Y347902D02*
X285787Y349581D01*
G01X288812Y347902D02*
X287466D01*
G01X290077Y349167D02*
X288812Y347902D01*
G01X292192Y349167D02*
X290077D01*
G01X292567Y348800D02*
X292192Y349167D01*
G01X293465Y347902D02*
X292567Y348800D01*
G01X256300Y349800D02*
X252700D01*
G01X292192Y372566D02*
X293456Y371302D01*
G01X290846Y372566D02*
X292192D01*
G01X289582Y371302D02*
X290846Y372566D01*
G01X286696Y371302D02*
X289582D01*
G01X285432Y372566D02*
X286696Y371302D01*
G01X284086Y372566D02*
X285432D01*
G01X282822Y371302D02*
X284086Y372566D01*
G01X279936Y371302D02*
X282822D01*
G01X278461Y372777D02*
X279936Y371302D01*
G01X277208Y372777D02*
X278461D01*
G01X275085Y374900D02*
X277208Y372777D01*
G01X248600Y374900D02*
X275085D01*
G01X260600Y362800D02*
X262200Y361200D01*
G01X252700Y362800D02*
X260600D01*
G01X292187Y360872D02*
X293929Y359130D01*
G01X290851Y360872D02*
X292187D01*
G01X289549Y359597D02*
X290851Y360872D01*
G01X286702Y359597D02*
X289549D01*
G01X285427Y360872D02*
X286702Y359597D01*
G01X284091Y360872D02*
X285427D01*
G01X282183Y359005D02*
X284091Y360872D01*
G01X280534Y359005D02*
X282183D01*
G01X278667Y360872D02*
X280534Y359005D01*
G01X277331Y360872D02*
X278667D01*
G01X276536Y360093D02*
X277331Y360872D01*
G01X276040Y359597D02*
X276536Y360093D01*
G01X271203Y359597D02*
X276040D01*
G01X270406Y358800D02*
X271203Y359597D01*
G01X264600Y358800D02*
X270406D01*
G01X262200Y361200D02*
X264600Y358800D01*
G01X292957Y368672D02*
X294231Y367398D01*
G01X290613Y368672D02*
X292957D01*
G01X288916Y366975D02*
X290613Y368672D01*
G01X287308Y366975D02*
X288916D01*
G01X285611Y368672D02*
X287308Y366975D01*
G01X284083Y368672D02*
X285611D01*
G01X282297Y366886D02*
X284083Y368672D01*
G01X280659Y366886D02*
X282297D01*
G01X278198Y369347D02*
X280659Y366886D01*
G01X276859Y369347D02*
X278198D01*
G01X275206Y371000D02*
X276859Y369347D01*
G01X260000Y371000D02*
X275206D01*
G01X249499D02*
X260000D01*
G01X264868Y353123D02*
X260900D01*
G01X266194Y351797D02*
X264868Y353123D01*
G01X269275Y351797D02*
X266194D01*
G01X269578Y352100D02*
X269275Y351797D01*
G01X270571Y353072D02*
X269578Y352100D01*
G01X272676Y353072D02*
X270571D01*
G01X273951Y351797D02*
X272676Y353072D01*
G01X276042Y351797D02*
X273951D01*
G01X276645Y352400D02*
X276042Y351797D01*
G01X277331Y353072D02*
X276645Y352400D01*
G01X279436Y353072D02*
X277331D01*
G01X280711Y351797D02*
X279436Y353072D01*
G01X282804Y351797D02*
X280711D01*
G01X283507Y352500D02*
X282804Y351797D01*
G01X284091Y353072D02*
X283507Y352500D01*
G01X285427Y353072D02*
X284091D01*
G01X286702Y351797D02*
X285427Y353072D01*
G01X289549Y351797D02*
X286702D01*
G01X290851Y353072D02*
X289549Y351797D01*
G01X292956Y353072D02*
X290851D01*
G01X294231Y351797D02*
X292956Y353072D01*
G01X256000Y354300D02*
X252700D01*
G01X257177Y353123D02*
X256000Y354300D01*
G01X260900Y353123D02*
X257177D01*
G01X292554Y376843D02*
X294195Y375202D01*
G01X290453Y376843D02*
X292554D01*
G01X288812Y375202D02*
X290453Y376843D01*
G01X287211Y375202D02*
X288812D01*
G01X285447Y376966D02*
X287211Y375202D01*
G01X284071Y376966D02*
X285447D01*
G01X282307Y375202D02*
X284071Y376966D01*
G01X280713Y375202D02*
X282307D01*
G01X278767Y377148D02*
X280713Y375202D01*
G01X277331Y377148D02*
X278767D01*
G01X275779Y378700D02*
X277331Y377148D01*
G01X248301Y378700D02*
X275779D01*
G01X317714Y4023D02*
Y9114D01*
G01X307675Y22133D02*
Y17057D01*
G01X317714Y79623D02*
Y84714D01*
G01X307675Y97733D02*
Y92657D01*
G01Y59933D02*
Y54857D01*
G01X317714Y41823D02*
Y46914D01*
G01X295625Y355697D02*
X293470D01*
G01X297252Y357324D02*
X295625Y355697D01*
G01X299215Y357324D02*
X297252D01*
G01X300914Y355631D02*
X299215Y357324D01*
G01X302261Y355631D02*
X300914D01*
G01X303967Y357337D02*
X302261Y355631D01*
G01X305978Y357337D02*
X303967D01*
G01X308294Y355021D02*
X305978Y357337D01*
G01X309086Y355021D02*
X308294D01*
G01X310030Y354077D02*
X309086Y355021D01*
G01X310030Y353228D02*
Y354077D01*
G01X311798Y351460D02*
X310030Y353228D01*
G01X313566Y355021D02*
X315178Y353409D01*
G01X313566Y359772D02*
Y355021D01*
G01X312466Y360872D02*
X313566Y359772D01*
G01X311124Y360872D02*
X312466D01*
G01X308499Y363497D02*
X311124Y360872D01*
G01X306982Y363497D02*
X308499D01*
G01X305707Y364772D02*
X306982Y363497D01*
G01X304371Y364772D02*
X305707D01*
G01X303096Y363497D02*
X304371Y364772D01*
G01X300222Y363497D02*
X303096D01*
G01X298947Y364772D02*
X300222Y363497D01*
G01X297611Y364772D02*
X298947D01*
G01X296336Y363497D02*
X297611Y364772D01*
G01X294231Y363497D02*
X296336D01*
G01X295572Y347902D02*
X293465D01*
G01X297331Y349661D02*
X295572Y347902D01*
G01X299227Y349661D02*
X297331D01*
G01X300986Y347902D02*
X299227Y349661D01*
G01X302332Y347902D02*
X300986D01*
G01X303597Y349167D02*
X302332Y347902D01*
G01X305712Y349167D02*
X303597D01*
G01X307319Y347560D02*
X305712Y349167D01*
G01X311798Y347560D02*
X307319D01*
G01X353389Y361153D02*
X355052Y362816D01*
G01X351457Y361153D02*
X353389D01*
G01X349794Y362816D02*
X351457Y361153D01*
G01X348236Y362816D02*
X349794D01*
G01X346519Y361099D02*
X348236Y362816D01*
G01X344686Y361099D02*
X346519D01*
G01X342969Y362816D02*
X344686Y361099D01*
G01X341316Y362816D02*
X342969D01*
G01X339698Y361198D02*
X341316Y362816D01*
G01X337749Y361198D02*
X339698D01*
G01X336131Y362816D02*
X337749Y361198D01*
G01X334014Y362816D02*
X336131D01*
G01X332751Y361553D02*
X334014Y362816D01*
G01X331326Y361553D02*
X332751D01*
G01X329659Y363220D02*
X331326Y361553D01*
G01X327750Y363220D02*
X329659D01*
G01X326083Y361553D02*
X327750Y363220D01*
G01X323874Y361553D02*
X326083D01*
G01X322606Y362821D02*
X323874Y361553D01*
G01X321862Y362821D02*
X322606D01*
G01X319541Y365142D02*
X321862Y362821D01*
G01X317425Y365142D02*
X319541D01*
G01X315846Y366721D02*
X317425Y365142D01*
G01X314607Y366721D02*
X315846D01*
G01X311981Y369347D02*
X314607Y366721D01*
G01X311130Y369347D02*
X311981D01*
G01X309180Y371297D02*
X311130Y369347D01*
G01X306981Y371297D02*
X309180D01*
G01X305712Y372566D02*
X306981Y371297D01*
G01X304366Y372566D02*
X305712D01*
G01X303102Y371302D02*
X304366Y372566D01*
G01X300216Y371302D02*
X303102D01*
G01X298952Y372566D02*
X300216Y371302D01*
G01X297606Y372566D02*
X298952D01*
G01X296342Y371302D02*
X297606Y372566D01*
G01X293456Y371302D02*
X296342D01*
G01X311798Y356209D02*
Y355360D01*
G01X309086Y358921D02*
X311798Y356209D01*
G01X307658Y358921D02*
X309086D01*
G01X305707Y360872D02*
X307658Y358921D01*
G01X304371Y360872D02*
X305707D01*
G01X302646Y359147D02*
X304371Y360872D01*
G01X300672Y359147D02*
X302646D01*
G01X298947Y360872D02*
X300672Y359147D01*
G01X297611Y360872D02*
X298947D01*
G01X295869Y359130D02*
X297611Y360872D01*
G01X293929Y359130D02*
X295869D01*
G01X353178Y357648D02*
X354808Y359278D01*
G01X351689Y357648D02*
X353178D01*
G01X350048Y359289D02*
X351689Y357648D01*
G01X348155Y359289D02*
X350048D01*
G01X346514Y357648D02*
X348155Y359289D01*
G01X344930Y357648D02*
X346514D01*
G01X343252Y359326D02*
X344930Y357648D01*
G01X341459Y359326D02*
X343252D01*
G01X339781Y357648D02*
X341459Y359326D01*
G01X338170Y357648D02*
X339781D01*
G01X336456Y359362D02*
X338170Y357648D01*
G01X334699Y359362D02*
X336456D01*
G01X332985Y357648D02*
X334699Y359362D01*
G01X331410Y357648D02*
X332985D01*
G01X329956Y359102D02*
X331410Y357648D01*
G01X327599Y359102D02*
X329956D01*
G01X326145Y357648D02*
X327599Y359102D01*
G01X324650Y357648D02*
X326145D01*
G01X322822Y359476D02*
X324650Y357648D01*
G01X320824Y359476D02*
X322822D01*
G01X319300Y361000D02*
X320824Y359476D01*
G01X317667Y361000D02*
X319300D01*
G01X315170Y363497D02*
X317667Y361000D01*
G01X314510Y363497D02*
X315170D01*
G01X312559Y365448D02*
X314510Y363497D01*
G01X311130Y365448D02*
X312559D01*
G01X309857Y366721D02*
X311130Y365448D01*
G01X308300Y366721D02*
X309857D01*
G01X306349Y368672D02*
X308300Y366721D01*
G01X304371Y368672D02*
X306349D01*
G01X303097Y367398D02*
X304371Y368672D01*
G01X300991Y367398D02*
X303097D01*
G01X299330Y369059D02*
X300991Y367398D01*
G01X297278Y369059D02*
X299330D01*
G01X295617Y367398D02*
X297278Y369059D01*
G01X294231Y367398D02*
X295617D01*
G01X296320Y351797D02*
X294231D01*
G01X296823Y352300D02*
X296320Y351797D01*
G01X297611Y353072D02*
X296823Y352300D01*
G01X299716Y353072D02*
X297611D01*
G01X300991Y351797D02*
X299716Y353072D01*
G01X303096Y351797D02*
X300991D01*
G01X304371Y353072D02*
X303096Y351797D01*
G01X306428Y353072D02*
X304371D01*
G01X308160Y351340D02*
X306428Y353072D01*
G01X309091Y351340D02*
X308160D01*
G01X310922Y349509D02*
X309091Y351340D01*
G01X315178Y349509D02*
X310922D01*
G01X315563Y345668D02*
X318495Y348600D01*
G01X315563Y345009D02*
Y345668D01*
G01X353362Y353531D02*
X355056Y355225D01*
G01X351525Y353531D02*
X353362D01*
G01X350010Y355046D02*
X351525Y353531D01*
G01X347895Y355046D02*
X350010D01*
G01X346535Y353686D02*
X347895Y355046D01*
G01X344504Y353686D02*
X346535D01*
G01X343023Y355167D02*
X344504Y353686D01*
G01X341369Y355167D02*
X343023D01*
G01X339753Y353551D02*
X341369Y355167D01*
G01X337949Y353551D02*
X339753D01*
G01X336313Y355187D02*
X337949Y353551D01*
G01X334887Y355187D02*
X336313D01*
G01X333302Y353602D02*
X334887Y355187D01*
G01X331098Y353602D02*
X333302D01*
G01X329482Y355218D02*
X331098Y353602D01*
G01X327718Y355218D02*
X329482D01*
G01X326119Y353619D02*
X327718Y355218D01*
G01X324591Y353619D02*
X326119D01*
G01X322422Y351450D02*
X324591Y353619D01*
G01X321345Y351450D02*
X322422D01*
G01X318495Y348600D02*
X321345Y351450D01*
G01X318107Y341509D02*
X315563D01*
G01X320000Y343402D02*
X318107Y341509D01*
G01X320000Y346248D02*
Y343402D01*
G01X321252Y347500D02*
X320000Y346248D01*
G01X322644Y347500D02*
X321252D01*
G01X324544Y349400D02*
X322644Y347500D01*
G01X326108Y349400D02*
X324544D01*
G01X327907Y351199D02*
X326108Y349400D01*
G01X329301Y351199D02*
X327907D01*
G01X331079Y349421D02*
X329301Y351199D01*
G01X332921Y349421D02*
X331079D01*
G01X334649Y351149D02*
X332921Y349421D01*
G01X336703Y351149D02*
X334649D01*
G01X338097Y349755D02*
X336703Y351149D01*
G01X340055Y349755D02*
X338097D01*
G01X341529Y351229D02*
X340055Y349755D01*
G01X342871Y351229D02*
X341529D01*
G01X344671Y349429D02*
X342871Y351229D01*
G01X346473Y349429D02*
X344671D01*
G01X348233Y351189D02*
X346473Y349429D01*
G01X349811Y351189D02*
X348233D01*
G01X351518Y349482D02*
X349811Y351189D01*
G01X353182Y349482D02*
X351518D01*
G01X354929Y351229D02*
X353182Y349482D01*
G01X353240Y365170D02*
X355070Y367000D01*
G01X351490Y365170D02*
X353240D01*
G01X349640Y367020D02*
X351490Y365170D01*
G01X348280Y367020D02*
X349640D01*
G01X346510Y365250D02*
X348280Y367020D01*
G01X344570Y365250D02*
X346510D01*
G01X343020Y366800D02*
X344570Y365250D01*
G01X341120Y366800D02*
X343020D01*
G01X339570Y365250D02*
X341120Y366800D01*
G01X338069Y365250D02*
X339570D01*
G01X336271Y367048D02*
X338069Y365250D01*
G01X334838Y367048D02*
X336271D01*
G01X333140Y365350D02*
X334838Y367048D01*
G01X331209Y365350D02*
X333140D01*
G01X329511Y367048D02*
X331209Y365350D01*
G01X327848Y367048D02*
X329511D01*
G01X326100Y365300D02*
X327848Y367048D01*
G01X324450Y365300D02*
X326100D01*
G01X322760Y366990D02*
X324450Y365300D01*
G01X321100Y366990D02*
X322760D01*
G01X318738Y369352D02*
X321100Y366990D01*
G01X317597Y369352D02*
X318738D01*
G01X317140Y369809D02*
X317597Y369352D01*
G01X317140Y369823D02*
Y369809D01*
G01X315991Y370972D02*
X317140Y369823D01*
G01X315977Y370972D02*
X315991D01*
G01X315652Y371297D02*
X315977Y370972D01*
G01X314510Y371297D02*
X315652D01*
G01X312559Y373248D02*
X314510Y371297D01*
G01X311130Y373248D02*
X312559D01*
G01X309181Y375197D02*
X311130Y373248D01*
G01X307673Y375197D02*
X309181D01*
G01X305780Y377090D02*
X307673Y375197D01*
G01X304404Y377090D02*
X305780D01*
G01X302516Y375202D02*
X304404Y377090D01*
G01X300731Y375202D02*
X302516D01*
G01X298967Y376966D02*
X300731Y375202D01*
G01X297591Y376966D02*
X298967D01*
G01X295827Y375202D02*
X297591Y376966D01*
G01X294195Y375202D02*
X295827D01*
G01X307675Y523134D02*
Y518057D01*
G01X317714Y505024D02*
Y510114D01*
G01Y585714D02*
Y580624D01*
G01X307675Y560934D02*
Y555857D01*
G01X317714Y547914D02*
Y542824D01*
G01X307675Y598734D02*
Y593657D01*
G01X411415Y9121D02*
X411416Y9122D01*
G01X411415Y4023D02*
Y9121D01*
G01X392592Y-2500D02*
Y40300D01*
G01X396392Y-6300D02*
X392592Y-2500D01*
G01X399192Y-6300D02*
X396392D01*
G01X400492Y-5000D02*
X399192Y-6300D01*
G01X402392Y-5000D02*
X400492D01*
G01X404092Y-6700D02*
X402392Y-5000D01*
G01X405492Y-6700D02*
X404092D01*
G01X407192Y-5000D02*
X405492Y-6700D01*
G01X409192Y-5000D02*
X407192D01*
G01X410792Y-6600D02*
X409192Y-5000D01*
G01X412592Y-6600D02*
X410792D01*
G01X413992Y-5200D02*
X412592Y-6600D01*
G01X415792Y-5200D02*
X413992D01*
G01X417192Y-6600D02*
X415792Y-5200D01*
G01X394683Y17158D02*
X394682Y17157D01*
G01X394683Y22133D02*
Y17158D01*
G01X411415Y46921D02*
X411416Y46922D01*
G01X411415Y41823D02*
Y46921D01*
G01Y79623D02*
Y84714D01*
G01X395286Y54700D02*
X394492D01*
G01X396443Y53543D02*
X395286Y54700D01*
G01X396443Y49257D02*
Y53543D01*
G01X397000Y48700D02*
X396443Y49257D01*
G01X419678Y48700D02*
X397000D01*
G01X392500Y52708D02*
X394492Y54700D01*
G01X392500Y46008D02*
Y52708D01*
G01X390842Y44350D02*
X392500Y46008D01*
G01X390842Y42050D02*
Y44350D01*
G01X392592Y40300D02*
X390842Y42050D01*
G01X394682Y73988D02*
Y68492D01*
G01X392592Y76078D02*
X394682Y73988D01*
G01X392592Y90392D02*
Y76078D01*
G01X394682Y92482D02*
X392592Y90392D01*
G01X394682Y97732D02*
Y92482D01*
G01X394683Y97733D02*
X394682Y97732D01*
G01X405287Y359400D02*
X411547Y365660D01*
G01X402300Y359400D02*
X405287D01*
G01X400553Y357653D02*
X402300Y359400D01*
G01X398860Y357653D02*
X400553D01*
G01X397218Y359295D02*
X398860Y357653D01*
G01X395318Y359295D02*
X397218D01*
G01X393676Y357653D02*
X395318Y359295D01*
G01X392075Y357653D02*
X393676D01*
G01X390228Y359500D02*
X392075Y357653D01*
G01X388799Y359500D02*
X390228D01*
G01X387324Y360975D02*
X388799Y359500D01*
G01X385309Y360975D02*
X387324D01*
G01X383468Y362816D02*
X385309Y360975D01*
G01X381943Y362816D02*
X383468D01*
G01X380128Y361001D02*
X381943Y362816D01*
G01X378674Y361001D02*
X380128D01*
G01X376859Y362816D02*
X378674Y361001D01*
G01X375241Y362816D02*
X376859D01*
G01X373596Y361171D02*
X375241Y362816D01*
G01X371714Y361171D02*
X373596D01*
G01X369885Y363000D02*
X371714Y361171D01*
G01X368789Y363000D02*
X369885D01*
G01X366667Y365122D02*
X368789Y363000D01*
G01X365064Y365122D02*
X366667D01*
G01X362758Y362816D02*
X365064Y365122D01*
G01X361719Y362816D02*
X362758D01*
G01X360020Y361117D02*
X361719Y362816D01*
G01X358109Y361117D02*
X360020D01*
G01X356410Y362816D02*
X358109Y361117D01*
G01X355052Y362816D02*
X356410D01*
G01X403787Y355500D02*
X411447Y363160D01*
G01X402600Y355500D02*
X403787D01*
G01X400733Y353633D02*
X402600Y355500D01*
G01X398567Y353633D02*
X400733D01*
G01X396900Y355300D02*
X398567Y353633D01*
G01X395400Y355300D02*
X396900D01*
G01X393733Y353633D02*
X395400Y355300D01*
G01X391754Y353633D02*
X393733D01*
G01X390142Y355245D02*
X391754Y353633D01*
G01X388715Y355245D02*
X390142D01*
G01X386460Y357500D02*
X388715Y355245D01*
G01X385441Y357500D02*
X386460D01*
G01X383479Y359462D02*
X385441Y357500D01*
G01X382109Y359462D02*
X383479D01*
G01X380295Y357648D02*
X382109Y359462D01*
G01X378658Y357648D02*
X380295D01*
G01X376946Y359360D02*
X378658Y357648D01*
G01X375025Y359360D02*
X376946D01*
G01X373313Y357648D02*
X375025Y359360D01*
G01X371969Y357648D02*
X373313D01*
G01X370117Y359500D02*
X371969Y357648D01*
G01X368501Y359500D02*
X370117D01*
G01X367131Y360870D02*
X368501Y359500D01*
G01X364431Y360870D02*
X367131D01*
G01X363163Y359602D02*
X364431Y360870D01*
G01X361943Y359602D02*
X363163D01*
G01X359989Y357648D02*
X361943Y359602D01*
G01X358449Y357648D02*
X359989D01*
G01X356819Y359278D02*
X358449Y357648D01*
G01X354808Y359278D02*
X356819D01*
G01X414060Y390460D02*
X415500Y391900D01*
G01X411086Y390460D02*
X414060D01*
G01X386014Y355217D02*
X386157Y355360D01*
G01X381856Y355217D02*
X386014D01*
G01X380271Y353632D02*
X381856Y355217D01*
G01X378220Y353632D02*
X380271D01*
G01X376708Y355144D02*
X378220Y353632D01*
G01X375386Y355144D02*
X376708D01*
G01X373864Y353622D02*
X375386Y355144D01*
G01X371599Y353622D02*
X373864D01*
G01X370075Y355146D02*
X371599Y353622D01*
G01X368184Y355146D02*
X370075D01*
G01X367484Y355846D02*
X368184Y355146D01*
G01X367484Y356026D02*
Y355846D01*
G01X366543Y356967D02*
X367484Y356026D01*
G01X365211Y356967D02*
X366543D01*
G01X364270Y356026D02*
X365211Y356967D01*
G01X364270Y355834D02*
Y356026D01*
G01X363570Y355134D02*
X364270Y355834D01*
G01X361467Y355134D02*
X363570D01*
G01X360036Y353703D02*
X361467Y355134D01*
G01X357900Y353703D02*
X360036D01*
G01X356378Y355225D02*
X357900Y353703D01*
G01X355056Y355225D02*
X356378D01*
G01X356469Y351229D02*
X354929D01*
G01X358278Y349420D02*
X356469Y351229D01*
G01X360016Y349420D02*
X358278D01*
G01X361759Y351163D02*
X360016Y349420D01*
G01X363215Y351163D02*
X361759D01*
G01X363915Y351863D02*
X363215Y351163D01*
G01X363915Y352273D02*
Y351863D01*
G01X365064Y353422D02*
X363915Y352273D01*
G01X366690Y353422D02*
X365064D01*
G01X367839Y352273D02*
X366690Y353422D01*
G01X367839Y351854D02*
Y352273D01*
G01X368539Y351154D02*
X367839Y351854D01*
G01X370141Y351154D02*
X368539D01*
G01X371927Y349368D02*
X370141Y351154D01*
G01X373566Y349368D02*
X371927D01*
G01X375483Y351285D02*
X373566Y349368D01*
G01X376595Y351285D02*
X375483D01*
G01X378459Y349421D02*
X376595Y351285D01*
G01X380163Y349421D02*
X378459D01*
G01X382777Y352035D02*
X380163Y349421D01*
G01X382777Y353409D02*
Y352035D01*
G01X410335Y367048D02*
X411547Y368260D01*
G01X407728Y367048D02*
X410335D01*
G01X403910Y363230D02*
X407728Y367048D01*
G01X402630Y363230D02*
X403910D01*
G01X400440Y361040D02*
X402630Y363230D01*
G01X398890Y361040D02*
X400440D01*
G01X396790Y363140D02*
X398890Y361040D01*
G01X395870Y363140D02*
X396790D01*
G01X393760Y361030D02*
X395870Y363140D01*
G01X392120Y361030D02*
X393760D01*
G01X390260Y362890D02*
X392120Y361030D01*
G01X389240Y362890D02*
X390260D01*
G01X386830Y365300D02*
X389240Y362890D01*
G01X385280Y365300D02*
X386830D01*
G01X383690Y366890D02*
X385280Y365300D01*
G01X381810Y366890D02*
X383690D01*
G01X380160Y365240D02*
X381810Y366890D01*
G01X378700Y365240D02*
X380160D01*
G01X377050Y366890D02*
X378700Y365240D01*
G01X375170Y366890D02*
X377050D01*
G01X373690Y365410D02*
X375170Y366890D01*
G01X371290Y365410D02*
X373690D01*
G01X369650Y367050D02*
X371290Y365410D01*
G01X368490Y367050D02*
X369650D01*
G01X366450Y369090D02*
X368490Y367050D01*
G01X365370Y369090D02*
X366450D01*
G01X363260Y366980D02*
X365370Y369090D01*
G01X361890Y366980D02*
X363260D01*
G01X360270Y365360D02*
X361890Y366980D01*
G01X358180Y365360D02*
X360270D01*
G01X356540Y367000D02*
X358180Y365360D01*
G01X355070Y367000D02*
X356540D01*
G01X411415Y505024D02*
Y510114D01*
G01X392492Y518100D02*
Y528950D01*
G01X397192Y513400D02*
X392492Y518100D01*
G01X399092Y513400D02*
X397192D01*
G01X400292Y514600D02*
X399092Y513400D01*
G01X402392Y514600D02*
X400292D01*
G01X403892Y513100D02*
X402392Y514600D01*
G01X405292Y513100D02*
X403892D01*
G01X406992Y514800D02*
X405292Y513100D01*
G01X409192Y514800D02*
X406992D01*
G01X411092Y512900D02*
X409192Y514800D01*
G01X412392Y512900D02*
X411092D01*
G01X413992Y514500D02*
X412392Y512900D01*
G01X415792Y514500D02*
X413992D01*
G01X417500Y512792D02*
X415792Y514500D01*
G01X394683Y523134D02*
Y528930D01*
G01X411415Y585721D02*
X411416Y585722D01*
G01X411415Y580624D02*
Y585721D01*
G01X392500Y551924D02*
X392800Y552224D01*
G01X392500Y548500D02*
Y551924D01*
G01X392492Y548492D02*
X392500Y548500D01*
G01X392492Y537000D02*
Y548492D01*
G01X392800Y536692D02*
X392492Y537000D01*
G01X392800Y529258D02*
Y536692D01*
G01X392492Y528950D02*
X392800Y529258D01*
G01X397200Y549700D02*
X420330D01*
G01X396500Y550400D02*
X397200Y549700D01*
G01X396500Y552000D02*
Y550400D01*
G01X395900Y552600D02*
X396500Y552000D01*
G01X393176Y552600D02*
X395900D01*
G01X392800Y552224D02*
X393176Y552600D01*
G01X397000Y587400D02*
X419778D01*
G01X396400Y588000D02*
X397000Y587400D01*
G01X396400Y590801D02*
Y588000D01*
G01X392500Y584558D02*
Y590110D01*
G01X392492Y584550D02*
X392500Y584558D01*
G01X392492Y576150D02*
Y584550D01*
G01X392750Y575892D02*
X392492Y576150D01*
G01X392750Y566008D02*
Y575892D01*
G01X392492Y565750D02*
X392750Y566008D01*
G01X392492Y556300D02*
Y565750D01*
G01X392800Y555992D02*
X392492Y556300D01*
G01X392800Y552224D02*
Y555992D01*
G01X411415Y547921D02*
Y542824D01*
G01X394682Y560934D02*
X394683D01*
G01X394682Y569492D02*
Y560934D01*
G01X394683Y528930D02*
X394587Y529026D01*
G01X395500Y591701D02*
X396400Y590801D01*
G01X394091Y591701D02*
X395500D01*
G01X415592Y609300D02*
X417192Y607700D01*
G01X414892Y609300D02*
X415592D01*
G01X412292Y611900D02*
X414892Y609300D01*
G01X410392Y611900D02*
X412292D01*
G01X409092Y610600D02*
X410392Y611900D01*
G01X407392Y610600D02*
X409092D01*
G01X406396Y611596D02*
X407392Y610600D01*
G01X402788Y611596D02*
X406396D01*
G01X402142Y610950D02*
X402788Y611596D01*
G01X400650Y610950D02*
X402142D01*
G01X399800Y611800D02*
X400650Y610950D01*
G01X397292Y611800D02*
X399800D01*
G01X394692Y609200D02*
X397292Y611800D01*
G01X393592Y609200D02*
X394692D01*
G01X392892Y608500D02*
X393592Y609200D01*
G01X392892Y592900D02*
Y608500D01*
G01X394091Y591701D02*
X392892Y592900D01*
G01X392500Y590110D02*
X394091Y591701D01*
G01X394682Y598734D02*
X394683D01*
G01X394682Y607292D02*
Y598734D01*
G01X441680Y-50423D02*
G02Y-53848I0J-1712D01*
G01X421455Y17058D02*
X421456Y17057D01*
G01X421455Y22133D02*
Y17058D01*
G01X470733Y-19933D02*
X656088D01*
G01X462920Y-12120D02*
X470733Y-19933D01*
G01X462920Y-7020D02*
Y-12120D01*
G01X461850Y-5950D02*
X462920Y-7020D01*
G01X449650Y-5950D02*
X461850D01*
G01X448700Y-5000D02*
X449650Y-5950D01*
G01X447000Y-5000D02*
X448700D01*
G01X445700Y-6300D02*
X447000Y-5000D01*
G01X443100Y-6300D02*
X445700D01*
G01X439500Y-2700D02*
X443100Y-6300D01*
G01X437600Y-2700D02*
X439500D01*
G01X435300Y-5000D02*
X437600Y-2700D01*
G01X434200Y-5000D02*
X435300D01*
G01X432700Y-6500D02*
X434200Y-5000D01*
G01X430500Y-6500D02*
X432700D01*
G01X429200Y-5200D02*
X430500Y-6500D01*
G01X427200Y-5200D02*
X429200D01*
G01X425400Y-7000D02*
X427200Y-5200D01*
G01X424400Y-7000D02*
X425400D01*
G01X422600Y-5200D02*
X424400Y-7000D01*
G01X422600Y-2963D02*
Y-5200D01*
G01X421454Y-1817D02*
X422600Y-2963D01*
G01X421455Y4023D02*
Y9121D01*
G01X418892Y-6600D02*
X417192D01*
G01X420100Y-5392D02*
X418892Y-6600D01*
G01X420100Y-3171D02*
Y-5392D01*
G01X421454Y-1817D02*
X420100Y-3171D01*
G01X438187Y46920D02*
X438189Y46922D01*
G01X438187Y41823D02*
Y46920D01*
G01X421455Y41823D02*
Y46921D01*
G01X421456Y46922D02*
X419678Y48700D01*
G01X421455Y46921D02*
X421456Y46922D01*
G01X421455Y73758D02*
X421456Y73757D01*
G01X421455Y79623D02*
Y73758D01*
G01Y54858D02*
X421456Y54857D01*
G01X421455Y59933D02*
Y54858D01*
G01X458100Y276400D02*
X456000Y278500D01*
G01X458400Y276400D02*
X458100D01*
G01X438934Y269765D02*
Y270091D01*
G01X440592Y268107D02*
X438934Y269765D01*
G01X441165Y268107D02*
X440592D01*
G01X444752Y264520D02*
X441165Y268107D01*
G01X444752Y264188D02*
Y264520D01*
G01X472648Y292341D02*
X472692Y292385D01*
G01X469018Y292341D02*
X472648D01*
G01X463359Y298000D02*
X469018Y292341D01*
G01X461500Y298000D02*
X463359D01*
G01X474276Y293969D02*
X478941D01*
G01X472692Y292385D02*
X474276Y293969D01*
G01X472811Y340247D02*
X471033Y342025D01*
G01X473185Y339343D02*
X472811Y340247D01*
G01X473185Y338730D02*
Y339343D01*
G01X472619Y337363D02*
X473185Y338730D01*
G01X472619Y332452D02*
Y337363D01*
G01X473871Y331200D02*
X472619Y332452D01*
G01X475101Y331200D02*
X473871D01*
G01X477160Y329141D02*
X475101Y331200D01*
G01X478537Y329141D02*
X477160D01*
G01X477100Y302100D02*
X478607D01*
G01X474057Y299057D02*
X477100Y302100D01*
G01X471100Y296100D02*
X474057Y299057D01*
G01X469299Y296100D02*
X471100D01*
G01X467970Y297429D02*
X469299Y296100D01*
G01X465435Y297429D02*
X467970D01*
G01X461864Y301000D02*
X465435Y297429D01*
G01X461500Y301000D02*
X461864D01*
G01X462254Y320803D02*
X461000D01*
G01X463671Y319386D02*
X462254Y320803D01*
G01X461500Y294200D02*
Y295000D01*
G01X466055Y289645D02*
X461500Y294200D01*
G01X467612Y289645D02*
X466055D01*
G01X468757Y288500D02*
X467612Y289645D01*
G01X475000Y288500D02*
X468757D01*
G01X476572Y290072D02*
X475000Y288500D01*
G01X478828Y290072D02*
X476572D01*
G01X471033Y342025D02*
Y342947D01*
G01X419630Y512792D02*
X417500D01*
G01X419630Y512775D02*
Y512792D01*
G01X421455Y510950D02*
X419630Y512775D01*
G01X421455Y505024D02*
Y510950D01*
G01Y548575D02*
Y547921D01*
G01X420330Y549700D02*
X421455Y548575D01*
G01X421456Y547922D02*
X421455Y547921D01*
G01X419778Y587400D02*
X421456Y585722D01*
G01X421455Y547921D02*
Y542824D01*
G01Y585721D02*
Y580624D01*
G01X421456Y585722D02*
X421455Y585721D01*
G01Y555858D02*
X421456Y555857D01*
G01X421455Y560934D02*
Y555858D01*
G01X438187Y585720D02*
X438189Y585722D01*
G01X438187Y580624D02*
Y585720D01*
G01X421455Y593658D02*
X421456Y593657D01*
G01X421455Y598734D02*
Y593658D01*
G01X421454Y610262D02*
Y612560D01*
G01X418892Y607700D02*
X421454Y610262D01*
G01X417192Y607700D02*
X418892D01*
G01X525111Y277767D02*
Y276646D01*
G01X522529Y280349D02*
X525111Y277767D01*
G01X515100Y268847D02*
X518352D01*
G01X514220Y267967D02*
X515100Y268847D01*
G01X514220Y266791D02*
Y267967D01*
G01X510972Y255019D02*
Y255647D01*
G01X509953Y254000D02*
X510972Y255019D01*
G01X509953Y250435D02*
Y254000D01*
G01X509786Y250268D02*
X509953Y250435D01*
G01X509786Y248261D02*
Y250268D01*
G01X510074Y247973D02*
X509786Y248261D01*
G01X510074Y246544D02*
Y247973D01*
G01X509922Y246392D02*
X510074Y246544D01*
G01X509922Y244569D02*
Y246392D01*
G01X511123Y243368D02*
X509922Y244569D01*
G01X512222Y243368D02*
X511123D01*
G01X514225Y241365D02*
X512222Y243368D01*
G01X518170Y241365D02*
X514225D01*
G01X518352Y241547D02*
X518170Y241365D01*
G01X510937Y261047D02*
X510401Y260511D01*
G01X510937Y262947D02*
Y261047D01*
G01Y266921D02*
Y266447D01*
G01X508990Y268868D02*
X510937Y266921D01*
G01X507772Y268868D02*
X508990D01*
G01X506067Y270573D02*
X507772Y268868D01*
G01X501675Y270573D02*
X506067D01*
G01X501452Y270796D02*
X501675Y270573D01*
G01X510819Y278315D02*
X508634Y280500D01*
G01X512629Y278315D02*
X510819D01*
G01X514298Y276646D02*
X512629Y278315D01*
G01X518352Y276646D02*
X514298D01*
G01X513266Y247121D02*
X511592Y245447D01*
G01X513266Y256483D02*
Y247121D01*
G01X512430Y257319D02*
X513266Y256483D01*
G01X512430Y258547D02*
Y257319D01*
G01X514220Y261244D02*
X513857Y260881D01*
G01X514220Y263291D02*
Y261244D01*
G01X506878Y264496D02*
X507400D01*
G01X505722Y263340D02*
X506878Y264496D01*
G01X504104Y263340D02*
X505722D01*
G01X502333Y265111D02*
X504104Y263340D01*
G01X498236Y265111D02*
X502333D01*
G01X498072Y264947D02*
X498236Y265111D01*
G01X521012Y280349D02*
X522529D01*
G01X519024Y282337D02*
X521012Y280349D01*
G01X517488Y282337D02*
X519024D01*
G01X515448Y284377D02*
X517488Y282337D01*
G01X514520Y284377D02*
X515448D01*
G01X512622Y286275D02*
X514520Y284377D01*
G01X511179Y286275D02*
X512622D01*
G01X508863Y288591D02*
X511179Y286275D01*
G01X507197Y288591D02*
X508863D01*
G01X505767Y290021D02*
X507197Y288591D01*
G01X504049Y290021D02*
X505767D01*
G01X502566Y288538D02*
X504049Y290021D01*
G01X500486Y288538D02*
X502566D01*
G01X498892Y290132D02*
X500486Y288538D01*
G01X497468Y290132D02*
X498892D01*
G01X495014Y292586D02*
X497468Y290132D01*
G01X493670Y292586D02*
X495014D01*
G01X492095Y294161D02*
X493670Y292586D01*
G01X490672Y294161D02*
X492095D01*
G01X488745Y292234D02*
X490672Y294161D01*
G01X486836Y292234D02*
X488745D01*
G01X484827Y294243D02*
X486836Y292234D01*
G01X483735Y294243D02*
X484827D01*
G01X481968Y292476D02*
X483735Y294243D01*
G01X480434Y292476D02*
X481968D01*
G01X478941Y293969D02*
X480434Y292476D01*
G01X479399Y328279D02*
X478537Y329141D01*
G01X479399Y326681D02*
Y328279D01*
G01X479087Y326369D02*
X479399Y326681D01*
G01X479087Y324424D02*
Y326369D01*
G01X479399Y324112D02*
X479087Y324424D01*
G01X479399Y322780D02*
Y324112D01*
G01X479087Y322468D02*
X479399Y322780D01*
G01X479087Y320525D02*
Y322468D01*
G01X479399Y320213D02*
X479087Y320525D01*
G01X479399Y318881D02*
Y320213D01*
G01X479087Y318569D02*
X479399Y318881D01*
G01X479087Y316625D02*
Y318569D01*
G01X479399Y316313D02*
X479087Y316625D01*
G01X479399Y302892D02*
Y316313D01*
G01X478607Y302100D02*
X479399Y302892D01*
G01X480500Y288400D02*
X478828Y290072D01*
G01X482000Y288400D02*
X480500D01*
G01X483700Y290100D02*
X482000Y288400D01*
G01X485200Y290100D02*
X483700D01*
G01X486802Y288498D02*
X485200Y290100D01*
G01X488620Y288498D02*
X486802D01*
G01X490541Y290419D02*
X488620Y288498D01*
G01X492129Y290419D02*
X490541D01*
G01X494148Y288400D02*
X492129Y290419D01*
G01X495300Y288400D02*
X494148D01*
G01X497200Y286500D02*
X495300Y288400D01*
G01X498348Y286500D02*
X497200D01*
G01X500595Y284253D02*
X498348Y286500D01*
G01X502047Y284253D02*
X500595D01*
G01X503500Y282800D02*
X502047Y284253D01*
G01X505100Y282800D02*
X503500D01*
G01X507400Y280500D02*
X505100Y282800D01*
G01X508634Y280500D02*
X507400D01*
G01X605640Y458540D02*
X595070Y447970D01*
G01X605510Y22133D02*
Y16999D01*
G01X659755Y-7527D02*
Y-8699D01*
G01X659128Y-6900D02*
X659755Y-7527D01*
G01X647400Y-6900D02*
X659128D01*
G01X615549Y22133D02*
Y16999D01*
G01X659700Y23400D02*
Y22900D01*
G01X661800Y25500D02*
X659700Y23400D01*
G01X664100Y25500D02*
X661800D01*
G01X605510Y4023D02*
Y9157D01*
G01X647500Y-9000D02*
X647000Y-9500D01*
G01X649600Y-9000D02*
X647500D01*
G01X656088Y-19933D02*
X656807Y-20652D01*
G01X653850Y-9750D02*
X653100Y-9000D01*
G01X653850Y-12050D02*
Y-9750D01*
G01X653150Y-12750D02*
X653850Y-12050D01*
G01X653150Y-14000D02*
Y-12750D01*
G01X653100Y-9400D02*
Y-9000D01*
G01X650400Y-12100D02*
X653100Y-9400D01*
G01X647000Y-12100D02*
X650400D01*
G01X655300Y-12800D02*
X656500Y-14000D01*
G01X655300Y-9654D02*
Y-12800D01*
G01X656255Y-8699D02*
X655300Y-9654D01*
G01X658764Y-12132D02*
X659747D01*
G01X656255Y-9623D02*
X658764Y-12132D01*
G01X656255Y-8699D02*
Y-9623D01*
G01X653833Y92766D02*
X652718Y93881D01*
G01X656406Y92766D02*
X653833D01*
G01X656405Y86295D02*
Y89566D01*
G01X657900Y84800D02*
X656405Y86295D01*
G01X660600Y84800D02*
X657900D01*
G01X656406Y89567D02*
Y92766D01*
G01X656405Y89566D02*
X656406Y89567D01*
G01X605510Y92599D02*
Y97733D01*
G01Y59933D02*
Y54799D01*
G01X615549Y59933D02*
Y54799D01*
G01Y92599D02*
Y97733D01*
G01X659905Y89566D02*
X662352D01*
G01X605510Y41823D02*
Y46957D01*
G01Y79623D02*
Y84757D01*
G01X623893Y251393D02*
X618279D01*
G01X636000Y263500D02*
X623893Y251393D01*
G01X636000Y269575D02*
Y263500D01*
G01X636925Y270500D02*
X636000Y269575D01*
G01X638500Y270500D02*
X636925D01*
G01X646000Y272368D02*
X643500Y274868D01*
G01X646000Y272000D02*
Y272368D01*
G01Y259728D02*
Y261500D01*
G01X652153Y253575D02*
X646000Y259728D01*
G01X652153Y253547D02*
Y253575D01*
G01X652260Y253440D02*
X652153Y253547D01*
G01X652260Y250190D02*
Y253440D01*
G01X651235Y249165D02*
X652260Y250190D01*
G01X644840Y269660D02*
X642855D01*
G01X646000Y268500D02*
X644840Y269660D01*
G01X664415Y276455D02*
X662786Y278084D01*
G01X654950Y254550D02*
Y253446D01*
G01X653000Y256500D02*
X654950Y254550D01*
G01X649500Y260000D02*
X653000Y256500D01*
G01X649500Y261300D02*
Y260000D01*
G01X635857Y280500D02*
X628525Y287832D01*
G01X638500Y280500D02*
X635857D01*
G01X661767Y295675D02*
X662238Y296146D01*
G01X661767Y293474D02*
Y295675D01*
G01X664321Y279856D02*
X660901D01*
G01X639622Y286894D02*
Y290210D01*
G01X643823Y286894D02*
Y289650D01*
G01X655500Y294400D02*
Y293500D01*
G01X657950Y296850D02*
X655500Y294400D01*
G01X658617Y294069D02*
X658853Y294305D01*
G01X658617Y291871D02*
Y294069D01*
G01X612307Y463508D02*
X607339Y458540D01*
G01X612307Y470019D02*
Y463508D01*
G01X607339Y458540D02*
X605640D01*
G01X614930Y475385D02*
Y478050D01*
G01X614105Y474560D02*
X614930Y475385D01*
G01X613700Y474560D02*
X614105D01*
G01X611250Y475150D02*
Y476750D01*
G01X611840Y474560D02*
X611250Y475150D01*
G01X613700Y474560D02*
X611840D01*
G01X627700Y477600D02*
X627000Y478300D01*
G01X631600Y477600D02*
X627700D01*
G01X605510Y505024D02*
Y510157D01*
G01X630152Y481100D02*
X631600D01*
G01X629389Y480337D02*
X630152Y481100D01*
G01X626800Y480337D02*
X629389D01*
G01X625569Y481568D02*
X626800Y480337D01*
G01X636400Y481100D02*
X631600D01*
G01X636600Y480900D02*
X636400Y481100D01*
G01X624700Y482437D02*
X625569Y481568D01*
G01X624700Y484100D02*
Y482437D01*
G01X611726Y488550D02*
X614430D01*
G01X609470Y486294D02*
X611726Y488550D01*
G01X609470Y484060D02*
Y486294D01*
G01X660700Y507500D02*
X663000D01*
G01X658900Y509300D02*
X660700Y507500D01*
G01X617930Y485050D02*
X618430D01*
G01X616195Y486785D02*
X617930Y485050D01*
G01X616195Y490328D02*
Y486785D01*
G01X614870Y491653D02*
X616195Y490328D01*
G01X614870Y492153D02*
Y491653D01*
G01X618430Y484002D02*
Y485050D01*
G01X617738Y483310D02*
X618430Y484002D01*
G01X616170Y483310D02*
X617738D01*
G01X614430Y485050D02*
X616170Y483310D01*
G01X613050Y485050D02*
X612000Y484000D01*
G01X614430Y485050D02*
X613050D01*
G01X615549Y523134D02*
Y517999D01*
G01X605510Y523134D02*
Y517999D01*
G01X635880Y493304D02*
X636500Y493924D01*
G01X635880Y490751D02*
Y493304D01*
G01X636930Y489701D02*
X635880Y490751D01*
G01X636930Y488050D02*
Y489701D01*
G01X638650Y484550D02*
X636930D01*
G01X641500Y487400D02*
X638650Y484550D01*
G01X636930D02*
X632930D01*
G01X631250D02*
X632930D01*
G01X628700Y482000D02*
X631250Y484550D01*
G01X614930Y481550D02*
X618430D01*
G01X610779D02*
X614930D01*
G01X609284Y480055D02*
X610779Y481550D01*
G01X659279Y488500D02*
X659070Y488709D01*
G01X662000Y488500D02*
X659279D01*
G01X605510Y542824D02*
Y547957D01*
G01Y580624D02*
Y585757D01*
G01X615549Y560934D02*
Y555799D01*
G01X658600Y587320D02*
X660320Y585600D01*
G01X658600Y590900D02*
Y587320D01*
G01X662200Y571500D02*
X664100Y569600D01*
G01X649900Y571500D02*
X662200D01*
G01X647700Y573700D02*
X649900Y571500D01*
G01X647700Y583500D02*
Y573700D01*
G01X651100Y586900D02*
X647700Y583500D01*
G01X651100Y610000D02*
Y586900D01*
G01X605510Y560934D02*
Y555799D01*
G01X660100Y590900D02*
X658600D01*
G01X662000Y589000D02*
X660100Y590900D01*
G01X655100Y614000D02*
X651100Y610000D01*
G01X655100Y614100D02*
Y614000D01*
G01X605510Y598734D02*
Y593599D01*
G01X615549Y598734D02*
Y593599D01*
G01X712594Y29000D02*
X727891D01*
G01X711000Y27406D02*
X712594Y29000D01*
G01X711000Y25572D02*
Y27406D01*
G01X707000Y21572D02*
X711000Y25572D01*
G01X707000Y16500D02*
Y21572D01*
G01X708412Y15088D02*
X707000Y16500D01*
G01X708412Y-15499D02*
Y15088D01*
G01X709255Y-16342D02*
X708412Y-15499D01*
G01X709255Y-16357D02*
Y-16342D01*
G01X710673Y-17775D02*
X709255Y-16357D01*
G01X710673Y-19273D02*
Y-17775D01*
G01X710107Y-19839D02*
X710673Y-19273D01*
G01X716869Y-6048D02*
X713937D01*
G01X716921Y-6100D02*
X716869Y-6048D01*
G01X716921D02*
Y-6100D01*
G01X667000Y28400D02*
X664100Y25500D01*
G01X712169Y30025D02*
X728175D01*
G01X709975Y27831D02*
X712169Y30025D01*
G01X709975Y25997D02*
Y27831D01*
G01X706000Y22022D02*
X709975Y25997D01*
G01X706000Y16000D02*
Y22022D01*
G01X707487Y14513D02*
X706000Y16000D01*
G01X707487Y-15883D02*
Y14513D01*
G01X708330Y-16726D02*
X707487Y-15883D01*
G01X708330Y-17806D02*
Y-16726D01*
G01X698300Y84800D02*
Y85300D01*
G01X694000Y80500D02*
X698300Y84800D01*
G01X694000Y79500D02*
Y80500D01*
G01X707893Y88091D02*
Y82298D01*
G01X707329Y88655D02*
X707893Y88091D01*
G01X707329Y88955D02*
Y88655D01*
G01X711900Y82965D02*
X711233Y82298D01*
G01X711900Y84600D02*
Y82965D01*
G01X713300Y86000D02*
X711900Y84600D01*
G01X667900Y85800D02*
Y84100D01*
G01X664888Y88812D02*
X667900Y85800D01*
G01X664888Y89189D02*
Y88812D01*
G01Y89189D02*
Y92766D01*
G01X666432Y84100D02*
X664471Y86061D01*
G01X667900Y84100D02*
X666432D01*
G01X706074Y81705D02*
X703919Y79550D01*
G01X706074Y86558D02*
Y81705D01*
G01X705972Y86660D02*
X706074Y86558D01*
G01X668388Y89189D02*
X670795D01*
G01X703919Y88478D02*
Y82850D01*
G01X703845Y88552D02*
X703919Y88478D01*
G01X703845Y88830D02*
Y88552D01*
G01X710500Y260000D02*
Y256000D01*
G01X710700Y260200D02*
X710500Y260000D01*
G01X697138Y276963D02*
X690048Y284053D01*
G01X697138Y274570D02*
Y276963D01*
G01X699147Y272561D02*
X697138Y274570D01*
G01X702011Y272561D02*
X699147D01*
G01X674253Y273177D02*
X673240Y274190D01*
G01X680472Y273177D02*
X674253D01*
G01X681321Y274026D02*
X680472Y273177D01*
G01X690704Y274026D02*
X681321D01*
G01X665688Y278489D02*
X664321Y279856D01*
G01X665688Y274520D02*
Y278489D01*
G01X667031Y273177D02*
X665688Y274520D01*
G01X670736Y273177D02*
X667031D01*
G01X671749Y274190D02*
X670736Y273177D01*
G01X673240Y274190D02*
X671749D01*
G01X679700Y256000D02*
X677800Y254100D01*
G01X683000Y256000D02*
X679700D01*
G01X716761Y269511D02*
Y284408D01*
G01X710675Y263425D02*
X716761Y269511D01*
G01X706110Y256080D02*
X704090D01*
G01X709690Y252500D02*
X706110Y256080D01*
G01X710500Y252500D02*
X709690D01*
G01X664415Y274320D02*
Y276455D01*
G01X666687Y272048D02*
X664415Y274320D01*
G01X677816Y272048D02*
X666687D01*
G01X679588Y270276D02*
X677816Y272048D01*
G01X682204Y270276D02*
X679588D01*
G01X700567Y270530D02*
X702036Y269061D01*
G01X699869Y270530D02*
X700567D01*
G01X696213Y274186D02*
X699869Y270530D01*
G01X696213Y276579D02*
Y274186D01*
G01X693259Y279533D02*
X696213Y276579D01*
G01X693252Y279533D02*
X693259D01*
G01X691732Y281053D02*
X693252Y279533D01*
G01X683000Y295120D02*
X686140Y298260D01*
G01X683000Y294800D02*
Y295120D01*
G01X673500Y297656D02*
X673922Y298078D01*
G01X673500Y295000D02*
Y297656D01*
G01X700500Y306300D02*
Y308000D01*
G01X700700Y306100D02*
X700500Y306300D01*
G01X700700Y304300D02*
Y306100D01*
G01X699500Y308000D02*
X700500D01*
G01X697700Y309800D02*
X699500Y308000D01*
G01X689300Y309800D02*
X697700D01*
G01X688100Y308600D02*
X689300Y309800D01*
G01X709000Y300000D02*
X709100Y300100D01*
G01X708380Y300000D02*
X709000D01*
G01X706780Y301600D02*
X708380Y300000D01*
G01X705800Y301600D02*
X706780D01*
G01X702503Y302253D02*
Y296653D01*
G01X705319Y305069D02*
X702503Y302253D01*
G01X707631Y305069D02*
X705319D01*
G01X709100Y303600D02*
X707631Y305069D01*
G01X709100Y302556D02*
Y303600D01*
G01X709856Y301800D02*
X709100Y302556D01*
G01X711800Y301800D02*
X709856D01*
G01X712600Y301000D02*
X711800Y301800D01*
G01X712600Y300100D02*
Y301000D01*
G01X704516Y296653D02*
X702503D01*
G01X716761Y284408D02*
X704516Y296653D01*
G01X690284Y289457D02*
Y291412D01*
G01X688974Y288147D02*
X690284Y289457D01*
G01X688924Y288147D02*
X688974D01*
G01X690048Y281053D02*
X691732D01*
G01X689000Y348400D02*
X692000Y345400D01*
G01X689000Y349000D02*
Y348400D01*
G01X694800Y345400D02*
X695700Y346300D01*
G01X692000Y345400D02*
X694800D01*
G01X687427Y384926D02*
Y380000D01*
G01X694504Y349000D02*
X693000D01*
G01X695790Y350286D02*
X694504Y349000D01*
G01X695790Y351300D02*
Y350286D01*
G01X695144Y354644D02*
X695644D01*
G01X693000Y352500D02*
X695144Y354644D01*
G01X693800Y357300D02*
X689000Y352500D01*
G01X695700Y357300D02*
X693800D01*
G01X678193Y507827D02*
X682050Y503970D01*
G01X678193Y510515D02*
Y507827D01*
G01X675841Y512867D02*
X678193Y510515D01*
G01X673316Y512867D02*
X675841D01*
G01X669900Y516283D02*
X673316Y512867D01*
G01X669900Y520029D02*
Y516283D01*
G01X668000Y521929D02*
X669900Y520029D01*
G01X668000Y527300D02*
Y521929D01*
G01X667000Y491600D02*
Y494500D01*
G01X669150Y489450D02*
X667000Y491600D01*
G01X668118Y497318D02*
Y500500D01*
G01X667000Y496200D02*
X668118Y497318D01*
G01X667000Y494500D02*
Y496200D01*
G01X664000Y494500D02*
X667000D01*
G01X668152Y500500D02*
X668118D01*
G01X671436Y503784D02*
X668152Y500500D01*
G01X673464Y503784D02*
X671436D01*
G01X680500Y490200D02*
Y493000D01*
G01X679700Y489400D02*
X680500Y490200D01*
G01X674546Y498546D02*
X670500Y494500D01*
G01X678020Y498546D02*
X674546D01*
G01X679049Y499575D02*
X678020Y498546D01*
G01X679049Y503746D02*
Y499575D01*
G01X665787Y529513D02*
X668000Y527300D01*
G01X665787Y543586D02*
Y529513D01*
G01X676900Y554699D02*
X665787Y543586D01*
G01X676900Y566337D02*
Y554699D01*
G01X673637Y569600D02*
X676900Y566337D01*
G01X664100Y569600D02*
X673637D01*
G01X722406Y596494D02*
Y598950D01*
G01X724300Y594600D02*
X722406Y596494D01*
G01X725600Y594600D02*
X724300D01*
G01X756705Y23130D02*
X756714D01*
G01X755033Y21458D02*
X756705Y23130D01*
G01X735433Y21458D02*
X755033D01*
G01X727891Y29000D02*
X735433Y21458D01*
G01X752919Y22483D02*
X753675Y23239D01*
G01X735717Y22483D02*
X752919D01*
G01X728175Y30025D02*
X735717Y22483D01*
G01X730923Y75315D02*
X726815D01*
G01X758970Y407700D02*
X758150Y406880D01*
G01X763200Y407700D02*
X758970D01*
G01X763200Y411517D02*
Y407700D01*
G01X762989Y411728D02*
X763200Y411517D01*
G01X768663Y418197D02*
X768080Y418780D01*
G01X768663Y411237D02*
Y418197D01*
G01X769600Y410300D02*
X768663Y411237D01*
G01X769600Y407600D02*
Y410300D01*
G01X766300Y411210D02*
Y407700D01*
G01X763069Y414441D02*
X766300Y411210D01*
G01X726660Y506700D02*
X726040Y506080D01*
G01X729350Y506700D02*
X726660D01*
G01X725190Y506930D02*
Y510910D01*
G01X726040Y506080D02*
X725190Y506930D01*
G01X726692Y580900D02*
X725400D01*
G01X728141Y579451D02*
X726692Y580900D01*
G01X728141Y578141D02*
Y579451D01*
G01X726500Y576500D02*
X728141Y578141D01*
G01X726500Y574500D02*
Y576500D01*
G01X727000Y596000D02*
X725600Y594600D01*
G01X727000Y600500D02*
Y596000D01*
G01X843989Y412312D02*
X891401Y364900D01*
G01X843988Y412311D02*
X843989Y412312D01*
G01X815189Y412311D02*
X843988D01*
G01X812000Y415500D02*
X815189Y412311D01*
G01X810000Y415500D02*
X812000D01*
G01X803621D02*
X806500D01*
G01X800721Y412600D02*
X803621Y415500D01*
G01X798500Y412600D02*
X800721D01*
G01X803133Y412500D02*
X806500D01*
G01X800463Y409830D02*
X803133Y412500D01*
G01X797200Y409830D02*
X800463D01*
G01X843254Y410536D02*
X889625Y364165D01*
G01X814159Y410536D02*
X843254D01*
G01X812190Y412505D02*
X814159Y410536D01*
G01X810005Y412505D02*
X812190D01*
G01X810000Y412500D02*
X810005Y412505D01*
G01X844725Y414087D02*
X893471Y365341D01*
G01X816413Y414087D02*
X844725D01*
G01X812000Y418500D02*
X816413Y414087D01*
G01X810000Y418500D02*
X812000D01*
G01X803785D02*
X802900Y417615D01*
G01X806500Y418500D02*
X803785D01*
G01X800610Y415325D02*
Y415000D01*
G01X802900Y417615D02*
X800610Y415325D01*
G01X902337Y348762D02*
X910455Y340644D01*
G01X909450Y395500D02*
X919706D01*
G01X908100Y358500D02*
X899500D01*
G01X912903Y353697D02*
X908100Y358500D01*
G01X906686Y355500D02*
X899500D01*
G01X912740Y349446D02*
X906686Y355500D01*
G01X904462Y350537D02*
X906622Y348377D01*
G01X901746Y350537D02*
X904462D01*
G01X900578Y351705D02*
X901746Y350537D01*
G01X894284Y351705D02*
X900578D01*
G01X891400Y354589D02*
X894284Y351705D01*
G01X891400Y363429D02*
Y354589D01*
G01X891401Y363430D02*
X891400Y363429D01*
G01X891401Y364900D02*
Y363430D01*
G01X906622Y348117D02*
Y348377D01*
G01X912939Y341800D02*
X906622Y348117D01*
G01X920847Y398260D02*
X903550D01*
G01X901010Y348762D02*
X902337D01*
G01X899842Y349930D02*
X901010Y348762D01*
G01X893548Y349930D02*
X899842D01*
G01X889625Y353853D02*
X893548Y349930D01*
G01X889625Y364165D02*
Y353853D01*
G01X906399Y352500D02*
X913099Y345800D01*
G01X902559Y352500D02*
X906399D01*
G01X901579Y353480D02*
X902559Y352500D01*
G01X895020Y353480D02*
X901579D01*
G01X893471Y355029D02*
X895020Y353480D01*
G01X893471Y365341D02*
Y355029D01*
G01X899500Y367500D02*
X908300D01*
G01X909762D02*
X913848Y363414D01*
G01X908300Y367500D02*
X909762D01*
G01X910700Y405500D02*
X908650Y403450D01*
G01X957283Y22133D02*
Y17057D01*
G01X957285Y22133D02*
X957283D01*
G01X967324Y9112D02*
X967322Y9114D01*
G01X967324Y4023D02*
Y9112D01*
G01Y46912D02*
X967322Y46914D01*
G01X967324Y41823D02*
Y46912D01*
G01Y84712D02*
X967322Y84714D01*
G01X967324Y79623D02*
Y84712D01*
G01X957283Y97733D02*
Y92657D01*
G01Y59933D02*
Y54857D01*
G01X957285Y59933D02*
X957283D01*
G01X957285Y97733D02*
X957283D01*
G01X914773Y211803D02*
X910900D01*
G01X917467Y209109D02*
X914773Y211803D01*
G01X915457Y207159D02*
X920847D01*
G01X910900Y203260D02*
X920847D01*
G01X916304Y340097D02*
X914601Y341800D01*
G01X918271Y340097D02*
X916304D01*
G01X919973Y341799D02*
X918271Y340097D01*
G01X924007Y339421D02*
X921629Y341799D01*
G01X925666Y339421D02*
X924007D01*
G01X926939Y338148D02*
X925666Y339421D01*
G01X928275Y338148D02*
X926939D01*
G01X929548Y339421D02*
X928275Y338148D01*
G01X932426Y339421D02*
X929548D01*
G01X933699Y338148D02*
X932426Y339421D01*
G01X935035Y338148D02*
X933699D01*
G01X936308Y339421D02*
X935035Y338148D01*
G01X939186Y339421D02*
X936308D01*
G01X940459Y338148D02*
X939186Y339421D01*
G01X941795Y338148D02*
X940459D01*
G01X943068Y339421D02*
X941795Y338148D01*
G01X945946Y339421D02*
X943068D01*
G01X947219Y338148D02*
X945946Y339421D01*
G01X948555Y338148D02*
X947219D01*
G01X950107Y339700D02*
X948555Y338148D01*
G01X952000Y339700D02*
X950107D01*
G01X953779Y337921D02*
X952000Y339700D01*
G01X955602Y337921D02*
X953779D01*
G01X957616Y335907D02*
X955602Y337921D01*
G01X965557Y335907D02*
X957616D01*
G01X967180Y337530D02*
X965557Y335907D01*
G01X969070Y337530D02*
X967180D01*
G01X970400Y336200D02*
X969070Y337530D01*
G01X972300Y336200D02*
X970400D01*
G01X970884Y332200D02*
X972262D01*
G01X969077Y334007D02*
X970884Y332200D01*
G01X967321Y334007D02*
X969077D01*
G01X965400Y332086D02*
X967321Y334007D01*
G01X964167Y332086D02*
X965400D01*
G01X962225Y334028D02*
X964167Y332086D01*
G01X960624Y334028D02*
X962225D01*
G01X958832Y332236D02*
X960624Y334028D01*
G01X957327Y332236D02*
X958832D01*
G01X955794Y333769D02*
X957327Y332236D01*
G01X953748Y333769D02*
X955794D01*
G01X951996Y335521D02*
X953748Y333769D01*
G01X950396Y335521D02*
X951996D01*
G01X948590Y333715D02*
X950396Y335521D01*
G01X947254Y333715D02*
X948590D01*
G01X945448Y335521D02*
X947254Y333715D01*
G01X943068Y335521D02*
X945448D01*
G01X941795Y334248D02*
X943068Y335521D01*
G01X940459Y334248D02*
X941795D01*
G01X939186Y335521D02*
X940459Y334248D01*
G01X936823Y335521D02*
X939186D01*
G01X935035Y333733D02*
X936823Y335521D01*
G01X933699Y333733D02*
X935035D01*
G01X931911Y335521D02*
X933699Y333733D01*
G01X930063Y335521D02*
X931911D01*
G01X928240Y333698D02*
X930063Y335521D01*
G01X926904Y333698D02*
X928240D01*
G01X925081Y335521D02*
X926904Y333698D01*
G01X923780Y335521D02*
X925081D01*
G01X921701Y337600D02*
X923780Y335521D01*
G01X920001Y337600D02*
X921701D01*
G01X918501Y336100D02*
X920001Y337600D01*
G01X916701Y336100D02*
X918501D01*
G01X914901Y337900D02*
X916701Y336100D01*
G01X913019Y337900D02*
X914901D01*
G01X910455Y340464D02*
X913019Y337900D01*
G01X910455Y340644D02*
Y340464D01*
G01X970720Y340034D02*
X972434D01*
G01X969302Y338616D02*
X970720Y340034D01*
G01X959808Y338616D02*
X969302D01*
G01X958750Y339674D02*
X959808Y338616D01*
G01X957226Y339674D02*
X958750D01*
G01X955200Y341700D02*
X957226Y339674D01*
G01X967971Y340840D02*
X967830D01*
G01X970592Y343461D02*
X967971Y340840D01*
G01X967830D02*
X965130D01*
G01X919791Y400209D02*
X924227D01*
G01X916700Y403300D02*
X919791Y400209D01*
G01X919706Y395500D02*
X920847Y394359D01*
G01X914679Y353697D02*
X912903D01*
G01X916657Y351719D02*
X914679Y353697D01*
G01X918255Y351719D02*
X916657D01*
G01X915054Y349446D02*
X912740D01*
G01X916293Y348207D02*
X915054Y349446D01*
G01X914601Y341800D02*
X912939D01*
G01X921629Y341799D02*
X919973D01*
G01X967347Y348611D02*
X967498D01*
G01X965130Y346394D02*
X967347Y348611D01*
G01X965130Y344340D02*
Y346394D01*
G01X969567Y347793D02*
X972619D01*
G01X968749Y348611D02*
X969567Y347793D01*
G01X967498Y348611D02*
X968749D01*
G01X954272Y341700D02*
X955200D01*
G01X952115Y343857D02*
X954272Y341700D01*
G01X950364Y343857D02*
X952115D01*
G01X948555Y342048D02*
X950364Y343857D01*
G01X947073Y342048D02*
X948555D01*
G01X945432Y343689D02*
X947073Y342048D01*
G01X943636Y343689D02*
X945432D01*
G01X941792Y341845D02*
X943636Y343689D01*
G01X940114Y341845D02*
X941792D01*
G01X938638Y343321D02*
X940114Y341845D01*
G01X936499Y343321D02*
X938638D01*
G01X934917Y341739D02*
X936499Y343321D01*
G01X933789Y341739D02*
X934917D01*
G01X931816Y343712D02*
X933789Y341739D01*
G01X930159Y343712D02*
X931816D01*
G01X928250Y341803D02*
X930159Y343712D01*
G01X926790Y341803D02*
X928250D01*
G01X924831Y343762D02*
X926790Y341803D01*
G01X923239Y343762D02*
X924831D01*
G01X921501Y345500D02*
X923239Y343762D01*
G01X920347Y345500D02*
X921501D01*
G01X918468Y343621D02*
X920347Y345500D01*
G01X916580Y343621D02*
X918468D01*
G01X914401Y345800D02*
X916580Y343621D01*
G01X913099Y345800D02*
X914401D01*
G01X927607Y400992D02*
X923099Y405500D01*
G01X927607Y398260D02*
Y400992D01*
G01X972257Y343461D02*
X970592D01*
G01X961406Y356509D02*
Y355360D01*
G01X958663Y359252D02*
X961406Y356509D01*
G01X957629Y359252D02*
X958663D01*
G01X955580Y361301D02*
X957629Y359252D01*
G01X953989Y361301D02*
X955580D01*
G01X952368Y362922D02*
X953989Y361301D01*
G01X950532Y362922D02*
X952368D01*
G01X948868Y361258D02*
X950532Y362922D01*
G01X946904Y361258D02*
X948868D01*
G01X945288Y362874D02*
X946904Y361258D01*
G01X943526Y362874D02*
X945288D01*
G01X941995Y361343D02*
X943526Y362874D01*
G01X940118Y361343D02*
X941995D01*
G01X938506Y362955D02*
X940118Y361343D01*
G01X936693Y362955D02*
X938506D01*
G01X935081Y361343D02*
X936693Y362955D01*
G01X933460Y361343D02*
X935081D01*
G01X931710Y363093D02*
X933460Y361343D01*
G01X930045Y363093D02*
X931710D01*
G01X928295Y361343D02*
X930045Y363093D01*
G01X926804Y361343D02*
X928295D01*
G01X924733Y363414D02*
X926804Y361343D01*
G01X913848Y363414D02*
X924733D01*
G01X923099Y405500D02*
X910700D01*
G01X967324Y510112D02*
X967322Y510114D01*
G01X967324Y505024D02*
Y510112D01*
G01X957283Y523133D02*
Y518057D01*
G01X957285Y523134D02*
X957283Y523133D01*
G01Y560933D02*
Y555857D01*
G01X957285Y560934D02*
X957283Y560933D01*
G01X967324Y547912D02*
X967322Y547914D01*
G01X967324Y542824D02*
Y547912D01*
G01Y585712D02*
X967322Y585714D01*
G01X967324Y580624D02*
Y585712D01*
G01X957283Y598733D02*
Y593657D01*
G01X957285Y598734D02*
X957283Y598733D01*
G01X973800Y337700D02*
X972300Y336200D01*
G01X975500Y337700D02*
X973800D01*
G01X977500Y335700D02*
X975500Y337700D01*
G01X979048Y335700D02*
X977500D01*
G01X980948Y337600D02*
X979048Y335700D01*
G01X982698Y337600D02*
X980948D01*
G01X984406Y335892D02*
X982698Y337600D01*
G01X985806Y335892D02*
X984406D01*
G01X987714Y337800D02*
X985806Y335892D01*
G01X988948Y337800D02*
X987714D01*
G01X991040Y335708D02*
X988948Y337800D01*
G01X992628Y335708D02*
X991040D01*
G01X994520Y337600D02*
X992628Y335708D01*
G01X995424Y337600D02*
X994520D01*
G01X997777Y339953D02*
X995424Y337600D01*
G01X999153Y339953D02*
X997777D01*
G01X1001181Y341981D02*
X999153Y339953D01*
G01X1006113Y339607D02*
X1008046Y341540D01*
G01X1004708Y339607D02*
X1006113D01*
G01X1002811Y337710D02*
X1004708Y339607D01*
G01X1001310Y337710D02*
X1002811D01*
G01X999200Y335600D02*
X1001310Y337710D01*
G01X997900Y335600D02*
X999200D01*
G01X996200Y333900D02*
X997900Y335600D01*
G01X994100Y333900D02*
X996200D01*
G01X992400Y332200D02*
X994100Y333900D01*
G01X991100Y332200D02*
X992400D01*
G01X989400Y333900D02*
X991100Y332200D01*
G01X987982Y333900D02*
X989400D01*
G01X986015Y331933D02*
X987982Y333900D01*
G01X984115Y331933D02*
X986015D01*
G01X982248Y333800D02*
X984115Y331933D01*
G01X980700Y333800D02*
X982248D01*
G01X979000Y332100D02*
X980700Y333800D01*
G01X977718Y332100D02*
X979000D01*
G01X975863Y333955D02*
X977718Y332100D01*
G01X974017Y333955D02*
X975863D01*
G01X972262Y332200D02*
X974017Y333955D01*
G01X992700Y340100D02*
X994200Y341600D01*
G01X990600Y340100D02*
X992700D01*
G01X989300Y341400D02*
X990600Y340100D01*
G01X985900D02*
X987200Y341400D01*
G01X984100Y340100D02*
X985900D01*
G01X982800Y341400D02*
X984100Y340100D01*
G01X979200D02*
X980500Y341400D01*
G01X977300Y340100D02*
X979200D01*
G01X976000Y341400D02*
X977300Y340100D01*
G01X972434Y340034D02*
X973800Y341400D01*
G01X1002822Y341981D02*
X1001181D01*
G01X1004686Y343845D02*
X1002822Y341981D01*
G01X1006400Y343845D02*
X1004686D01*
G01X1007107Y344552D02*
X1006400Y343845D01*
G01X1007107Y346433D02*
Y344552D01*
G01X1006540Y347000D02*
X1007107Y346433D01*
G01X1006540Y348270D02*
Y347000D01*
G01X1007990Y349720D02*
X1006540Y348270D01*
G01X1009620Y349720D02*
X1007990D01*
G01X1011230Y351330D02*
X1009620Y349720D01*
G01X1013051Y351330D02*
X1011230D01*
G01X1014684Y349697D02*
X1013051Y351330D01*
G01X1016499Y349697D02*
X1014684D01*
G01X1018180Y351378D02*
X1016499Y349697D01*
G01X1019332Y351378D02*
X1018180D01*
G01X1021484Y353530D02*
X1019332Y351378D01*
G01X1023053Y353530D02*
X1021484D01*
G01X1024967Y351616D02*
X1023053Y353530D01*
G01X1025880Y351616D02*
X1024967D01*
G01X1028113Y349383D02*
X1025880Y351616D01*
G01X1030062Y349383D02*
X1028113D01*
G01X1031908Y347537D02*
X1030062Y349383D01*
G01X1033502Y347537D02*
X1031908D01*
G01X1035505Y349540D02*
X1033502Y347537D01*
G01X1033481Y363171D02*
X1034500Y362152D01*
G01X1031572Y363171D02*
X1033481D01*
G01X1031401Y363000D02*
X1031572Y363171D01*
G01X1031400Y363000D02*
X1031401D01*
G01X1029800Y361400D02*
X1031400Y363000D01*
G01X1028315Y361400D02*
X1029800D01*
G01X1026366Y363349D02*
X1028315Y361400D01*
G01X1024624Y363349D02*
X1026366D01*
G01X1023002Y364971D02*
X1024624Y363349D01*
G01X1021508Y364971D02*
X1023002D01*
G01X1019890Y363353D02*
X1021508Y364971D01*
G01X1018226Y363353D02*
X1019890D01*
G01X1015960Y361087D02*
X1018226Y363353D01*
G01X1015250Y361087D02*
X1015960D01*
G01X1013187Y363150D02*
X1015250Y361087D01*
G01X1011160Y363150D02*
X1013187D01*
G01X1009230Y361220D02*
X1011160Y363150D01*
G01X1008230Y361220D02*
X1009230D01*
G01X1005926Y358916D02*
X1008230Y361220D01*
G01X1004386Y358916D02*
X1005926D01*
G01X1002743Y357273D02*
X1004386Y358916D01*
G01X1001033Y357273D02*
X1002743D01*
G01X998850Y355090D02*
X1001033Y357273D01*
G01X997910Y355090D02*
X998850D01*
G01X996850Y354030D02*
X997910Y355090D01*
G01X996850Y350470D02*
Y354030D01*
G01X996086Y349706D02*
X996850Y350470D01*
G01X994404Y349706D02*
X996086D01*
G01X992639Y351471D02*
X994404Y349706D01*
G01X991013Y351471D02*
X992639D01*
G01X989106Y349564D02*
X991013Y351471D01*
G01X987578Y349564D02*
X989106D01*
G01X985828Y347814D02*
X987578Y349564D01*
G01X984206Y347814D02*
X985828D01*
G01X982584Y349436D02*
X984206Y347814D01*
G01X980920Y349436D02*
X982584D01*
G01X979213Y347729D02*
X980920Y349436D01*
G01X977548Y347729D02*
X979213D01*
G01X975969Y349308D02*
X977548Y347729D01*
G01X974134Y349308D02*
X975969D01*
G01X972619Y347793D02*
X974134Y349308D01*
G01X1032873Y343720D02*
X1033969Y344816D01*
G01X1024770Y343720D02*
X1032873D01*
G01X1022700Y345790D02*
X1024770Y343720D01*
G01X1021120Y345790D02*
X1022700D01*
G01X1019490Y347420D02*
X1021120Y345790D01*
G01X1018148Y347420D02*
X1019490D01*
G01X1016215Y345487D02*
X1018148Y347420D01*
G01X1014857Y345487D02*
X1016215D01*
G01X1012850Y343480D02*
X1014857Y345487D01*
G01X1011359Y343480D02*
X1012850D01*
G01X1009419Y341540D02*
X1011359Y343480D01*
G01X1008046Y341540D02*
X1009419D01*
G01X1033296Y351666D02*
X1035383Y353753D01*
G01X1031645Y351666D02*
X1033296D01*
G01X1029863Y353448D02*
X1031645Y351666D01*
G01X1028295Y353448D02*
X1029863D01*
G01X1026139Y355604D02*
X1028295Y353448D01*
G01X1024539Y355604D02*
X1026139D01*
G01X1023025Y357118D02*
X1024539Y355604D01*
G01X1021508Y357118D02*
X1023025D01*
G01X1019417Y355027D02*
X1021508Y357118D01*
G01X1018008Y355027D02*
X1019417D01*
G01X1016192Y353211D02*
X1018008Y355027D01*
G01X1014613Y353211D02*
X1016192D01*
G01X1012524Y355300D02*
X1014613Y353211D01*
G01X1011510Y355300D02*
X1012524D01*
G01X1009661Y353451D02*
X1011510Y355300D01*
G01X1009661Y353390D02*
Y353451D01*
G01X1008110Y353390D02*
X1009661D01*
G01X1006430Y351710D02*
X1008110Y353390D01*
G01X1005110Y351710D02*
X1006430D01*
G01X1003530Y350130D02*
X1005110Y351710D01*
G01X1003530Y348910D02*
Y350130D01*
G01X1004193Y348247D02*
X1003530Y348910D01*
G01X1004193Y346817D02*
Y348247D01*
G01X1002840Y345464D02*
X1004193Y346817D01*
G01X1001147Y345464D02*
X1002840D01*
G01X999314Y343631D02*
X1001147Y345464D01*
G01X997821Y343631D02*
X999314D01*
G01X995790Y341600D02*
X997821Y343631D01*
G01X994200Y341600D02*
X995790D01*
G01X987200Y341400D02*
X989300D01*
G01X980500D02*
X982800D01*
G01X973800D02*
X976000D01*
G01X974272Y345476D02*
X972257Y343461D01*
G01X975831Y345476D02*
X974272D01*
G01X977633Y343674D02*
X975831Y345476D01*
G01X978820Y343674D02*
X977633D01*
G01X980841Y345695D02*
X978820Y343674D01*
G01X982462Y345695D02*
X980841D01*
G01X984398Y343759D02*
X982462Y345695D01*
G01X985683Y343759D02*
X984398D01*
G01X987690Y345766D02*
X985683Y343759D01*
G01X989241Y345766D02*
X987690D01*
G01X991269Y343738D02*
X989241Y345766D01*
G01X992593Y343738D02*
X991269D01*
G01X994386Y345531D02*
X992593Y343738D01*
G01X996037Y345531D02*
X994386D01*
G01X998150Y347644D02*
X996037Y345531D01*
G01X999035Y347644D02*
X998150D01*
G01X1000250Y348859D02*
X999035Y347644D01*
G01X1000250Y352290D02*
Y348859D01*
G01X1001407Y353447D02*
X1000250Y352290D01*
G01X1003057Y353447D02*
X1001407D01*
G01X1004950Y355340D02*
X1003057Y353447D01*
G01X1005810Y355340D02*
X1004950D01*
G01X1007743Y357273D02*
X1005810Y355340D01*
G01X1008013Y357273D02*
X1007743D01*
G01X1008050Y357310D02*
X1008013Y357273D01*
G01X1009320Y357310D02*
X1008050D01*
G01X1011070Y359060D02*
X1009320Y357310D01*
G01X1012940Y359060D02*
X1011070D01*
G01X1014647Y357353D02*
X1012940Y359060D01*
G01X1016174Y357353D02*
X1014647D01*
G01X1017966Y359145D02*
X1016174Y357353D01*
G01X1019757Y359145D02*
X1017966D01*
G01X1021656Y361044D02*
X1019757Y359145D01*
G01X1022917Y361044D02*
X1021656D01*
G01X1024938Y359023D02*
X1022917Y361044D01*
G01X1026582Y359023D02*
X1024938D01*
G01X1027996Y357609D02*
X1026582Y359023D01*
G01X1029392Y357609D02*
X1027996D01*
G01X1030423Y356578D02*
X1029392Y357609D01*
G01X1030423Y356496D02*
Y356578D01*
G01X1031666Y355253D02*
X1030423Y356496D01*
G01X1031666Y354128D02*
Y355253D01*
G01X1032385Y353409D02*
X1031666Y354128D01*
G01X1044291Y22133D02*
X1044293D01*
G01X1044291Y17610D02*
Y22133D01*
G01X1045525Y16376D02*
X1044291Y17610D01*
G01X1045525Y15357D02*
Y16376D01*
G01X1071063Y9121D02*
X1071064Y9122D01*
G01X1071063Y4023D02*
Y9121D01*
G01X1071065Y4023D02*
X1071063D01*
G01X1042200Y-2500D02*
Y40300D01*
G01X1046000Y-6300D02*
X1042200Y-2500D01*
G01X1048800Y-6300D02*
X1046000D01*
G01X1050100Y-5000D02*
X1048800Y-6300D01*
G01X1052000Y-5000D02*
X1050100D01*
G01X1053700Y-6700D02*
X1052000Y-5000D01*
G01X1055100Y-6700D02*
X1053700D01*
G01X1056800Y-5000D02*
X1055100Y-6700D01*
G01X1058800Y-5000D02*
X1056800D01*
G01X1060400Y-6600D02*
X1058800Y-5000D01*
G01X1062200Y-6600D02*
X1060400D01*
G01X1063600Y-5200D02*
X1062200Y-6600D01*
G01X1065400Y-5200D02*
X1063600D01*
G01X1066800Y-6600D02*
X1065400Y-5200D01*
G01X1068500Y-6600D02*
X1066800D01*
G01X1071062Y-4038D02*
X1068500Y-6600D01*
G01X1071062Y-1817D02*
Y-4038D01*
G01X1061025Y9121D02*
X1061024Y9122D01*
G01X1061025Y4023D02*
Y9121D01*
G01Y46921D02*
X1061024Y46922D01*
G01X1061025Y41823D02*
Y46921D01*
G01X1071063Y54858D02*
X1071064Y54857D01*
G01X1071063Y59933D02*
Y54858D01*
G01X1071065Y59933D02*
X1071063D01*
G01X1044293Y92693D02*
Y97733D01*
G01X1042200Y90600D02*
X1044293Y92693D01*
G01X1042200Y73100D02*
Y90600D01*
G01X1044290Y71010D02*
X1042200Y73100D01*
G01X1044290Y68964D02*
Y71010D01*
G01X1044293Y68961D02*
X1044290Y68964D01*
G01X1044293Y59933D02*
Y68961D01*
G01X1087795Y46920D02*
X1087797Y46922D01*
G01X1087795Y41823D02*
Y46920D01*
G01X1087797Y41823D02*
X1087795D01*
G01X1061025Y84712D02*
X1061023Y84714D01*
G01X1061025Y79623D02*
Y84712D01*
G01X1071063Y73758D02*
X1071064Y73757D01*
G01X1071063Y79623D02*
Y73758D01*
G01X1071065Y79623D02*
X1071063D01*
G01Y41823D02*
X1071065D01*
G01X1071063Y46921D02*
Y41823D01*
G01X1071064Y46922D02*
X1071063Y46921D01*
G01X1042500Y53100D02*
X1044100Y54700D01*
G01X1042500Y46400D02*
Y53100D01*
G01X1040450Y44350D02*
X1042500Y46400D01*
G01X1040450Y42050D02*
Y44350D01*
G01X1042200Y40300D02*
X1040450Y42050D01*
G01X1069286Y48700D02*
X1071064Y46922D01*
G01X1046900Y48700D02*
X1069286D01*
G01X1046200Y49400D02*
X1046900Y48700D01*
G01X1046200Y53394D02*
Y49400D01*
G01X1044894Y54700D02*
X1046200Y53394D01*
G01X1044100Y54700D02*
X1044894D01*
G01X1088500Y269699D02*
Y270000D01*
G01X1089592Y268607D02*
X1088500Y269699D01*
G01X1089665Y268607D02*
X1089592D01*
G01X1090607Y267665D02*
X1089665Y268607D01*
G01X1090607Y265993D02*
Y267665D01*
G01X1092100Y264500D02*
X1090607Y265993D01*
G01X1035961Y349540D02*
X1035505D01*
G01X1036371Y349950D02*
X1035961Y349540D01*
G01X1037285Y349950D02*
X1036371D01*
G01X1038131Y350796D02*
X1037285Y349950D01*
G01X1039410Y350796D02*
X1038131D01*
G01X1042014Y353400D02*
X1039410Y350796D01*
G01X1043100Y353400D02*
X1042014D01*
G01X1045100Y355400D02*
X1043100Y353400D01*
G01X1046208Y355400D02*
X1045100D01*
G01X1048433Y353175D02*
X1046208Y355400D01*
G01X1052430Y353175D02*
X1048433D01*
G01X1052664Y353409D02*
X1052430Y353175D01*
G01X1035300Y355825D02*
X1035765Y355360D01*
G01X1035300Y357200D02*
Y355825D01*
G01X1034158Y358342D02*
X1035300Y357200D01*
G01X1034158Y359926D02*
Y358342D01*
G01X1034500Y360268D02*
X1034158Y359926D01*
G01X1034500Y362152D02*
Y360268D01*
G01X1060150Y355360D02*
X1060694D01*
G01X1053516Y348726D02*
X1060150Y355360D01*
G01X1040356Y348726D02*
X1053516D01*
G01X1039040Y347410D02*
X1040356Y348726D01*
G01X1037379Y347410D02*
X1039040D01*
G01X1034785Y344816D02*
X1037379Y347410D01*
G01X1033969Y344816D02*
X1034785D01*
G01X1060773Y359085D02*
X1061039Y359351D01*
G01X1051885Y359085D02*
X1060773D01*
G01X1050300Y357500D02*
X1051885Y359085D01*
G01X1048400Y357500D02*
X1050300D01*
G01X1046924Y358976D02*
X1048400Y357500D01*
G01X1045076Y358976D02*
X1046924D01*
G01X1043497Y357397D02*
X1045076Y358976D01*
G01X1042276Y357397D02*
X1043497D01*
G01X1040189Y355310D02*
X1042276Y357397D01*
G01X1038409Y355310D02*
X1040189D01*
G01X1036852Y353753D02*
X1038409Y355310D01*
G01X1035383Y353753D02*
X1036852D01*
G01X1060694Y391094D02*
X1066300Y396700D01*
G01X1060694Y390460D02*
Y391094D01*
G01X1042100Y518100D02*
Y528800D01*
G01X1046800Y513400D02*
X1042100Y518100D01*
G01X1048700Y513400D02*
X1046800D01*
G01X1049900Y514600D02*
X1048700Y513400D01*
G01X1052000Y514600D02*
X1049900D01*
G01X1053500Y513100D02*
X1052000Y514600D01*
G01X1054900Y513100D02*
X1053500D01*
G01X1056600Y514800D02*
X1054900Y513100D01*
G01X1058800Y514800D02*
X1056600D01*
G01X1060700Y512900D02*
X1058800Y514800D01*
G01X1062000Y512900D02*
X1060700D01*
G01X1063600Y514500D02*
X1062000Y512900D01*
G01X1065400Y514500D02*
X1063600D01*
G01X1067100Y512800D02*
X1065400Y514500D01*
G01X1069543Y512800D02*
X1067100D01*
G01X1071063Y511280D02*
X1069543Y512800D01*
G01X1071063Y505026D02*
Y511280D01*
G01X1071065Y505024D02*
X1071063Y505026D01*
G01X1061025Y510112D02*
X1061023Y510114D01*
G01X1061025Y505024D02*
Y510112D01*
G01X1044291Y523134D02*
X1044293D01*
G01X1044291Y528930D02*
Y523134D01*
G01X1087795Y585720D02*
X1087797Y585722D01*
G01X1087795Y580624D02*
Y585720D01*
G01X1087797Y580624D02*
X1087795D01*
G01X1042110Y585442D02*
Y590112D01*
G01X1041500Y584832D02*
X1042110Y585442D01*
G01X1041500Y576200D02*
Y584832D01*
G01X1042500Y575200D02*
X1041500Y576200D01*
G01X1042500Y566250D02*
Y575200D01*
G01X1042100Y565850D02*
X1042500Y566250D01*
G01X1042100Y555134D02*
Y565850D01*
G01X1043734Y553500D02*
X1042100Y555134D01*
G01X1071065Y585721D02*
X1071064Y585722D01*
G01X1071065Y580624D02*
Y585721D01*
G01X1042500Y552266D02*
X1043734Y553500D01*
G01X1042500Y547550D02*
Y552266D01*
G01X1042100Y547150D02*
X1042500Y547550D01*
G01X1042100Y537200D02*
Y547150D01*
G01X1042450Y536850D02*
X1042100Y537200D01*
G01X1042450Y529150D02*
Y536850D01*
G01X1042100Y528800D02*
X1042450Y529150D01*
G01X1071065Y547921D02*
Y542824D01*
G01X1071064Y547922D02*
X1071065Y547921D01*
G01X1069149Y549837D02*
X1071064Y547922D01*
G01X1046784Y549837D02*
X1069149D01*
G01X1046000Y550621D02*
X1046784Y549837D01*
G01X1046000Y551234D02*
Y550621D01*
G01X1043734Y553500D02*
X1046000Y551234D01*
G01X1069286Y587500D02*
X1071064Y585722D01*
G01X1046500Y587500D02*
X1069286D01*
G01X1046000Y588000D02*
X1046500Y587500D01*
G01X1046000Y590500D02*
Y588000D01*
G01X1061025Y585721D02*
X1061024Y585722D01*
G01X1061025Y580624D02*
Y585721D01*
G01X1044293Y569489D02*
X1044290Y569492D01*
G01X1044293Y560934D02*
Y569489D01*
G01X1044195Y529026D02*
X1044291Y528930D01*
G01X1071063Y555858D02*
X1071064Y555857D01*
G01X1071063Y560933D02*
Y555858D01*
G01X1071065Y560934D02*
X1071063Y560933D01*
G01X1061025Y547921D02*
X1061024Y547922D01*
G01X1061025Y542824D02*
Y547921D01*
G01X1042110Y590112D02*
X1043699Y591701D01*
G01X1042500Y592900D02*
X1043699Y591701D01*
G01X1042500Y608983D02*
Y592900D01*
G01X1043017Y609500D02*
X1042500Y608983D01*
G01X1045500Y609500D02*
X1043017D01*
G01X1047000Y608000D02*
X1045500Y609500D01*
G01X1048500Y608000D02*
X1047000D01*
G01X1050000Y609500D02*
X1048500Y608000D01*
G01X1052000Y609500D02*
X1050000D01*
G01X1053500Y608000D02*
X1052000Y609500D01*
G01X1055500Y608000D02*
X1053500D01*
G01X1057000Y609500D02*
X1055500Y608000D01*
G01X1059000Y609500D02*
X1057000D01*
G01X1060500Y608000D02*
X1059000Y609500D01*
G01X1061511Y608000D02*
X1060500D01*
G01X1063011Y609500D02*
X1061511Y608000D01*
G01X1065500Y609500D02*
X1063011D01*
G01X1067000Y608000D02*
X1065500Y609500D01*
G01X1068500Y608000D02*
X1067000D01*
G01X1071062Y610562D02*
X1068500Y608000D01*
G01X1071062Y612560D02*
Y610562D01*
G01X1071159Y612657D02*
X1071062Y612560D01*
G01X1074343Y612657D02*
X1071159D01*
G01X1077000Y610000D02*
X1074343Y612657D01*
G01X1078000Y610000D02*
X1077000D01*
G01X1080000Y608000D02*
X1078000Y610000D01*
G01X1082500Y608000D02*
X1080000D01*
G01X1087000Y612500D02*
X1082500Y608000D01*
G01X1088500Y612500D02*
X1087000D01*
G01X1090106Y610894D02*
X1088500Y612500D01*
G01X1093166Y610894D02*
X1090106D01*
G01X1093972Y611700D02*
X1093166Y610894D01*
G01X1095400Y611700D02*
X1093972D01*
G01X1044799Y591701D02*
X1046000Y590500D01*
G01X1043699Y591701D02*
X1044799D01*
G01X1071063Y593658D02*
X1071064Y593657D01*
G01X1071063Y598733D02*
Y593658D01*
G01X1071065Y598734D02*
X1071063Y598733D01*
G01X1044293Y607289D02*
Y598734D01*
G01X1044290Y607292D02*
X1044293Y607289D01*
G01X1105456Y274044D02*
Y278241D01*
G01X1107600Y271900D02*
X1105456Y274044D01*
G01X1155199Y275000D02*
X1157188Y276989D01*
G01X1153501Y275000D02*
X1155199D01*
G01X1151512Y276989D02*
X1153501Y275000D01*
G01X1150251Y276989D02*
X1151512D01*
G01X1148632Y278608D02*
X1150251Y276989D01*
G01X1146585Y278608D02*
X1148632D01*
G01X1144966Y276989D02*
X1146585Y278608D01*
G01X1143788Y276989D02*
X1144966D01*
G01X1141699Y274900D02*
X1143788Y276989D01*
G01X1140001Y274900D02*
X1141699D01*
G01X1137912Y276989D02*
X1140001Y274900D01*
G01X1136711Y276989D02*
X1137912D01*
G01X1135000Y278700D02*
X1136711Y276989D01*
G01X1132949Y278700D02*
X1135000D01*
G01X1131446Y280203D02*
X1132949Y278700D01*
G01X1155232Y278634D02*
X1157181Y280583D01*
G01X1153648Y278634D02*
X1155232D01*
G01X1151582Y280700D02*
X1153648Y278634D01*
G01X1141733Y278585D02*
X1143648Y280500D01*
G01X1140107Y278585D02*
X1141733D01*
G01X1138958Y279734D02*
X1140107Y278585D01*
G01X1156100Y265300D02*
X1156980Y264420D01*
G01X1156100Y265559D02*
Y265300D01*
G01X1154859Y266800D02*
X1156100Y265559D01*
G01X1153600Y266800D02*
X1154859D01*
G01X1152478Y267922D02*
X1153600Y266800D01*
G01X1152478Y269378D02*
Y267922D01*
G01X1151060Y270796D02*
X1152478Y269378D01*
G01X1121891Y284349D02*
X1123256Y282984D01*
G01X1121891Y287054D02*
Y284349D01*
G01X1120600Y288345D02*
X1121891Y287054D01*
G01X1119155Y288345D02*
X1120600D01*
G01X1113000Y294500D02*
X1119155Y288345D01*
G01X1111300Y294500D02*
X1113000D01*
G01X1130017Y280203D02*
X1131446D01*
G01X1128020Y282200D02*
X1130017Y280203D01*
G01X1124040Y282200D02*
X1128020D01*
G01X1123256Y282984D02*
X1124040Y282200D01*
G01X1121993Y292400D02*
X1123769Y290624D01*
G01X1118562Y292400D02*
X1121993D01*
G01X1117351Y293611D02*
X1118562Y292400D01*
G01X1115489Y293611D02*
X1117351D01*
G01X1113174Y295926D02*
X1115489Y293611D01*
G01X1113174Y296226D02*
Y295926D01*
G01X1111300Y298100D02*
X1113174Y296226D01*
G01X1150200Y280700D02*
X1151582D01*
G01X1148746Y282154D02*
X1150200Y280700D01*
G01X1147015Y282154D02*
X1148746D01*
G01X1145361Y280500D02*
X1147015Y282154D01*
G01X1143648Y280500D02*
X1145361D01*
G01X1138958Y280389D02*
Y279734D01*
G01X1138458Y280889D02*
X1138958Y280389D01*
G01X1136091Y280889D02*
X1138458D01*
G01X1134780Y282200D02*
X1136091Y280889D01*
G01X1133500Y282200D02*
X1134780D01*
G01X1131000Y284700D02*
X1133500Y282200D01*
G01X1129420Y284700D02*
X1131000D01*
G01X1128066Y286054D02*
X1129420Y284700D01*
G01X1127421Y286054D02*
X1128066D01*
G01X1125578Y287897D02*
X1127421Y286054D01*
G01X1125578Y288815D02*
Y287897D01*
G01X1123769Y290624D02*
X1125578Y288815D01*
G01X1112564Y317800D02*
X1110300D01*
G01X1114839Y320075D02*
X1112564Y317800D01*
G01X1121664Y296200D02*
X1123747Y298283D01*
G01X1118832Y296200D02*
X1121664D01*
G01X1116832Y298200D02*
X1118832Y296200D01*
G01X1116200Y298200D02*
X1116832D01*
G01X1113300Y301100D02*
X1116200Y298200D01*
G01X1111300Y301100D02*
X1113300D01*
G01X1122200Y340279D02*
Y341388D01*
G01X1123379Y339100D02*
X1122200Y340279D01*
G01X1124601Y339100D02*
X1123379D01*
G01X1126000Y337701D02*
X1124601Y339100D01*
G01X1126000Y336400D02*
Y337701D01*
G01X1125500Y335900D02*
X1126000Y336400D01*
G01X1125500Y334300D02*
Y335900D01*
G01X1126100Y333700D02*
X1125500Y334300D01*
G01X1126100Y332500D02*
Y333700D01*
G01X1125600Y332000D02*
X1126100Y332500D01*
G01X1125600Y330401D02*
Y332000D01*
G01X1126801Y329200D02*
X1125600Y330401D01*
G01X1128100Y329200D02*
X1126801D01*
G01X1129779Y327521D02*
X1128100Y329200D01*
G01X1131699Y327521D02*
X1129779D01*
G01X1132509Y326711D02*
X1131699Y327521D01*
G01X1132804Y326000D02*
X1132509Y326711D01*
G01X1132958Y325628D02*
X1132804Y326000D01*
G01X1132958Y325108D02*
Y325628D01*
G01X1132284Y323480D02*
X1132958Y325108D01*
G01X1132284Y322816D02*
Y323480D01*
G01X1132366Y322734D02*
X1132284Y322816D01*
G01X1132366Y322702D02*
Y322734D01*
G01X1133559Y321509D02*
X1132366Y322702D01*
G01X1134973Y321509D02*
X1133559D01*
G01X1136122Y320360D02*
X1134973Y321509D01*
G01X1136122Y318734D02*
Y320360D01*
G01X1134973Y317585D02*
X1136122Y318734D01*
G01X1133302Y317585D02*
X1134973D01*
G01X1132898Y317181D02*
X1133302Y317585D01*
G01X1132303Y315743D02*
X1132898Y317181D01*
G01X1132303Y315180D02*
Y315743D01*
G01X1132574Y314526D02*
X1132303Y315180D01*
G01X1132574Y312774D02*
Y314526D01*
G01X1132200Y312400D02*
X1132574Y312774D01*
G01X1132200Y311000D02*
Y312400D01*
G01X1132574Y310626D02*
X1132200Y311000D01*
G01X1132574Y308974D02*
Y310626D01*
G01X1132200Y308600D02*
X1132574Y308974D01*
G01X1132200Y307100D02*
Y308600D01*
G01X1132668Y306632D02*
X1132200Y307100D01*
G01X1132668Y305881D02*
Y306632D01*
G01X1132251Y304875D02*
X1132668Y305881D01*
G01X1131302Y303926D02*
X1132251Y304875D01*
G01X1129917Y303926D02*
X1131302D01*
G01X1128144Y302153D02*
X1129917Y303926D01*
G01X1126453Y302153D02*
X1128144D01*
G01X1125100Y300800D02*
X1126453Y302153D01*
G01X1125100Y299636D02*
Y300800D01*
G01X1123747Y298283D02*
X1125100Y299636D01*
G01X1122200Y341388D02*
X1120641Y342947D01*
G01X1096314Y610786D02*
X1095400Y611700D01*
G01X1098514Y610786D02*
X1096314D01*
G01X1100700Y608600D02*
X1098514Y610786D01*
G01X1111800Y608600D02*
X1100700D01*
G01X1112300Y609100D02*
X1111800Y608600D01*
G01X1112300Y613000D02*
Y609100D01*
G01X1116129Y616829D02*
X1112300Y613000D01*
G01X1238579Y616829D02*
X1116129D01*
G01X1216100Y104400D02*
Y106520D01*
G01X1217598Y102902D02*
X1216100Y104400D01*
G01X1233661Y102902D02*
X1217598D01*
G01X1216100Y108302D02*
X1218254Y110456D01*
G01X1216100Y106520D02*
Y108302D01*
G01X1165405Y276646D02*
X1167960D01*
G01X1165393Y276658D02*
X1165405Y276646D01*
G01X1163657Y276658D02*
X1165393D01*
G01X1161899Y274900D02*
X1163657Y276658D01*
G01X1160401Y274900D02*
X1161899D01*
G01X1158312Y276989D02*
X1160401Y274900D01*
G01X1157188Y276989D02*
X1158312D01*
G01X1157850Y260920D02*
X1156980D01*
G01X1159390Y262460D02*
X1157850Y260920D01*
G01X1217277Y226750D02*
X1218771Y225256D01*
G01X1178086Y263009D02*
X1178099Y262996D01*
G01X1173909Y263009D02*
X1178086D01*
G01X1172100Y261200D02*
X1173909Y263009D01*
G01X1170300Y261200D02*
X1172100D01*
G01X1168505Y262995D02*
X1170300Y261200D01*
G01X1167374Y262995D02*
X1168505D01*
G01X1165522Y261143D02*
X1167374Y262995D01*
G01X1172164Y276646D02*
X1174719D01*
G01X1172152Y276634D02*
X1172164Y276646D01*
G01X1170266Y276634D02*
X1172152D01*
G01X1168400Y278500D02*
X1170266Y276634D01*
G01X1166949Y278500D02*
X1168400D01*
G01X1165246Y280203D02*
X1166949Y278500D01*
G01X1162311Y278600D02*
X1163914Y280203D01*
G01X1160300Y278600D02*
X1162311D01*
G01X1158317Y280583D02*
X1160300Y278600D01*
G01X1167960Y250347D02*
Y249347D01*
G01X1166084Y252223D02*
X1167960Y250347D01*
G01X1166084Y253694D02*
Y252223D01*
G01X1166256Y253866D02*
X1166084Y253694D01*
G01X1166256Y256059D02*
Y253866D01*
G01X1165400Y256915D02*
X1166256Y256059D01*
G01X1165400Y257726D02*
Y256915D01*
G01X1167439Y268326D02*
X1164900D01*
G01X1167960Y268847D02*
X1167439Y268326D01*
G01X1157776Y254048D02*
X1157013D01*
G01X1160303Y251521D02*
X1157776Y254048D01*
G01X1162083Y251521D02*
X1160303D01*
G01X1164601Y249003D02*
X1162083Y251521D01*
G01X1165245Y249003D02*
X1164601D01*
G01X1167960Y246288D02*
X1165245Y249003D01*
G01X1167960Y245447D02*
Y246288D01*
G01X1167839Y264826D02*
X1167960Y264947D01*
G01X1164900Y264826D02*
X1167839D01*
G01X1218080Y224000D02*
X1230569D01*
G01X1216380Y225700D02*
X1218080Y224000D01*
G01X1211763Y225700D02*
X1216380D01*
G01X1210027Y226745D02*
G03X1211763Y225700I1736J920D01*
G01X1199100Y226150D02*
X1200472Y227522D01*
G01X1197850Y226150D02*
X1199100D01*
G01X1195850Y228150D02*
X1197850Y226150D01*
G01X1194150Y228150D02*
X1195850D01*
G01X1192600Y229700D02*
X1194150Y228150D01*
G01X1191250Y229700D02*
X1192600D01*
G01X1189350Y231600D02*
X1191250Y229700D01*
G01X1187850Y231600D02*
X1189350D01*
G01X1185950Y233500D02*
X1187850Y231600D01*
G01X1184450Y233500D02*
X1185950D01*
G01X1182350Y235600D02*
X1184450Y233500D01*
G01X1181000Y235600D02*
X1182350D01*
G01X1179100Y237500D02*
X1181000Y235600D01*
G01X1177335Y237500D02*
X1179100D01*
G01X1175385Y239450D02*
X1177335Y237500D01*
G01X1173950Y239450D02*
X1175385D01*
G01X1171339Y242061D02*
X1173950Y239450D01*
G01X1171339Y243496D02*
Y242061D01*
G01X1163914Y280203D02*
X1165246D01*
G01X1157181Y280583D02*
X1158317D01*
G01X1198029Y405171D02*
X1201000Y402200D01*
G01X1198029Y405411D02*
Y405171D01*
G01X1265159Y17001D02*
X1265157Y16999D01*
G01X1265159Y22133D02*
Y17001D01*
G01X1255118Y22133D02*
Y16999D01*
G01X1255120Y22133D02*
X1255118D01*
G01Y4023D02*
Y9157D01*
G01X1255120Y4023D02*
X1255118D01*
G01X1265159Y92601D02*
X1265157Y92599D01*
G01X1265159Y97733D02*
Y92601D01*
G01Y54801D02*
X1265157Y54799D01*
G01X1265159Y59933D02*
Y54801D01*
G01X1255118Y97733D02*
Y92599D01*
G01Y59933D02*
Y54799D01*
G01X1255120Y59933D02*
X1255118D01*
G01Y79623D02*
Y84757D01*
G01X1255120Y79623D02*
X1255118D01*
G01Y41823D02*
Y46957D01*
G01X1255120Y41823D02*
X1255118D01*
G01X1226210Y109162D02*
X1224924Y110448D01*
G01X1228835Y109162D02*
X1226210D01*
G01X1231394Y106910D02*
Y109162D01*
G01X1230948Y106464D02*
X1231394Y106910D01*
G01X1229336Y106464D02*
X1230948D01*
G01X1228835Y106965D02*
X1229336Y106464D01*
G01X1228835Y109162D02*
Y106965D01*
G01X1221300Y106824D02*
X1224924Y110448D01*
G01X1221300Y106600D02*
Y106824D01*
G01X1268050Y105250D02*
X1268600Y104700D01*
G01X1268050Y107670D02*
Y105250D01*
G01Y111670D02*
Y107670D01*
G01X1267441Y136290D02*
X1268401Y137250D01*
G01X1260389Y136290D02*
X1267441D01*
G01X1259964Y135865D02*
X1260389Y136290D01*
G01X1259964Y135864D02*
Y135865D01*
G01X1255800Y131700D02*
X1259964Y135864D01*
G01X1255800Y130700D02*
Y131700D01*
G01X1266774Y140568D02*
X1265828D01*
G01X1268550Y138792D02*
X1266774Y140568D01*
G01X1268550Y137399D02*
Y138792D01*
G01X1268401Y137250D02*
X1268550Y137399D01*
G01X1271550Y111670D02*
Y107918D01*
G01Y104760D02*
X1271490Y104700D01*
G01X1271550Y107918D02*
Y104760D01*
G01X1255120Y97733D02*
X1255118D01*
G01X1275050Y105050D02*
Y107918D01*
G01X1272100Y102100D02*
X1275050Y105050D01*
G01X1271500Y102100D02*
X1272100D01*
G01X1250961Y134700D02*
X1252300D01*
G01X1250078Y133817D02*
X1250961Y134700D01*
G01X1248616Y133817D02*
X1250078D01*
G01X1252300Y134700D02*
Y130700D01*
G01X1271550Y129670D02*
Y125857D01*
G01Y122550D02*
X1271500Y122500D01*
G01X1271550Y125857D02*
Y122550D01*
G01X1230725Y121275D02*
X1231442D01*
G01X1229600Y122400D02*
X1230725Y121275D01*
G01X1229600Y128300D02*
Y122400D01*
G01X1231394Y121227D02*
X1231442Y121275D01*
G01X1231394Y116162D02*
Y121227D01*
G01X1268991Y117373D02*
X1268576Y117788D01*
G01X1271139Y117373D02*
X1268991D01*
G01X1232700Y143419D02*
X1237704Y148423D01*
G01X1232700Y126033D02*
Y143419D01*
G01X1231442Y124775D02*
X1232700Y126033D01*
G01X1246338Y154894D02*
X1244371Y156861D01*
G01X1246338Y132332D02*
Y154894D01*
G01X1248210Y130460D02*
X1246338Y132332D01*
G01X1249025Y130460D02*
X1248210D01*
G01X1268050Y129670D02*
Y125670D01*
G01Y123380D02*
Y125670D01*
G01X1268900Y122530D02*
X1268050Y123380D01*
G01X1268900Y122500D02*
Y122530D01*
G01X1236600Y126100D02*
Y124877D01*
G01X1240000Y129500D02*
X1236600Y126100D01*
G01X1240010Y144242D02*
Y144754D01*
G01X1238323Y142555D02*
X1240010Y144242D01*
G01X1238323Y141120D02*
Y142555D01*
G01X1242463Y136980D02*
X1238323Y141120D01*
G01X1242463Y129207D02*
Y136980D01*
G01X1244929Y126741D02*
X1242463Y129207D01*
G01X1244996Y126741D02*
X1244929D01*
G01X1245385Y126352D02*
X1244996Y126741D01*
G01X1245385Y126285D02*
Y126352D01*
G01X1246904Y124766D02*
X1245385Y126285D01*
G01X1258016Y124766D02*
X1246904D01*
G01X1262920Y129670D02*
X1258016Y124766D01*
G01X1264550Y129670D02*
X1262920D01*
G01X1244025Y137770D02*
X1240022Y141773D01*
G01X1244025Y129899D02*
Y137770D01*
G01X1247733Y126191D02*
X1244025Y129899D01*
G01X1256391Y126191D02*
X1247733D01*
G01X1259371Y129171D02*
X1256391Y126191D01*
G01X1261900Y131700D02*
X1259371Y129171D01*
G01X1274500Y131700D02*
X1261900D01*
G01X1275050Y131150D02*
X1274500Y131700D01*
G01X1275050Y129670D02*
Y131150D01*
G01X1266638Y143788D02*
X1262900Y140050D01*
G01X1269114Y143788D02*
X1266638D01*
G01X1270088Y142814D02*
X1269114Y143788D01*
G01X1270088Y141007D02*
Y142814D01*
G01X1271155Y139940D02*
X1270088Y141007D01*
G01X1275006Y139940D02*
X1271155D01*
G01X1275540Y140474D02*
X1275006Y139940D01*
G01X1275540Y147076D02*
Y140474D01*
G01X1276890Y148426D02*
X1275540Y147076D01*
G01X1277946Y148426D02*
X1276890D01*
G01X1278030Y148510D02*
X1277946Y148426D01*
G01X1256230Y134700D02*
X1255800D01*
G01X1261580Y140050D02*
X1256230Y134700D01*
G01X1262900Y140050D02*
X1261580D01*
G01X1244331Y118640D02*
Y116188D01*
G01X1243693Y119278D02*
X1244331Y118640D01*
G01X1242116Y119278D02*
X1243693D01*
G01X1241772Y118934D02*
X1242116Y119278D01*
G01X1241772Y116188D02*
Y118934D01*
G01X1236001Y105242D02*
X1233661Y102902D01*
G01X1244355Y105242D02*
X1236001D01*
G01X1245866Y106753D02*
X1244355Y105242D01*
G01X1245866Y112285D02*
Y106753D01*
G01X1244331Y113820D02*
X1245866Y112285D01*
G01X1244331Y116188D02*
Y113820D01*
G01X1239213Y107788D02*
Y109188D01*
G01X1238144Y106719D02*
X1239213Y107788D01*
G01X1235462Y106719D02*
X1238144D01*
G01X1233155Y104412D02*
X1235462Y106719D01*
G01X1220589Y104412D02*
X1233155D01*
G01X1219300Y105701D02*
X1220589Y104412D01*
G01X1219300Y108074D02*
Y105701D01*
G01X1221682Y110456D02*
X1219300Y108074D01*
G01X1233953Y114448D02*
X1239213Y109188D01*
G01X1233953Y116162D02*
Y114448D01*
G01X1235165Y128265D02*
Y129710D01*
G01X1233953Y127053D02*
X1235165Y128265D01*
G01X1233953Y116162D02*
Y127053D01*
G01X1240843Y151811D02*
X1243948Y154916D01*
G01X1240843Y148808D02*
Y151811D01*
G01X1233953Y141918D02*
X1240843Y148808D01*
G01X1233953Y131947D02*
Y141918D01*
G01X1235165Y130735D02*
X1233953Y131947D01*
G01X1235165Y129710D02*
Y130735D01*
G01X1238377Y121377D02*
X1236600D01*
G01X1242000Y125000D02*
X1238377Y121377D01*
G01X1236125Y120902D02*
X1236600Y121377D01*
G01X1236125Y114730D02*
Y120902D01*
G01X1238944Y111911D02*
X1236125Y114730D01*
G01X1240672Y111911D02*
X1238944D01*
G01X1241772Y110811D02*
X1240672Y111911D01*
G01X1241772Y109188D02*
Y110811D01*
G01X1257500Y142200D02*
X1259950Y144650D01*
G01X1257500Y142000D02*
Y142200D01*
G01X1268400Y102100D02*
X1268500D01*
G01X1264550Y105950D02*
X1268400Y102100D01*
G01X1264550Y107670D02*
Y105950D01*
G01X1263300Y172440D02*
Y169450D01*
G01X1226866Y207904D02*
X1226867D01*
G01X1226866Y207927D02*
Y207904D01*
G01X1228500Y206293D02*
X1226866Y207927D01*
G01X1228500Y191270D02*
Y206293D01*
G01X1224600Y187370D02*
X1228500Y191270D01*
G01X1224600Y158780D02*
Y187370D01*
G01X1226519Y156861D02*
X1224600Y158780D01*
G01X1244371Y156861D02*
X1226519D01*
G01X1259200Y174900D02*
Y168350D01*
G01X1229700Y204400D02*
X1259200Y174900D01*
G01X1229700Y213043D02*
Y204400D01*
G01X1227200Y215543D02*
X1229700Y213043D01*
G01X1268771Y246671D02*
X1268404Y246304D01*
G01X1271477Y246671D02*
X1268771D01*
G01X1277235Y252429D02*
X1271477Y246671D01*
G01X1280026Y252429D02*
X1277235D01*
G01X1302000Y274403D02*
X1280026Y252429D01*
G01X1270029Y245246D02*
X1263401Y240889D01*
G01X1272445Y245246D02*
X1270029D01*
G01X1274801Y247602D02*
X1272445Y245246D01*
G01X1279393Y247602D02*
X1274801D01*
G01X1259201Y238129D02*
X1263401Y240889D01*
G01X1249737Y234238D02*
X1259201Y238129D01*
G01X1244418Y230742D02*
X1249737Y234238D01*
G01X1231141Y225256D02*
X1244418Y230742D01*
G01X1218771Y225256D02*
X1231141D01*
G01X1279393Y247602D02*
X1281712Y247597D01*
G01X1270478Y243490D02*
X1276337D01*
G01X1279327Y240500D02*
X1276337Y243490D01*
G01X1287500Y240500D02*
X1279327D01*
G01X1280087Y255300D02*
X1287743Y262956D01*
G01X1274100Y255300D02*
X1280087D01*
G01X1271656Y235900D02*
X1269500D01*
G01X1273744Y237988D02*
X1271656Y235900D01*
G01X1277350Y237988D02*
X1273744D01*
G01X1284139Y231199D02*
X1277350Y237988D01*
G01X1256327Y235900D02*
X1269500D01*
G01X1250014Y233313D02*
X1256327Y235900D01*
G01X1246403Y230937D02*
X1250014Y233313D01*
G01X1246397Y230934D02*
X1246403Y230937D01*
G01X1244852Y229919D02*
X1246397Y230934D01*
G01X1230569Y224000D02*
X1244852Y229919D01*
G01X1259010Y477310D02*
X1254000D01*
G01X1260120Y478420D02*
X1259010Y477310D01*
G01X1263600Y478420D02*
X1260120D01*
G01X1248810Y477310D02*
X1248800Y477300D01*
G01X1254000Y477310D02*
X1248810D01*
G01X1248700Y475602D02*
Y473700D01*
G01X1248800Y475702D02*
X1248700Y475602D01*
G01X1248800Y477300D02*
Y475702D01*
G01X1255120Y523134D02*
Y518000D01*
G01X1248610Y497310D02*
X1246300Y495000D01*
G01X1250890Y497310D02*
X1248610D01*
G01X1247842Y491308D02*
X1249193D01*
G01X1246300Y492850D02*
X1247842Y491308D01*
G01X1246300Y495000D02*
Y492850D01*
G01X1265159Y518001D02*
X1265157Y517999D01*
G01X1265159Y523134D02*
Y518001D01*
G01X1263600Y472800D02*
Y475860D01*
G01X1266900Y469500D02*
X1263600Y472800D01*
G01X1251710Y486010D02*
X1249500Y483800D01*
G01X1251710Y491290D02*
Y486010D01*
G01X1250890Y492110D02*
X1251710Y491290D01*
G01X1250890Y493810D02*
Y492110D01*
G01X1249500Y482410D02*
Y483800D01*
G01X1251410Y480500D02*
X1249500Y482410D01*
G01X1258290Y480500D02*
X1251410D01*
G01X1258770Y480980D02*
X1258290Y480500D01*
G01X1263600Y480980D02*
X1258770D01*
G01X1250890Y493810D02*
X1254390D01*
G01X1255120Y510158D02*
Y505024D01*
G01X1242100Y479399D02*
Y484100D01*
G01X1244199Y477300D02*
X1242100Y479399D01*
G01X1245300Y477300D02*
X1244199D01*
G01X1247987Y489400D02*
X1248474Y488913D01*
G01X1244001Y489400D02*
X1247987D01*
G01X1242100Y487499D02*
X1244001Y489400D01*
G01X1242100Y484100D02*
Y487499D01*
G01X1255120Y560934D02*
Y555144D01*
G01Y537034D02*
Y542824D01*
G01Y580624D02*
Y574834D01*
G01X1265159Y555801D02*
X1265157Y555799D01*
G01X1265159Y560934D02*
Y555801D01*
G01X1242586Y620836D02*
X1238579Y616829D01*
G01X1281064Y620836D02*
X1242586D01*
G01X1265159Y593601D02*
X1265157Y593599D01*
G01X1265159Y598734D02*
Y593601D01*
G01X1255120Y598734D02*
Y593600D01*
G01X1298309Y21510D02*
X1297010D01*
G01X1300299Y23500D02*
X1298309Y21510D01*
G01X1301500Y23500D02*
X1300299D01*
G01X1303760Y28900D02*
X1301200D01*
G01X1300600Y29500D02*
X1297000D01*
G01X1301200Y28900D02*
X1300600Y29500D01*
G01X1296910Y29410D02*
X1297000Y29500D01*
G01X1296910Y21610D02*
Y29410D01*
G01X1297010Y21510D02*
X1296910Y21610D01*
G01X1327467Y71085D02*
Y70786D01*
G01X1327892Y71510D02*
X1327467Y71085D01*
G01X1330100Y71510D02*
X1327892D01*
G01X1304670Y78827D02*
X1304685D01*
G01X1304670Y78842D02*
Y78827D01*
G01X1307428Y81600D02*
X1304670Y78842D01*
G01X1313020Y81600D02*
X1307428D01*
G01X1315620Y79000D02*
X1313020Y81600D01*
G01X1344340Y79000D02*
X1315620D01*
G01X1330100Y68000D02*
X1327500D01*
G01X1303634Y40066D02*
X1301100Y42600D01*
G01X1304500Y40066D02*
X1303634D01*
G01X1304500Y39000D02*
Y40066D01*
G01X1303760Y38260D02*
X1304500Y39000D01*
G01X1303760Y35900D02*
Y38260D01*
G01X1306320Y40780D02*
X1304500Y42600D01*
G01X1306320Y35900D02*
Y40780D01*
G01X1303800Y42600D02*
X1304500D01*
G01X1302774Y43626D02*
X1303800Y42600D01*
G01X1302774Y48826D02*
Y43626D01*
G01X1300265Y51335D02*
X1302774Y48826D01*
G01X1296935Y51335D02*
X1300265D01*
G01X1334724Y207692D02*
X1344741Y197675D01*
G01X1334724Y209051D02*
Y207692D01*
G01X1324811Y215811D02*
Y221131D01*
G01X1326675Y213947D02*
X1324811Y215811D01*
G01X1326675Y204108D02*
Y213947D01*
G01X1338433Y192350D02*
X1326675Y204108D01*
G01X1381553Y192350D02*
X1338433D01*
G01X1330074Y217937D02*
Y216500D01*
G01X1330800Y218663D02*
X1330074Y217937D01*
G01X1336561Y208048D02*
X1345509Y199100D01*
G01X1336561Y210013D02*
Y208048D01*
G01X1330074Y216500D02*
X1336561Y210013D01*
G01X1334100Y217326D02*
Y225600D01*
G01X1333274Y216500D02*
X1334100Y217326D01*
G01X1333074Y216500D02*
X1333274D01*
G01X1329324Y207076D02*
X1336100Y200300D01*
G01X1329324Y208951D02*
Y207076D01*
G01X1341551Y194849D02*
X1336100Y200300D01*
G01X1382973Y194849D02*
X1341551D01*
G01X1328221Y214034D02*
Y221827D01*
G01X1327600Y213413D02*
X1328221Y214034D01*
G01X1327600Y205271D02*
Y213413D01*
G01X1339447Y193424D02*
X1327600Y205271D01*
G01X1382382Y193424D02*
X1339447D01*
G01X1335874Y216500D02*
X1336074D01*
G01X1335525Y216849D02*
X1335874Y216500D01*
G01X1335525Y227475D02*
Y216849D01*
G01X1338224Y209051D02*
X1346750Y200525D01*
G01X1326474Y221512D02*
Y216500D01*
G01X1291524Y213524D02*
Y214952D01*
G01X1289000Y211000D02*
X1291524Y213524D01*
G01X1285000Y211000D02*
X1289000D01*
G01X1291524Y214952D02*
X1294500Y217928D01*
G01X1302000Y282300D02*
Y274403D01*
G01X1305700Y260840D02*
X1303040D01*
G01X1306585Y259955D02*
X1305700Y260840D01*
G01X1306585Y258250D02*
Y259955D01*
G01X1303072Y249560D02*
Y252660D01*
G01X1304632Y249560D02*
X1303072D01*
G01X1305790Y248402D02*
X1304632Y249560D01*
G01X1309365Y248402D02*
X1305790D01*
G01X1312950Y251987D02*
X1309365Y248402D01*
G01X1312950Y268188D02*
Y251987D01*
G01X1311175Y269963D02*
X1312950Y268188D01*
G01X1311175Y288975D02*
Y269963D01*
G01X1291810Y233900D02*
X1288800D01*
G01X1293780Y231930D02*
X1291810Y233900D01*
G01X1293780Y228730D02*
Y231930D01*
G01X1294493Y228017D02*
X1293780Y228730D01*
G01X1296679Y228017D02*
X1294493D01*
G01X1303003D02*
X1296679D01*
G01X1307383Y223637D02*
X1303003Y228017D01*
G01X1322305Y223637D02*
X1307383D01*
G01X1324811Y221131D02*
X1322305Y223637D01*
G01X1306860Y264840D02*
X1308400Y263300D01*
G01X1303040Y264840D02*
X1306860D01*
G01X1309600Y257200D02*
X1308200Y255800D01*
G01X1309600Y262100D02*
Y257200D01*
G01X1308400Y263300D02*
X1309600Y262100D01*
G01X1330800Y220450D02*
Y218663D01*
G01X1285809Y243500D02*
X1287500D01*
G01X1281712Y247597D02*
X1285809Y243500D01*
G01X1287500Y237500D02*
Y240500D01*
G01X1293075Y246575D02*
X1294909Y248409D01*
G01X1293075Y242046D02*
Y246575D01*
G01X1296732Y238389D02*
X1293075Y242046D01*
G01X1300410Y238389D02*
X1296732D01*
G01X1310486Y228313D02*
X1300410Y238389D01*
G01X1331387Y228313D02*
X1310486D01*
G01X1334100Y225600D02*
X1331387Y228313D01*
G01X1298421Y248409D02*
X1299572Y249560D01*
G01X1294909Y248409D02*
X1298421D01*
G01X1304567Y245893D02*
X1303171D01*
G01X1305651Y246977D02*
X1304567Y245893D01*
G01X1309956Y246977D02*
X1305651D01*
G01X1314490Y251511D02*
X1309956Y246977D01*
G01X1314490Y268664D02*
Y251511D01*
G01X1312600Y270554D02*
X1314490Y268664D01*
G01X1312600Y287334D02*
Y270554D01*
G01X1299750Y243075D02*
Y241500D01*
G01X1300175Y243500D02*
X1299750Y243075D01*
G01X1302500Y243500D02*
X1300175D01*
G01X1303171Y244171D02*
X1302500Y243500D01*
G01X1303171Y245893D02*
Y244171D01*
G01X1299996Y275209D02*
Y296501D01*
G01X1287743Y262956D02*
X1299996Y275209D01*
G01X1283720Y221617D02*
Y223870D01*
G01X1286337Y219000D02*
X1283720Y221617D01*
G01X1288000Y219000D02*
X1286337D01*
G01X1310200Y252600D02*
X1308130D01*
G01X1310950Y253350D02*
X1310200Y252600D01*
G01X1310950Y255650D02*
Y253350D01*
G01X1304398Y257102D02*
X1303089D01*
G01X1305400Y256100D02*
X1304398Y257102D01*
G01X1305400Y253799D02*
Y256100D01*
G01X1306599Y252600D02*
X1305400Y253799D01*
G01X1308130Y252600D02*
X1306599D01*
G01X1293163Y237500D02*
X1291000D01*
G01X1295663Y235000D02*
X1293163Y237500D01*
G01X1299040Y235000D02*
X1295663D01*
G01X1308653Y225387D02*
X1299040Y235000D01*
G01X1324661Y225387D02*
X1308653D01*
G01X1328221Y221827D02*
X1324661Y225387D01*
G01X1298580Y246984D02*
X1299671Y245893D01*
G01X1296286Y246984D02*
X1298580D01*
G01X1294500Y245198D02*
X1296286Y246984D01*
G01X1294500Y242637D02*
Y245198D01*
G01X1297303Y239834D02*
X1294500Y242637D01*
G01X1300981Y239834D02*
X1297303D01*
G01X1311077Y229738D02*
X1300981Y239834D01*
G01X1333262Y229738D02*
X1311077D01*
G01X1334600Y228400D02*
X1333262Y229738D01*
G01X1334600Y228400D02*
X1335525Y227475D01*
G01X1323524Y224462D02*
X1326474Y221512D01*
G01X1308057Y224462D02*
X1323524D01*
G01X1301825Y230694D02*
X1308057Y224462D01*
G01X1297632Y230694D02*
X1301825D01*
G01X1292606Y235720D02*
X1297632Y230694D01*
G01X1287609Y235720D02*
X1292606D01*
G01X1287137Y235248D02*
X1287609Y235720D01*
G01X1287137Y233211D02*
Y235248D01*
G01X1287670Y232678D02*
X1287137Y233211D01*
G01X1287670Y231199D02*
Y232678D01*
G01Y231199D02*
X1284139D01*
G01X1291500Y219000D02*
X1294500D01*
G01Y217928D02*
Y219000D01*
G01X1291500Y220210D02*
Y219000D01*
G01X1289679Y222031D02*
X1291500Y220210D01*
G01X1289679Y222899D02*
Y222031D01*
G01X1305950Y300662D02*
Y306611D01*
G01X1304358Y299070D02*
X1305950Y300662D01*
G01X1304358Y297674D02*
Y299070D01*
G01X1304712Y297320D02*
X1304358Y297674D01*
G01X1304712Y295819D02*
Y297320D01*
G01X1302000Y293107D02*
X1304712Y295819D01*
G01X1302000Y282300D02*
Y293107D01*
G01X1315177Y299283D02*
Y297177D01*
G01X1313000Y301460D02*
X1315177Y299283D01*
G01X1313000Y307100D02*
Y301460D01*
G01X1321375Y315475D02*
X1313000Y307100D01*
G01X1321375Y320825D02*
Y315475D01*
G01X1320900Y321300D02*
X1321375Y320825D01*
G01X1315177Y292977D02*
X1311175Y288975D01*
G01X1315177Y297177D02*
Y292977D01*
G01X1335250Y339450D02*
Y341350D01*
G01X1337900Y336800D02*
X1335250Y339450D01*
G01X1339800Y336800D02*
X1337900D01*
G01X1341522D02*
X1343300Y338578D01*
G01X1339800Y336800D02*
X1341522D01*
G01X1317144Y291878D02*
X1315183Y289917D01*
G01X1317144Y299404D02*
Y291878D01*
G01X1314500Y302048D02*
X1317144Y299404D01*
G01X1314500Y306200D02*
Y302048D01*
G01X1322800Y314500D02*
X1314500Y306200D01*
G01X1322800Y318800D02*
Y314500D01*
G01X1323750Y319750D02*
X1322800Y318800D01*
G01X1315183Y289917D02*
X1312600Y287334D01*
G01X1316628Y341028D02*
X1317834Y342234D01*
G01X1316628Y313144D02*
Y341028D01*
G01X1311237Y307753D02*
X1316628Y313144D01*
G01X1311237Y297215D02*
Y307753D01*
G01X1306367Y292345D02*
X1311237Y297215D01*
G01X1303866Y292345D02*
X1306367D01*
G01X1315035Y313965D02*
Y343201D01*
G01X1309812Y308742D02*
X1315035Y313965D01*
G01X1309812Y298567D02*
Y308742D01*
G01X1305558Y294313D02*
X1309812Y298567D01*
G01X1304277Y307649D02*
X1305873Y309245D01*
G01X1304277Y303877D02*
Y307649D01*
G01X1301447Y301047D02*
X1304277Y303877D01*
G01X1301447Y297952D02*
Y301047D01*
G01X1299996Y296501D02*
X1301447Y297952D01*
G01X1322460Y333930D02*
X1327400D01*
G01X1322430Y333960D02*
X1322460Y333930D01*
G01X1327400Y327195D02*
Y333930D01*
G01Y315587D02*
Y327195D01*
G01X1325062Y313249D02*
X1327400Y315587D01*
G01X1325062Y298162D02*
Y313249D01*
G01X1321600Y294700D02*
X1325062Y298162D01*
G01X1313442Y314826D02*
Y344198D01*
G01X1308039Y309423D02*
X1313442Y314826D01*
G01X1308039Y300004D02*
Y309423D01*
G01X1306290Y298255D02*
X1308039Y300004D01*
G01X1336600Y323400D02*
X1344140D01*
G01X1338700Y285000D02*
Y284700D01*
G01X1330257Y293443D02*
X1338700Y285000D01*
G01X1326700Y297000D02*
X1330257Y293443D01*
G01X1326700Y312432D02*
Y297000D01*
G01X1329147Y314879D02*
X1326700Y312432D01*
G01X1329147Y320207D02*
Y314879D01*
G01X1334540Y325600D02*
X1329147Y320207D01*
G01X1341500Y325600D02*
X1334540D01*
G01X1341520Y344840D02*
X1342060Y344300D01*
G01X1341520Y346208D02*
Y344840D01*
G01X1340928Y346800D02*
X1341520Y346208D01*
G01X1339800Y346800D02*
X1340928D01*
G01X1339800Y349553D02*
Y346800D01*
G01X1339597Y349756D02*
X1339800Y349553D01*
G01X1335250Y341350D02*
Y344250D01*
G01X1325700Y350100D02*
X1330100D01*
G01X1317834Y342234D02*
X1325700Y350100D01*
G01X1330766Y351734D02*
X1332600Y349900D01*
G01X1323568Y351734D02*
X1330766D01*
G01X1321068Y349234D02*
X1323568Y351734D01*
G01X1315035Y343201D02*
X1321068Y349234D01*
G01X1341172Y351591D02*
X1343300Y349463D01*
G01X1337364Y351591D02*
X1341172D01*
G01X1336886Y351113D02*
X1337364Y351591D01*
G01X1315496Y354100D02*
Y361190D01*
G01Y346252D02*
Y354100D01*
G01X1313442Y344198D02*
X1315496Y346252D01*
G01X1289601Y481099D02*
X1290500Y480200D01*
G01X1288349Y481099D02*
X1289601D01*
G01X1285670Y478420D02*
X1288349Y481099D01*
G01X1281600Y478420D02*
X1285670D01*
G01X1287900Y482700D02*
X1290500D01*
G01X1286180Y480980D02*
X1287900Y482700D01*
G01X1281600Y480980D02*
X1286180D01*
G01X1340500Y542900D02*
X1368608D01*
G01X1338058Y540458D02*
X1340500Y542900D01*
G01X1323268Y540458D02*
X1338058D01*
G01X1318143Y545583D02*
X1323268Y540458D01*
G01X1296617Y545583D02*
X1318143D01*
G01X1294127Y548073D02*
X1296617Y545583D01*
G01X1294127Y555523D02*
Y548073D01*
G01X1290900Y558750D02*
X1294127Y555523D01*
G01X1290900Y563300D02*
Y558750D01*
G01X1336400Y544500D02*
X1363192D01*
G01X1334398Y542498D02*
X1336400Y544500D01*
G01X1323441Y542498D02*
X1334398D01*
G01X1319131Y546808D02*
X1323441Y542498D01*
G01X1297685Y546808D02*
X1319131D01*
G01X1295574Y548919D02*
X1297685Y546808D01*
G01X1295574Y575124D02*
Y548919D01*
G01X1293746Y576952D02*
X1295574Y575124D01*
G01X1292190Y576952D02*
X1293746D01*
G01X1293078Y578962D02*
X1290292D01*
G01X1296599Y575441D02*
X1293078Y578962D01*
G01X1296599Y549344D02*
Y575441D01*
G01X1298110Y547833D02*
X1296599Y549344D01*
G01X1319556Y547833D02*
X1298110D01*
G01X1323866Y543523D02*
X1319556Y547833D01*
G01X1333923Y543523D02*
X1323866D01*
G01X1335925Y545525D02*
X1333923Y543523D01*
G01X1362811Y545525D02*
X1335925D01*
G01X1286304Y615596D02*
X1281064Y620836D01*
G01X1296295Y615596D02*
X1286304D01*
G01X1401800Y8300D02*
X1405899D01*
G01X1400100Y10000D02*
X1401800Y8300D01*
G01X1403475Y10875D02*
X1402600Y10000D01*
G01X1403475Y17198D02*
Y10875D01*
G01X1410007Y23730D02*
X1403475Y17198D01*
G01X1347500Y82160D02*
X1344340Y79000D01*
G01X1347500Y83000D02*
Y82160D01*
G01X1394614Y155225D02*
Y179289D01*
G01X1398451Y151388D02*
X1394614Y155225D01*
G01X1404562Y151388D02*
X1398451D01*
G01X1402809Y121706D02*
X1429973D01*
G01X1402808Y121705D02*
X1402809Y121706D01*
G01X1402042Y121705D02*
X1402808D01*
G01X1401771Y121976D02*
X1402042Y121705D01*
G01X1400776Y121976D02*
X1401771D01*
G01X1400300Y121500D02*
X1400776Y121976D01*
G01X1397500Y119800D02*
X1396780Y119080D01*
G01X1400952Y119800D02*
X1397500D01*
G01X1402015Y120863D02*
X1400952Y119800D01*
G01X1427945Y120863D02*
X1402015D01*
G01X1399537Y154163D02*
X1397413Y156287D01*
G01X1404342Y154163D02*
X1399537D01*
G01X1402425Y122631D02*
X1432458D01*
G01X1401200Y123856D02*
X1402425Y122631D01*
G01X1401200Y124300D02*
Y123856D01*
G01X1395988Y155408D02*
Y179818D01*
G01X1398658Y152738D02*
X1395988Y155408D01*
G01X1404933Y152738D02*
X1398658D01*
G01X1403400Y203500D02*
Y204766D01*
G01X1406050Y200850D02*
X1403400Y203500D01*
G01X1400983Y214175D02*
X1409001D01*
G01X1399248Y215910D02*
X1400983Y214175D01*
G01X1397080Y215910D02*
X1399248D01*
G01X1396933Y215763D02*
X1397080Y215910D01*
G01X1384905Y197675D02*
X1406956Y175624D01*
G01X1344741Y197675D02*
X1384905D01*
G01X1394614Y179289D02*
X1381553Y192350D01*
G01X1393500Y213250D02*
X1409385D01*
G01X1390650D02*
X1393500D01*
G01X1386500Y217400D02*
X1390650Y213250D01*
G01X1378673Y217400D02*
X1386500D01*
G01X1370489Y209216D02*
X1378673Y217400D01*
G01X1367789Y209216D02*
X1370489D01*
G01X1385496Y199100D02*
X1408381Y176215D01*
G01X1345509Y199100D02*
X1385496D01*
G01X1344462Y205530D02*
Y209272D01*
G01X1348542Y201450D02*
X1344462Y205530D01*
G01X1387699Y201450D02*
X1348542D01*
G01X1410731Y178418D02*
X1387699Y201450D01*
G01X1403208Y165561D02*
X1406131Y162638D01*
G01X1402020Y165561D02*
X1403208D01*
G01X1397413Y180409D02*
X1382973Y194849D01*
G01X1397413Y156287D02*
Y180409D01*
G01X1402870Y207918D02*
X1411950Y198838D01*
G01X1395988Y179818D02*
X1382382Y193424D01*
G01X1386380Y200525D02*
X1409806Y177099D01*
G01X1346750Y200525D02*
X1386380D01*
G01X1390983Y268740D02*
X1377650Y282073D01*
G01X1395655Y268740D02*
X1390983D01*
G01X1412769Y251626D02*
X1395655Y268740D01*
G01X1395737Y276596D02*
Y283959D01*
G01X1418219Y254114D02*
X1395737Y276596D01*
G01X1394812Y276212D02*
Y284343D01*
G01X1417294Y253730D02*
X1394812Y276212D01*
G01X1391367Y269665D02*
X1378575Y282457D01*
G01X1396039Y269665D02*
X1391367D01*
G01X1413694Y252010D02*
X1396039Y269665D01*
G01X1398926Y274716D02*
Y281582D01*
G01X1419144Y254498D02*
X1398926Y274716D01*
G01X1393887Y275828D02*
X1416369Y253346D01*
G01X1393887Y284727D02*
Y275828D01*
G01X1392962Y275444D02*
Y284273D01*
G01X1415444Y252962D02*
X1392962Y275444D01*
G01X1409200Y271800D02*
X1402918Y278082D01*
G01X1402220Y278780D02*
X1402918Y278082D01*
G01X1402220Y283894D02*
Y278780D01*
G01X1390800Y279000D02*
X1389350Y280450D01*
G01X1400821Y277079D02*
X1407200Y270700D01*
G01X1400821Y282039D02*
Y277079D01*
G01X1414519Y252352D02*
X1386470Y280401D01*
G01X1395271Y290487D02*
X1422548D01*
G01X1393684Y288900D02*
X1395271Y290487D01*
G01X1392657Y288900D02*
X1393684D01*
G01X1390500Y289700D02*
X1389350D01*
G01X1391300Y288900D02*
X1390500Y289700D01*
G01X1392657Y288900D02*
X1391300D01*
G01X1363513Y333362D02*
Y334650D01*
G01X1362503Y332352D02*
X1363513Y333362D01*
G01X1362503Y328074D02*
Y332352D01*
G01X1365763Y324814D02*
X1362503Y328074D01*
G01X1365763Y324535D02*
Y324814D01*
G01X1365769Y324529D02*
X1365763Y324535D01*
G01X1365769Y323031D02*
Y324529D01*
G01X1367200Y321600D02*
X1365769Y323031D01*
G01X1388453Y293203D02*
X1388750Y293500D01*
G01X1383344Y293203D02*
X1388453D01*
G01X1377650Y287509D02*
X1383344Y293203D01*
G01X1377650Y282073D02*
Y287509D01*
G01X1397464Y285686D02*
X1428593D01*
G01X1395737Y283959D02*
X1397464Y285686D01*
G01X1397080Y286611D02*
X1426458D01*
G01X1394812Y284343D02*
X1397080Y286611D01*
G01X1355300Y322911D02*
Y321675D01*
G01X1353500Y324711D02*
X1355300Y322911D01*
G01X1353500Y325500D02*
Y324711D01*
G01X1394679Y292011D02*
X1422252D01*
G01X1394218Y291550D02*
X1394679Y292011D01*
G01X1383000Y291550D02*
X1394218D01*
G01X1378575Y287125D02*
X1383000Y291550D01*
G01X1378575Y282457D02*
Y287125D01*
G01X1392814Y292936D02*
X1421329D01*
G01X1392250Y293500D02*
X1392814Y292936D01*
G01X1382090Y283600D02*
X1385850D01*
G01X1381431Y284259D02*
X1382090Y283600D01*
G01X1396696Y287536D02*
X1393887Y284727D01*
G01X1424590Y287536D02*
X1396696D01*
G01X1396312Y288461D02*
X1424106D01*
G01X1392961Y285110D02*
X1396312Y288461D01*
G01X1392961Y284274D02*
Y285110D01*
G01X1392962Y284273D02*
X1392961Y284274D01*
G01X1402092Y284022D02*
X1402220Y283894D01*
G01X1343300Y338578D02*
Y340800D01*
G01X1345000Y332700D02*
X1350200D01*
G01X1350250D02*
X1350200D01*
G01X1352600Y335050D02*
X1350250Y332700D01*
G01X1352600Y336500D02*
Y335050D01*
G01X1353313Y337213D02*
X1352600Y336500D01*
G01X1354650Y337213D02*
X1353313D01*
G01X1353500Y329000D02*
X1357000D01*
G01X1350687Y329687D02*
X1350000Y329000D01*
G01X1352155Y329687D02*
X1350687D01*
G01X1352842Y329000D02*
X1352155Y329687D01*
G01X1353500Y329000D02*
X1352842D01*
G01X1351729Y322380D02*
X1352285Y321824D01*
G01X1351729Y327937D02*
Y322380D01*
G01X1350666Y329000D02*
X1351729Y327937D01*
G01X1350000Y329000D02*
X1350666D01*
G01X1357000Y331700D02*
Y329000D01*
G01X1358788Y333488D02*
X1357000Y331700D01*
G01X1358788Y334650D02*
Y333488D01*
G01X1389350Y286700D02*
Y283600D01*
G01X1396027Y289485D02*
X1423577D01*
G01X1393242Y286700D02*
X1396027Y289485D01*
G01X1389350Y286700D02*
X1393242D01*
G01X1389350Y280450D02*
Y283600D01*
G01X1398837Y284023D02*
X1400821Y282039D01*
G01X1398347Y284023D02*
X1398837D01*
G01X1361700Y325800D02*
X1361558Y325942D01*
G01X1363468Y325800D02*
X1361700D01*
G01X1364838Y324430D02*
X1363468Y325800D01*
G01X1364838Y322738D02*
Y324430D01*
G01X1363700Y321600D02*
X1364838Y322738D01*
G01X1361938Y333386D02*
Y334650D01*
G01X1361400Y332848D02*
X1361938Y333386D01*
G01X1361400Y326100D02*
Y332848D01*
G01X1361558Y325942D02*
X1361400Y326100D01*
G01X1347099Y329100D02*
X1345000D01*
G01X1348662Y330663D02*
X1347099Y329100D01*
G01X1353947Y330663D02*
X1348662D01*
G01X1357213Y333929D02*
X1353947Y330663D01*
G01X1357213Y334650D02*
Y333929D01*
G01X1345000Y325600D02*
Y329100D01*
G01Y324260D02*
Y325600D01*
G01X1344140Y323400D02*
X1345000Y324260D01*
G01X1380416Y286700D02*
X1385850D01*
G01X1379400Y285684D02*
X1380416Y286700D01*
G01X1379400Y282799D02*
Y285684D01*
G01X1381799Y280400D02*
X1379400Y282799D01*
G01X1385787Y280400D02*
X1381799D01*
G01X1385788Y280401D02*
X1385787Y280400D01*
G01X1386470Y280401D02*
X1385788D01*
G01X1385850Y286700D02*
Y289700D01*
G01X1384350Y362150D02*
X1386400D01*
G01X1381780Y359580D02*
X1384350Y362150D01*
G01X1381780Y356848D02*
Y359580D01*
G01X1380097Y356848D02*
X1376027Y352778D01*
G01X1381780Y356848D02*
X1380097D01*
G01X1342060Y344300D02*
X1343300D01*
G01Y349463D02*
Y347800D01*
G01X1346800D02*
X1349700D01*
G01X1388360Y460100D02*
X1380260Y468200D01*
G01X1390400Y460100D02*
X1388360D01*
G01X1392500Y458000D02*
X1390400Y460100D01*
G01X1392500Y451000D02*
Y458000D01*
G01X1389900Y448400D02*
X1392500Y451000D01*
G01X1389900Y447400D02*
Y448400D01*
G01X1369251Y464649D02*
X1355160Y478740D01*
G01X1371321Y464649D02*
X1369251D01*
G01X1371322Y464650D02*
X1371321Y464649D01*
G01X1377090Y464650D02*
X1371322D01*
G01X1383000Y458740D02*
X1377090Y464650D01*
G01X1383000Y446500D02*
Y458740D01*
G01X1383850Y445650D02*
X1383000Y446500D01*
G01X1386600Y445650D02*
X1383850D01*
G01X1390155Y442095D02*
X1386600Y445650D01*
G01X1390294Y442095D02*
X1390155D01*
G01X1395075Y437314D02*
X1390294Y442095D01*
G01X1395075Y437175D02*
Y437314D01*
G01X1395100Y437150D02*
X1395075Y437175D01*
G01X1395100Y432500D02*
Y437150D01*
G01X1395227Y424900D02*
X1407345D01*
G01X1393150Y426977D02*
X1395227Y424900D01*
G01X1393150Y436516D02*
Y426977D01*
G01X1389496Y440170D02*
X1393150Y436516D01*
G01X1384210Y440170D02*
X1389496D01*
G01X1383060Y441320D02*
X1384210Y440170D01*
G01X1383060Y443390D02*
Y441320D01*
G01X1381046Y445404D02*
X1383060Y443390D01*
G01X1379844Y445404D02*
X1381046D01*
G01X1377800Y447448D02*
X1379844Y445404D01*
G01X1377800Y453977D02*
Y447448D01*
G01X1375777Y456000D02*
X1377800Y453977D01*
G01X1368500Y456000D02*
X1375777D01*
G01X1367138Y457362D02*
X1368500Y456000D01*
G01X1367138Y464039D02*
Y457362D01*
G01X1352650Y478527D02*
X1367138Y464039D01*
G01X1395350Y427500D02*
X1395100D01*
G01X1397150Y429300D02*
X1395350Y427500D01*
G01X1397150Y437750D02*
Y429300D01*
G01X1387500Y447400D02*
X1397150Y437750D01*
G01X1387500Y456751D02*
Y447400D01*
G01X1377826Y466425D02*
X1387500Y456751D01*
G01X1364310Y502000D02*
X1404950D01*
G01X1358710Y496400D02*
X1364310Y502000D01*
G01X1358710Y480261D02*
Y496400D01*
G01X1370771Y468200D02*
X1358710Y480261D01*
G01X1380260Y468200D02*
X1370771D01*
G01X1403828Y511528D02*
X1402950Y510650D01*
G01X1403430Y505550D02*
X1413530Y515650D01*
G01X1362838Y505550D02*
X1403430D01*
G01X1355160Y497872D02*
X1362838Y505550D01*
G01X1355160Y478740D02*
Y497872D01*
G01X1352650Y498550D02*
Y478527D01*
G01X1361684Y507584D02*
X1352650Y498550D01*
G01X1390984Y507584D02*
X1361684D01*
G01X1392450Y509050D02*
X1390984Y507584D01*
G01X1392450Y526292D02*
Y509050D01*
G01X1388500Y530242D02*
X1392450Y526292D01*
G01X1369986Y466425D02*
X1377826D01*
G01X1356935Y479476D02*
X1369986Y466425D01*
G01X1356935Y497136D02*
Y479476D01*
G01X1363574Y503775D02*
X1356935Y497136D01*
G01X1404166Y503775D02*
X1363574D01*
G01X1404296Y521500D02*
X1403027Y520231D01*
G01X1388257Y546990D02*
X1390595Y549328D01*
G01X1372698Y546990D02*
X1388257D01*
G01X1368608Y542900D02*
X1372698Y546990D01*
G01X1388500Y543693D02*
Y530242D01*
G01X1387907Y544286D02*
X1388500Y543693D01*
G01X1364312Y547238D02*
X1365028Y547954D01*
G01X1364312Y545620D02*
Y547238D01*
G01X1363192Y544500D02*
X1364312Y545620D01*
G01X1363352Y546066D02*
X1362811Y545525D01*
G01X1363352Y547130D02*
Y546066D01*
G01X1362528Y547954D02*
X1363352Y547130D01*
G01X1414900Y15600D02*
X1413800Y16700D01*
G01X1414900Y14318D02*
Y15600D01*
G01X1413721Y13139D02*
X1414900Y14318D01*
G01X1462000Y-5000D02*
X1465581Y-1419D01*
G01X1452017Y12225D02*
Y16800D01*
G01X1445971Y6179D02*
X1452017Y12225D01*
G01X1445971Y-5D02*
Y6179D01*
G01X1447391Y-1425D02*
X1445971Y-5D01*
G01X1447391Y-6891D02*
Y-1425D01*
G01X1449800Y-9300D02*
X1447391Y-6891D01*
G01X1454100Y-9300D02*
X1449800D01*
G01X1457000Y-12200D02*
X1454100Y-9300D01*
G01X1457000Y-16612D02*
Y-12200D01*
G01X1459700Y-19312D02*
X1457000Y-16612D01*
G01X1487688Y-19312D02*
X1459700D01*
G01X1448600Y20217D02*
Y21050D01*
G01X1452017Y16800D02*
X1448600Y20217D01*
G01X1409200Y20200D02*
X1410800D01*
G01X1405400Y16400D02*
X1409200Y20200D01*
G01X1405400Y12400D02*
Y16400D01*
G01X1406900Y10900D02*
X1405400Y12400D01*
G01X1406900Y9301D02*
Y10900D01*
G01X1405899Y8300D02*
X1406900Y9301D01*
G01X1454800Y17850D02*
X1451600Y21050D01*
G01X1454800Y10735D02*
Y17850D01*
G01X1457890Y7645D02*
X1454800Y10735D01*
G01X1457890Y890D02*
Y7645D01*
G01X1452000Y-5000D02*
X1457890Y890D01*
G01X1416800Y22330D02*
Y20200D01*
G01X1415400Y23730D02*
X1416800Y22330D01*
G01X1415400Y23730D02*
X1410007D01*
G01X1415725Y15625D02*
X1416800Y16700D01*
G01X1415725Y14285D02*
Y15625D01*
G01X1416871Y13139D02*
X1415725Y14285D01*
G01X1416800Y16700D02*
X1421400D01*
G01X1408299D02*
X1410800D01*
G01X1407422Y15823D02*
X1408299Y16700D01*
G01X1407422Y13139D02*
Y15823D01*
G01X1457600Y-10600D02*
X1462000Y-15000D01*
G01X1457600Y-567D02*
Y-10600D01*
G01X1458715Y548D02*
X1457600Y-567D01*
G01X1458715Y7987D02*
Y548D01*
G01X1455900Y10802D02*
X1458715Y7987D01*
G01X1455900Y15000D02*
Y10802D01*
G01X1457674Y16774D02*
X1455900Y15000D01*
G01X1455650Y21050D02*
X1455100D01*
G01X1457674Y19026D02*
X1455650Y21050D01*
G01X1457674Y16774D02*
Y19026D01*
G01X1404300Y10800D02*
X1405100Y10000D01*
G01X1404300Y16856D02*
Y10800D01*
G01X1410144Y22700D02*
X1404300Y16856D01*
G01X1413375Y22700D02*
X1410144D01*
G01X1413800Y22275D02*
X1413375Y22700D01*
G01X1413800Y20200D02*
Y22275D01*
G01X1463115Y20750D02*
X1464500D01*
G01X1455865Y28000D02*
X1463115Y20750D01*
G01X1448100Y28000D02*
X1455865D01*
G01X1446600Y26500D02*
X1448100Y28000D01*
G01X1446600Y18601D02*
Y26500D01*
G01X1450100Y15101D02*
X1446600Y18601D01*
G01X1450100Y11475D02*
Y15101D01*
G01X1444632Y6007D02*
X1450100Y11475D01*
G01X1444632Y167D02*
Y6007D01*
G01X1446566Y-1767D02*
X1444632Y167D01*
G01X1446566Y-9566D02*
Y-1767D01*
G01X1452000Y-15000D02*
X1446566Y-9566D01*
G01X1415902Y46412D02*
X1416837Y45477D01*
G01X1414091Y46412D02*
X1415902D01*
G01X1420337Y45477D02*
Y48377D01*
G01X1456790Y86840D02*
X1453700Y83750D01*
G01X1456790Y87112D02*
Y86840D01*
G01X1451227Y141261D02*
X1451228D01*
G01X1451227Y141289D02*
Y141261D01*
G01X1449167Y139229D02*
X1451227Y141289D01*
G01X1447391Y139229D02*
X1449167D01*
G01X1455839Y94639D02*
X1453809D01*
G01X1457694Y96494D02*
X1455839Y94639D01*
G01X1440142Y122188D02*
X1465472D01*
G01X1406956Y155374D02*
X1440142Y122188D01*
G01X1406956Y175624D02*
Y155374D01*
G01X1429044Y123556D02*
X1428000Y124600D01*
G01X1432842Y123556D02*
X1429044D01*
G01X1438310Y118088D02*
X1432842Y123556D01*
G01X1462115Y118088D02*
X1438310D01*
G01X1471496Y108707D02*
X1462115Y118088D01*
G01X1427025Y128925D02*
X1404562Y151388D01*
G01X1427025Y125575D02*
Y128925D01*
G01X1428000Y124600D02*
X1427025Y125575D01*
G01X1458850Y146010D02*
X1460354D01*
G01X1451590Y138750D02*
X1458850Y146010D01*
G01X1429973Y121706D02*
X1434581Y117098D01*
G01X1462307Y115129D02*
X1470579Y106857D01*
G01X1436550Y115129D02*
X1462307D01*
G01X1434581Y117098D02*
X1436550Y115129D01*
G01X1429863Y151419D02*
X1433500D01*
G01X1419511Y161771D02*
X1429863Y151419D01*
G01X1447281Y151600D02*
X1451950Y156269D01*
G01X1446808Y151600D02*
X1447281D01*
G01X1446795Y151587D02*
X1446808Y151600D01*
G01X1444986Y151587D02*
X1446795D01*
G01X1444818Y151419D02*
X1444986Y151587D01*
G01X1433500Y151419D02*
X1444818D01*
G01X1441233Y123113D02*
X1469213D01*
G01X1408381Y155965D02*
X1441233Y123113D01*
G01X1408381Y176215D02*
Y155965D01*
G01X1446576Y153300D02*
X1445500D01*
G01X1450250Y156974D02*
X1446576Y153300D01*
G01X1444500Y126600D02*
X1466877D01*
G01X1441071D02*
X1410731Y156940D01*
G01X1444500Y126600D02*
X1441071D01*
G01X1453232Y108500D02*
X1452232Y109500D01*
G01X1457000Y108500D02*
X1453232D01*
G01X1463474Y121363D02*
X1469808Y115029D01*
G01X1439800Y121363D02*
X1463474D01*
G01X1406131Y155032D02*
X1439800Y121363D01*
G01X1406131Y162638D02*
Y155032D01*
G01X1434504Y114304D02*
X1427945Y120863D01*
G01X1461748Y114304D02*
X1434504D01*
G01X1470020Y106032D02*
X1461748Y114304D01*
G01X1463017Y142849D02*
X1465428Y140438D01*
G01X1463017Y147790D02*
Y142849D01*
G01X1462238Y148569D02*
X1463017Y147790D01*
G01X1460354Y148569D02*
X1462238D01*
G01X1404343Y154164D02*
X1404342Y154163D01*
G01X1405523Y154164D02*
X1404343D01*
G01X1405524Y154163D02*
X1405523Y154164D01*
G01X1405560Y154163D02*
X1405524D01*
G01X1439285Y120438D02*
X1405560Y154163D01*
G01X1463090Y120438D02*
X1439285D01*
G01X1469439Y114089D02*
X1463090Y120438D01*
G01X1457479Y137837D02*
X1477203D01*
G01X1454550Y134908D02*
X1457479Y137837D01*
G01X1442802Y134908D02*
X1454550D01*
G01X1440700Y137010D02*
X1442802Y134908D01*
G01X1440700Y138900D02*
Y137010D01*
G01X1439451Y140149D02*
X1440700Y138900D01*
G01X1437561Y140149D02*
X1416957Y160753D01*
G01X1439451Y140149D02*
X1437561D01*
G01X1466144Y134244D02*
X1464800Y132900D01*
G01X1463036Y131136D02*
X1464800Y132900D01*
G01X1441764Y131136D02*
X1463036D01*
G01X1413557Y159343D02*
X1441764Y131136D01*
G01X1461731Y117163D02*
X1471113Y107781D01*
G01X1437926Y117163D02*
X1461731D01*
G01X1432458Y122631D02*
X1437926Y117163D01*
G01X1462132Y157468D02*
X1467354Y152246D01*
G01X1433190Y124481D02*
X1404933Y152738D01*
G01X1433226Y124481D02*
X1433190D01*
G01X1438694Y119013D02*
X1433226Y124481D01*
G01X1462499Y119013D02*
X1438694D01*
G01X1471142Y110370D02*
X1462499Y119013D01*
G01X1459199Y136137D02*
X1457572Y134510D01*
G01X1477908Y136137D02*
X1459199D01*
G01X1456094Y133032D02*
X1457572Y134510D01*
G01X1442273Y133032D02*
X1456094D01*
G01X1415257Y160048D02*
X1442273Y133032D01*
G01X1450166Y142729D02*
X1451198Y143761D01*
G01X1447391Y142729D02*
X1450166D01*
G01X1445271D02*
X1441600Y146400D01*
G01X1447391Y142729D02*
X1445271D01*
G01X1442324Y124038D02*
X1468829D01*
G01X1409806Y156556D02*
X1442324Y124038D01*
G01X1455851Y139513D02*
X1477496D01*
G01X1453142Y136804D02*
X1455851Y139513D01*
G01X1444400Y136804D02*
X1453142D01*
G01X1443300Y137904D02*
X1444400Y136804D01*
G01X1443300Y140000D02*
Y137904D01*
G01X1437900Y145400D02*
X1443300Y140000D01*
G01X1435500Y145400D02*
X1437900D01*
G01X1433477D02*
X1417798Y161079D01*
G01X1435500Y145400D02*
X1433477D01*
G01X1450371Y145543D02*
X1451233Y146405D01*
G01X1447428Y145543D02*
X1450371D01*
G01X1457838Y185620D02*
Y184207D01*
G01X1456159Y187299D02*
X1457838Y185620D01*
G01X1456159Y188296D02*
Y187299D01*
G01X1423011Y166559D02*
Y163559D01*
G01X1424756Y159100D02*
X1427100D01*
G01X1423011Y160845D02*
X1424756Y159100D01*
G01X1423011Y163559D02*
Y160845D01*
G01X1427100Y161112D02*
Y159100D01*
G01X1426261Y161951D02*
X1427100Y161112D01*
G01X1426261Y163309D02*
Y161951D01*
G01X1411584Y195316D02*
X1406050Y200850D01*
G01X1420916Y195316D02*
X1411584D01*
G01X1423126Y197526D02*
X1420916Y195316D01*
G01X1439492Y197526D02*
X1423126D01*
G01X1439499Y197533D02*
X1439492Y197526D01*
G01X1442057Y197533D02*
X1439499D01*
G01X1444273Y195317D02*
X1442057Y197533D01*
G01X1444294Y195317D02*
X1444273D01*
G01X1445006Y194605D02*
X1444294Y195317D01*
G01X1447454Y194605D02*
X1445006D01*
G01X1450205Y197356D02*
X1447454Y194605D01*
G01X1467344Y197356D02*
X1450205D01*
G01X1450910Y195656D02*
X1466044D01*
G01X1448159Y192905D02*
X1450910Y195656D01*
G01X1444280Y192905D02*
X1448159D01*
G01X1441352Y195833D02*
X1444280Y192905D01*
G01X1440204Y195833D02*
X1441352D01*
G01X1440197Y195826D02*
X1440204Y195833D01*
G01X1423831Y195826D02*
X1440197D01*
G01X1421621Y193616D02*
X1423831Y195826D01*
G01X1417356Y193616D02*
X1421621D01*
G01X1412200Y188460D02*
X1417356Y193616D01*
G01X1412200Y182499D02*
Y188460D01*
G01X1415140Y179559D02*
X1412200Y182499D01*
G01X1419511Y179559D02*
X1415140D01*
G01X1409001Y214175D02*
X1414363Y219537D01*
G01X1425410Y217553D02*
X1423147Y219816D01*
G01X1425410Y206257D02*
Y217553D01*
G01X1427287Y204380D02*
X1425410Y206257D01*
G01X1432750Y204380D02*
X1427287D01*
G01X1419511Y188251D02*
Y186059D01*
G01X1421476Y190216D02*
X1419511Y188251D01*
G01X1423031Y190216D02*
X1421476D01*
G01X1425241Y192426D02*
X1423031Y190216D01*
G01X1439949Y192426D02*
X1425241D01*
G01X1442870Y189505D02*
X1439949Y192426D01*
G01X1442891Y189505D02*
X1442870D01*
G01X1442893Y189503D02*
X1442891Y189505D01*
G01X1450719Y189503D02*
X1442893D01*
G01X1453359Y192143D02*
X1450719Y189503D01*
G01X1458569Y192143D02*
X1453359D01*
G01X1432600Y164266D02*
Y161300D01*
G01X1429154Y167712D02*
X1432600Y164266D01*
G01X1429154Y170777D02*
Y167712D01*
G01X1429784Y171407D02*
X1429154Y170777D01*
G01X1434338Y171407D02*
X1429784D01*
G01X1430568Y161300D02*
X1432600D01*
G01X1428918Y162950D02*
X1430568Y161300D01*
G01X1428918Y165237D02*
Y162950D01*
G01X1427346Y166809D02*
X1428918Y165237D01*
G01X1426261Y166809D02*
X1427346D01*
G01X1463498Y173967D02*
X1457838D01*
G01X1466188Y171277D02*
X1463498Y173967D01*
G01X1463900Y206800D02*
X1465650Y208550D01*
G01X1463900Y205550D02*
Y206800D01*
G01X1462850Y209500D02*
X1456250D01*
G01X1463000Y209350D02*
X1462850Y209500D01*
G01X1465650Y209350D02*
X1463000D01*
G01X1409385Y213250D02*
X1415288Y219153D01*
G01X1445763Y211457D02*
X1437804Y219416D01*
G01X1445763Y210236D02*
Y211457D01*
G01X1451619Y204380D02*
X1445763Y210236D01*
G01X1456250Y204380D02*
X1451619D01*
G01X1464077Y163412D02*
Y159912D01*
G01Y158123D02*
Y159912D01*
G01X1465400Y156800D02*
X1464077Y158123D01*
G01X1419511Y163559D02*
Y161771D01*
G01X1459045Y159912D02*
X1460577D01*
G01X1458583Y159450D02*
X1459045Y159912D01*
G01X1452849Y159450D02*
X1458583D01*
G01X1451950Y158551D02*
X1452849Y159450D01*
G01X1451950Y156269D02*
Y158551D01*
G01X1417963Y228826D02*
Y206280D01*
G01Y204087D02*
Y206280D01*
G01X1416500Y202624D02*
X1417963Y204087D01*
G01X1416500Y198890D02*
Y202624D01*
G01X1417153Y198237D02*
X1416500Y198890D01*
G01X1419189Y198237D02*
X1417153D01*
G01X1421253Y200301D02*
X1419189Y198237D01*
G01X1437720Y200301D02*
X1421253D01*
G01X1438765Y201346D02*
X1437720Y200301D01*
G01X1438765Y206269D02*
Y201346D01*
G01X1438094Y206940D02*
X1438765Y206269D01*
G01X1432750Y206940D02*
X1438094D01*
G01X1429475Y173967D02*
X1434338D01*
G01X1428817Y173309D02*
X1429475Y173967D01*
G01X1426261Y173309D02*
X1428817D01*
G01X1451366Y162446D02*
X1450250Y161330D01*
G01X1451366Y165296D02*
Y162446D01*
G01X1450250Y161330D02*
Y156974D01*
G01X1439090Y212060D02*
X1432750D01*
G01X1440663Y210487D02*
X1439090Y212060D01*
G01X1440663Y201840D02*
Y210487D01*
G01X1438199Y199376D02*
X1440663Y201840D01*
G01X1421714Y199376D02*
X1438199D01*
G01X1419650Y197312D02*
X1421714Y199376D01*
G01X1416739Y197312D02*
X1419650D01*
G01X1415480Y198571D02*
X1416739Y197312D01*
G01X1415480Y213068D02*
Y198571D01*
G01X1415712Y213300D02*
X1415480Y213068D01*
G01X1415712Y217101D02*
X1417038Y218427D01*
G01X1415712Y213300D02*
Y217101D01*
G01X1428050Y212060D02*
X1432750D01*
G01X1427500Y212610D02*
X1428050Y212060D01*
G01X1427500Y213944D02*
Y212610D01*
G01X1428176Y214620D02*
X1427500Y213944D01*
G01X1432750Y214620D02*
X1428176D01*
G01X1423261Y169809D02*
X1423011Y170059D01*
G01X1426261Y169809D02*
X1423261D01*
G01X1423011Y173059D02*
Y170059D01*
G01X1422607Y174791D02*
X1415985D01*
G01X1423011Y174387D02*
X1422607Y174791D01*
G01X1423011Y173059D02*
Y174387D01*
G01X1449379Y214620D02*
X1442525Y221474D01*
G01X1456250Y214620D02*
X1449379D01*
G01X1410731Y156940D02*
Y178418D01*
G01X1462870Y217180D02*
X1465610Y214440D01*
G01X1456250Y217180D02*
X1462870D01*
G01X1459786Y193956D02*
X1462059Y191683D01*
G01X1452767Y193956D02*
X1459786D01*
G01X1450016Y191205D02*
X1452767Y193956D01*
G01X1443575Y191205D02*
X1450016D01*
G01X1440654Y194126D02*
X1443575Y191205D01*
G01X1424536Y194126D02*
X1440654D01*
G01X1422326Y191916D02*
X1424536Y194126D01*
G01X1419116Y191916D02*
X1422326D01*
G01X1415800Y188600D02*
X1419116Y191916D01*
G01X1418052Y183059D02*
X1419511D01*
G01X1415800Y185311D02*
X1418052Y183059D01*
G01X1415800Y188600D02*
Y185311D01*
G01X1462200Y171407D02*
X1457838D01*
G01X1463150Y170457D02*
X1462200Y171407D01*
G01X1463150Y167650D02*
Y170457D01*
G01X1460577Y165077D02*
X1463150Y167650D01*
G01X1460577Y163412D02*
Y165077D01*
G01X1458960Y163412D02*
X1460577D01*
G01X1457043Y161495D02*
X1458960Y163412D01*
G01X1423011Y179559D02*
Y176559D01*
G01X1416505Y181295D02*
X1415819Y181981D01*
G01X1421944Y181295D02*
X1416505D01*
G01X1423011Y180228D02*
X1421944Y181295D01*
G01X1423011Y179559D02*
Y180228D01*
G01X1424371Y176559D02*
X1423011D01*
G01X1424621Y176309D02*
X1424371Y176559D01*
G01X1426261Y176309D02*
X1424621D01*
G01X1423011Y186059D02*
Y183059D01*
G01X1424050Y189960D02*
X1425443D01*
G01X1423011Y188921D02*
X1424050Y189960D01*
G01X1423011Y186059D02*
Y188921D01*
G01X1427605Y186309D02*
X1426261D01*
G01X1428030Y186734D02*
X1427605Y186309D01*
G01X1428030Y189535D02*
Y186734D01*
G01X1427605Y189960D02*
X1428030Y189535D01*
G01X1425443Y189960D02*
X1427605D01*
G01X1417422Y170059D02*
X1419511D01*
G01X1416957Y169594D02*
X1417422Y170059D01*
G01X1416957Y160753D02*
Y169594D01*
G01X1414401Y196387D02*
X1411950Y198838D01*
G01X1420205Y196387D02*
X1414401D01*
G01X1422269Y198451D02*
X1420205Y196387D01*
G01X1439108Y198451D02*
X1422269D01*
G01X1439115Y198458D02*
X1439108Y198451D01*
G01X1442441Y198458D02*
X1439115D01*
G01X1443263Y197636D02*
X1442441Y198458D01*
G01X1443284Y197636D02*
X1443263D01*
G01X1445390Y195530D02*
X1443284Y197636D01*
G01X1447070Y195530D02*
X1445390D01*
G01X1449821Y198281D02*
X1447070Y195530D01*
G01X1467951Y198281D02*
X1449821D01*
G01X1456250Y212060D02*
X1466590D01*
G01X1459392Y188183D02*
X1462059D01*
G01X1458908Y187699D02*
X1459392Y188183D01*
G01X1465942Y186758D02*
X1465234D01*
G01X1463257Y188183D02*
X1462059D01*
G01X1464409Y189335D02*
X1463257Y188183D01*
G01X1467368Y189335D02*
X1464409D01*
G01X1413557Y176500D02*
Y159343D01*
G01X1414757Y177700D02*
X1413557Y176500D01*
G01X1418370Y177700D02*
X1414757D01*
G01X1419511Y176559D02*
X1418370Y177700D01*
G01X1428291Y182809D02*
X1426261D01*
G01X1429453Y181647D02*
X1428291Y182809D01*
G01X1434338Y181647D02*
X1429453D01*
G01X1465234Y182354D02*
Y183258D01*
G01X1464527Y181647D02*
X1465234Y182354D01*
G01X1457838Y181647D02*
X1464527D01*
G01X1454079Y157468D02*
X1462132D01*
G01X1451589Y206940D02*
X1438111Y220418D01*
G01X1456250Y206940D02*
X1451589D01*
G01X1415257Y170396D02*
Y160048D01*
G01X1417920Y173059D02*
X1415257Y170396D01*
G01X1419511Y173059D02*
X1417920D01*
G01X1427991Y179809D02*
X1426261D01*
G01X1428713Y179087D02*
X1427991Y179809D01*
G01X1434338Y179087D02*
X1428713D01*
G01X1409806Y177099D02*
Y156556D01*
G01X1418224Y166559D02*
X1419511D01*
G01X1417798Y166133D02*
X1418224Y166559D01*
G01X1417798Y161079D02*
Y166133D01*
G01X1408247Y210945D02*
X1416113Y218811D01*
G01X1408247Y206270D02*
Y210945D01*
G01X1445500Y167613D02*
Y163300D01*
G01X1451289Y173402D02*
X1445500Y167613D01*
G01X1451289Y173499D02*
Y173402D01*
G01X1451386Y173499D02*
X1451289D01*
G01X1464287Y179087D02*
X1466600Y181400D01*
G01X1457838Y179087D02*
X1464287D01*
G01X1437923Y260775D02*
Y269627D01*
G01X1436137Y258989D02*
X1437923Y260775D01*
G01X1436137Y255411D02*
Y258989D01*
G01X1437923Y253625D02*
X1436137Y255411D01*
G01X1437923Y252127D02*
Y253625D01*
G01X1440000Y250050D02*
X1437923Y252127D01*
G01X1440000Y248750D02*
Y250050D01*
G01X1437923Y269627D02*
Y283424D01*
G01X1453580Y237120D02*
X1458250D01*
G01X1453287Y237413D02*
X1453580Y237120D01*
G01X1453287Y240654D02*
Y237413D01*
G01X1453953Y241320D02*
X1453287Y240654D01*
G01X1460670Y241320D02*
X1453953D01*
G01X1463110Y243760D02*
X1460670Y241320D01*
G01X1463110Y245864D02*
Y243760D01*
G01X1462377Y246597D02*
X1463110Y245864D01*
G01X1462377Y248223D02*
Y246597D01*
G01X1464374Y250220D02*
X1462377Y248223D01*
G01X1465850Y250220D02*
X1464374D01*
G01X1463599Y229440D02*
X1466039Y227000D01*
G01X1458250Y229440D02*
X1463599D01*
G01X1438700Y255400D02*
X1441600Y258300D01*
G01X1438500Y255400D02*
X1438700D01*
G01X1463980Y239680D02*
X1458250D01*
G01X1464847Y240547D02*
X1463980Y239680D01*
G01X1467229Y240547D02*
X1464847D01*
G01X1464340Y244730D02*
X1467229Y241841D01*
G01X1464340Y247410D02*
Y244730D01*
G01X1412769Y228926D02*
Y251626D01*
G01X1414363Y227332D02*
X1412769Y228926D01*
G01X1414363Y219537D02*
Y227332D01*
G01X1418219Y231188D02*
Y254114D01*
G01X1419813Y229594D02*
X1418219Y231188D01*
G01X1419813Y220939D02*
Y229594D01*
G01X1420936Y219816D02*
X1419813Y220939D01*
G01X1423147Y219816D02*
X1420936D01*
G01X1417294Y230804D02*
Y253730D01*
G01X1418888Y229210D02*
X1417294Y230804D01*
G01X1418888Y220555D02*
Y229210D01*
G01X1421391Y218052D02*
X1418888Y220555D01*
G01X1422196Y218052D02*
X1421391D01*
G01X1464985Y275246D02*
X1467743Y272488D01*
G01X1459559Y275246D02*
X1464985D01*
G01X1458052Y276753D02*
X1459559Y275246D01*
G01X1435800Y275940D02*
Y284977D01*
G01X1426905Y267045D02*
X1435800Y275940D01*
G01X1413694Y229310D02*
Y252010D01*
G01X1415288Y227716D02*
X1413694Y229310D01*
G01X1415288Y219153D02*
Y227716D01*
G01X1419144Y231572D02*
Y254498D01*
G01X1420738Y229978D02*
X1419144Y231572D01*
G01X1420738Y225693D02*
Y229978D01*
G01X1423239Y223192D02*
X1420738Y225693D01*
G01X1424171Y223192D02*
X1423239D01*
G01X1427947Y219416D02*
X1424171Y223192D01*
G01X1437804Y219416D02*
X1427947D01*
G01X1447187Y245250D02*
X1446000D01*
G01X1449919Y247982D02*
X1447187Y245250D01*
G01X1449919Y252409D02*
Y247982D01*
G01X1440225Y229440D02*
X1434750D01*
G01X1447163Y236378D02*
X1440225Y229440D01*
G01X1447163Y242837D02*
Y236378D01*
G01X1446942Y243058D02*
X1447163Y242837D01*
G01X1446942Y243146D02*
Y243058D01*
G01X1446000Y244088D02*
X1446942Y243146D01*
G01X1446000Y245250D02*
Y244088D01*
G01X1455817Y264408D02*
X1454056Y266169D01*
G01X1458011Y264408D02*
X1455817D01*
G01X1416369Y230420D02*
X1417963Y228826D01*
G01X1416369Y253346D02*
Y230420D01*
G01X1431100Y254200D02*
X1433700D01*
G01X1422498Y245598D02*
X1431100Y254200D01*
G01X1422498Y232852D02*
Y245598D01*
G01X1424013Y231337D02*
X1422498Y232852D01*
G01X1424013Y228466D02*
Y231337D01*
G01X1429580Y222899D02*
X1424013Y228466D01*
G01X1443929Y222899D02*
X1429580D01*
G01X1448024Y218804D02*
X1443929Y222899D01*
G01X1457496Y218804D02*
X1448024D01*
G01X1457707Y218593D02*
X1457496Y218804D01*
G01X1464508Y218593D02*
X1457707D01*
G01X1466001Y217100D02*
X1464508Y218593D01*
G01X1448603Y265413D02*
X1449497Y264519D01*
G01X1448603Y267304D02*
Y265413D01*
G01X1415444Y230036D02*
Y252962D01*
G01X1417038Y228442D02*
X1415444Y230036D01*
G01X1417038Y218427D02*
Y228442D01*
G01X1445454Y265011D02*
Y267304D01*
G01X1444948Y264505D02*
X1445454Y265011D01*
G01X1409200Y267747D02*
Y271800D01*
G01X1421073Y255874D02*
X1409200Y267747D01*
G01X1421073Y232261D02*
Y255874D01*
G01X1422588Y230746D02*
X1421073Y232261D01*
G01X1422588Y227875D02*
Y230746D01*
G01X1428989Y221474D02*
X1422588Y227875D01*
G01X1442525Y221474D02*
X1428989D01*
G01X1452066Y254634D02*
X1452200Y254500D01*
G01X1447726Y254634D02*
X1452066D01*
G01X1445354Y252262D02*
X1447726Y254634D01*
G01X1445354Y249396D02*
Y252262D01*
G01X1446000Y248750D02*
X1445354Y249396D01*
G01X1423475Y266349D02*
Y269600D01*
G01X1427200Y262624D02*
X1423475Y266349D01*
G01X1430365Y262624D02*
X1427200D01*
G01X1423475Y275901D02*
X1441607Y294033D01*
G01X1423475Y269600D02*
Y275901D01*
G01X1453286Y270212D02*
Y281436D01*
G01X1453260Y270186D02*
X1453286Y270212D01*
G01X1453260Y269830D02*
Y270186D01*
G01X1452377Y268947D02*
X1453260Y269830D01*
G01X1452021Y268947D02*
X1452377D01*
G01X1451938Y268864D02*
X1452021Y268947D01*
G01X1451237Y268864D02*
X1451938D01*
G01X1451184Y268811D02*
X1451237Y268864D01*
G01X1451129Y268811D02*
X1451184D01*
G01X1450246Y267928D02*
X1451129Y268811D01*
G01X1450246Y266680D02*
Y267928D01*
G01X1454350Y262576D02*
X1450246Y266680D01*
G01X1454350Y262200D02*
Y262576D01*
G01X1451502Y247750D02*
X1450413Y246661D01*
G01X1454500Y247750D02*
X1451502D01*
G01X1439689Y226880D02*
X1434750D01*
G01X1448800Y235991D02*
X1439689Y226880D01*
G01X1448800Y245048D02*
Y235991D01*
G01X1450413Y246661D02*
X1448800Y245048D01*
G01X1457835Y261026D02*
X1460835D01*
G01Y261958D02*
Y261026D01*
G01X1462950Y264073D02*
X1460835Y261958D01*
G01X1462950Y267913D02*
Y264073D01*
G01Y271855D02*
Y267913D01*
G01X1461202Y273603D02*
X1462950Y271855D01*
G01X1443700Y251520D02*
Y253769D01*
G01X1443000Y250820D02*
X1443700Y251520D01*
G01X1443000Y248750D02*
Y250820D01*
G01X1440331Y262571D02*
Y280651D01*
G01X1443700Y259202D02*
X1440331Y262571D01*
G01X1443700Y253769D02*
Y259202D01*
G01Y253769D02*
X1443715D01*
G01X1447345Y266431D02*
Y260523D01*
G01X1447096Y266680D02*
X1447345Y266431D01*
G01X1447096Y268947D02*
Y266680D01*
G01X1448603Y270454D02*
X1447096Y268947D01*
G01X1407200Y270700D02*
Y269600D01*
G01Y268047D02*
Y269600D01*
G01X1420148Y255099D02*
X1407200Y268047D01*
G01X1420148Y231877D02*
Y255099D01*
G01X1421663Y230362D02*
X1420148Y231877D01*
G01X1421663Y227009D02*
Y230362D01*
G01X1428254Y220418D02*
X1421663Y227009D01*
G01X1438111Y220418D02*
X1428254D01*
G01X1449585Y255623D02*
X1451858Y257896D01*
G01X1445955Y255623D02*
X1449585D01*
G01X1444933Y256645D02*
X1445955Y255623D01*
G01X1444933Y259672D02*
Y256645D01*
G01X1441905Y262700D02*
X1444933Y259672D01*
G01X1441905Y264353D02*
Y262700D01*
G01X1443939Y266387D02*
X1441905Y264353D01*
G01X1443939Y280634D02*
Y266387D01*
G01X1454500Y253248D02*
Y251250D01*
G01X1453937Y253811D02*
X1454500Y253248D01*
G01X1453937Y255817D02*
Y253811D01*
G01X1451858Y257896D02*
X1453937Y255817D01*
G01X1454902Y269842D02*
Y270454D01*
G01X1456836Y267908D02*
X1454902Y269842D01*
G01X1458011Y267908D02*
X1456836D01*
G01X1428178Y237120D02*
X1434750D01*
G01X1425469Y239829D02*
X1428178Y237120D01*
G01X1438550D02*
X1434750D01*
G01X1440000Y238570D02*
X1438550Y237120D01*
G01X1440000Y245250D02*
Y238570D01*
G01X1462988Y226880D02*
X1458250D01*
G01X1465800Y224068D02*
X1462988Y226880D01*
G01X1461379Y219900D02*
X1465600D01*
G01X1459548Y221731D02*
X1461379Y219900D01*
G01X1458318Y243019D02*
Y243000D01*
G01X1458337Y243019D02*
X1458318D01*
G01X1458337Y243000D02*
Y243019D01*
G01X1458500Y243163D02*
X1458337Y243000D01*
G01X1458500Y245500D02*
Y243163D01*
G01X1452150Y234560D02*
X1458250D01*
G01X1450128Y236582D02*
X1452150Y234560D01*
G01X1450128Y243078D02*
Y236582D01*
G01X1452550Y245500D02*
X1450128Y243078D01*
G01X1458500Y245500D02*
X1452550D01*
G01X1414519Y229652D02*
Y252352D01*
G01X1416113Y228058D02*
X1414519Y229652D01*
G01X1416113Y218811D02*
Y228058D01*
G01X1443000Y239680D02*
Y245250D01*
G01X1443590Y239090D02*
X1443000Y239680D01*
G01X1443590Y235090D02*
Y239090D01*
G01X1442550Y234050D02*
X1443590Y235090D01*
G01X1440350Y234050D02*
X1442550D01*
G01X1439840Y234560D02*
X1440350Y234050D01*
G01X1434750Y234560D02*
X1439840D01*
G01X1425477D02*
X1425304Y234733D01*
G01X1434750Y234560D02*
X1425477D01*
G01X1464623Y273676D02*
X1464424D01*
G01X1465904Y272395D02*
X1464623Y273676D01*
G01X1464500Y263500D02*
Y262100D01*
G01X1464233Y263767D02*
X1464500Y263500D01*
G01X1464233Y266001D02*
Y263767D01*
G01X1465904Y267672D02*
X1464233Y266001D01*
G01X1453260Y284559D02*
X1451754Y283053D01*
G01X1453260Y286826D02*
Y284559D01*
G01X1452377Y287709D02*
X1453260Y286826D01*
G01X1451264Y287709D02*
X1452377D01*
G01X1450224Y288749D02*
X1451264Y287709D01*
G01X1450224Y289861D02*
Y288749D01*
G01X1449088Y290997D02*
X1450224Y289861D01*
G01X1444864Y290997D02*
X1449088D01*
G01X1443910Y290043D02*
X1444864Y290997D01*
G01X1443910Y288825D02*
Y290043D01*
G01X1442928Y287843D02*
X1443910Y288825D01*
G01X1442342Y287843D02*
X1442928D01*
G01X1437923Y283424D02*
X1442342Y287843D01*
G01X1410489Y334891D02*
Y337988D01*
G01X1410990Y334390D02*
X1410489Y334891D01*
G01X1461569Y316993D02*
X1462776Y318200D01*
G01X1457342Y316993D02*
X1461569D01*
G01X1456570Y317765D02*
X1457342Y316993D01*
G01X1456570Y318444D02*
Y317765D01*
G01X1455659Y319355D02*
X1456570Y318444D01*
G01X1433229Y319355D02*
X1455659D01*
G01X1431033Y317159D02*
X1433229Y319355D01*
G01X1431033Y298972D02*
Y317159D01*
G01X1422548Y290487D02*
X1431033Y298972D01*
G01X1465187Y323842D02*
X1466008Y323021D01*
G01X1447377Y323842D02*
X1465187D01*
G01X1445098Y326121D02*
X1447377Y323842D01*
G01X1442836Y326121D02*
X1445098D01*
G01X1438958Y329999D02*
X1442836Y326121D01*
G01X1417900Y333600D02*
X1416000Y335500D01*
G01X1435357Y333600D02*
X1417900D01*
G01X1438958Y329999D02*
X1435357Y333600D01*
G01X1464351Y311397D02*
X1467700D01*
G01X1448051Y289351D02*
X1448603D01*
G01X1444400Y285700D02*
X1448051Y289351D01*
G01X1443400Y285700D02*
X1444400D01*
G01X1428593Y285686D02*
X1432344Y289437D01*
G01X1459003Y292567D02*
X1475997D01*
G01X1456545Y295025D02*
X1459003Y292567D01*
G01X1456545Y296273D02*
Y295025D01*
G01X1456546Y296274D02*
X1456545Y296273D01*
G01X1456546Y296489D02*
Y296274D01*
G01X1455766Y297269D02*
X1456546Y296489D01*
G01X1453957Y297269D02*
X1455766D01*
G01X1453314Y297912D02*
X1453957Y297269D01*
G01X1453314Y299459D02*
Y297912D01*
G01X1452468Y300305D02*
X1453314Y299459D01*
G01X1444830Y300305D02*
X1452468D01*
G01X1443810Y299285D02*
X1444830Y300305D01*
G01X1443810Y298175D02*
Y299285D01*
G01X1442862Y297227D02*
X1443810Y298175D01*
G01X1440134Y297227D02*
X1442862D01*
G01X1432344Y289437D02*
X1440134Y297227D01*
G01X1435500Y308400D02*
Y305400D01*
G01X1426458Y286611D02*
X1434624Y294777D01*
G01X1435500Y295653D02*
X1434624Y294777D01*
G01X1435500Y305400D02*
Y295653D01*
G01X1417909Y330832D02*
X1422553Y326188D01*
G01X1414868Y330832D02*
X1417909D01*
G01X1413476Y332224D02*
X1414868Y330832D01*
G01X1413476Y344484D02*
Y332224D01*
G01X1427526Y321215D02*
X1422553Y326188D01*
G01X1431304Y321215D02*
X1427526D01*
G01X1432119Y322030D02*
X1431304Y321215D01*
G01X1460650Y322030D02*
X1432119D01*
G01X1461512Y322892D02*
X1460650Y322030D01*
G01X1464257Y322892D02*
X1461512D01*
G01X1465300Y321849D02*
X1464257Y322892D01*
G01X1465300Y317700D02*
Y321849D01*
G01X1466402Y316598D02*
X1465300Y317700D01*
G01X1445056Y292526D02*
X1445427D01*
G01X1443430Y290900D02*
X1445056Y292526D01*
G01X1441723Y290900D02*
X1443430D01*
G01X1436812Y285989D02*
X1441723Y290900D01*
G01X1435800Y284977D02*
X1436812Y285989D01*
G01X1416000Y338100D02*
X1425828Y347928D01*
G01X1456721Y320179D02*
X1458400Y318500D01*
G01X1439343Y320179D02*
X1456721D01*
G01X1439342Y320180D02*
X1439343Y320179D01*
G01X1432887Y320180D02*
X1439342D01*
G01X1430159Y317452D02*
X1432887Y320180D01*
G01X1430159Y299918D02*
Y317452D01*
G01X1422252Y292011D02*
X1430159Y299918D01*
G01X1464476Y318631D02*
Y315500D01*
G01X1463285Y319822D02*
X1464476Y318631D01*
G01X1462771Y319822D02*
X1463285D01*
G01X1461488Y321105D02*
X1462771Y319822D01*
G01X1432503Y321105D02*
X1461488D01*
G01X1429103Y317705D02*
X1432503Y321105D01*
G01X1429103Y300710D02*
Y317705D01*
G01X1421329Y292936D02*
X1429103Y300710D01*
G01X1462800Y309797D02*
X1464350Y308247D01*
G01X1462800Y312300D02*
Y309797D01*
G01X1464476Y313976D02*
X1462800Y312300D01*
G01X1464476Y315500D02*
Y313976D01*
G01X1433826Y296772D02*
X1424590Y287536D01*
G01X1433826Y314226D02*
Y296772D01*
G01X1434700Y315100D02*
X1433826Y314226D01*
G01X1427535Y281739D02*
X1423407D01*
G01X1441509Y295713D02*
X1427535Y281739D01*
G01X1443265Y295713D02*
X1441509D01*
G01X1444708Y297156D02*
X1443265Y295713D01*
G01X1449346Y297156D02*
X1444708D01*
G01X1450095Y296407D02*
X1449346Y297156D01*
G01X1450095Y295004D02*
Y296407D01*
G01X1453999Y291100D02*
X1450095Y295004D01*
G01X1456200Y291100D02*
X1453999D01*
G01X1456807Y291707D02*
X1456200Y291100D01*
G01X1478287Y291707D02*
X1456807D01*
G01X1407675Y281739D02*
X1423407D01*
G01X1405392Y284022D02*
X1407675Y281739D01*
G01X1440710Y316893D02*
X1440910Y316693D01*
G01X1433280Y316893D02*
X1440710D01*
G01X1432855Y316468D02*
X1433280Y316893D01*
G01X1432855Y297210D02*
Y316468D01*
G01X1424106Y288461D02*
X1432855Y297210D01*
G01X1457452Y290882D02*
X1483761D01*
G01X1456500Y289930D02*
X1457452Y290882D01*
G01X1456500Y288818D02*
Y289930D01*
G01X1455526Y287844D02*
X1456500Y288818D01*
G01X1454278Y287844D02*
X1455526D01*
G01X1453300Y288822D02*
X1454278Y287844D01*
G01X1453300Y289935D02*
Y288822D01*
G01X1449202Y294033D02*
X1453300Y289935D01*
G01X1441607Y294033D02*
X1449202D01*
G01X1439700Y302494D02*
X1442304Y305098D01*
G01X1439700Y300400D02*
Y302494D01*
G01X1453286Y281436D02*
X1454902Y283052D01*
G01X1434535Y324366D02*
X1431194Y327707D01*
G01X1444311Y324366D02*
X1434535D01*
G01X1416800Y332100D02*
X1416000Y332900D01*
G01X1426801Y332100D02*
X1416800D01*
G01X1431194Y327707D02*
X1426801Y332100D01*
G01X1451606Y314546D02*
X1451753D01*
G01X1449963Y316189D02*
X1451606Y314546D01*
G01X1444852Y316189D02*
X1449963D01*
G01X1442841Y318200D02*
X1444852Y316189D01*
G01X1433241Y318200D02*
X1442841D01*
G01X1431858Y316817D02*
X1433241Y318200D01*
G01X1431858Y297766D02*
Y316817D01*
G01X1423577Y289485D02*
X1431858Y297766D01*
G01X1440300Y305400D02*
X1439000D01*
G01X1441505Y306605D02*
X1440300Y305400D01*
G01X1450804Y306605D02*
X1441505D01*
G01X1454007Y309808D02*
X1450804Y306605D01*
G01X1458826Y309808D02*
X1454007D01*
G01X1459695Y308939D02*
X1458826Y309808D01*
G01X1459695Y307475D02*
Y308939D01*
G01X1460479Y306691D02*
X1459695Y307475D01*
G01X1461875Y306691D02*
X1460479D01*
G01X1462844Y305722D02*
X1461875Y306691D01*
G01X1462844Y304474D02*
Y305722D01*
G01X1463727Y303591D02*
X1462844Y304474D01*
G01X1465156Y303591D02*
X1463727D01*
G01X1467613Y306048D02*
X1465156Y303591D01*
G01X1439000Y311400D02*
Y308400D01*
G01X1441714Y309840D02*
X1443930D01*
G01X1440274Y308400D02*
X1441714Y309840D01*
G01X1439000Y308400D02*
X1440274D01*
G01X1447753Y308247D02*
X1448603D01*
G01X1446160Y309840D02*
X1447753Y308247D01*
G01X1443930Y309840D02*
X1446160D01*
G01X1450867Y286202D02*
X1451753D01*
G01X1449360Y287709D02*
X1450867Y286202D01*
G01X1447979Y287709D02*
X1449360D01*
G01X1446257Y285987D02*
X1447979Y287709D01*
G01X1446257Y284802D02*
Y285987D01*
G01X1444664Y283209D02*
X1446257Y284802D01*
G01X1442889Y283209D02*
X1444664D01*
G01X1440331Y280651D02*
X1442889Y283209D01*
G01X1448603Y285298D02*
X1443939Y280634D01*
G01X1448603Y286202D02*
Y285298D01*
G01X1464974Y306740D02*
X1465857Y307623D01*
G01X1463726Y306740D02*
X1464974D01*
G01X1459600Y310866D02*
X1463726Y306740D01*
G01X1459600Y311980D02*
Y310866D01*
G01X1458676Y312904D02*
X1459600Y311980D01*
G01X1454278Y312904D02*
X1458676D01*
G01X1453300Y311926D02*
X1454278Y312904D01*
G01X1453300Y310813D02*
Y311926D01*
G01X1452377Y309890D02*
X1453300Y310813D01*
G01X1447979Y309890D02*
X1452377D01*
G01X1447096Y310773D02*
X1447979Y309890D01*
G01X1447096Y311886D02*
Y310773D01*
G01X1445919Y313063D02*
X1447096Y311886D01*
G01X1435763Y313063D02*
X1445919D01*
G01X1435500Y312800D02*
X1435763Y313063D01*
G01X1435500Y311400D02*
Y312800D01*
G01X1445876Y315080D02*
X1443150D01*
G01X1448006Y312950D02*
X1445876Y315080D01*
G01X1452524Y312950D02*
X1448006D01*
G01X1453260Y313686D02*
X1452524Y312950D01*
G01X1453260Y315342D02*
Y313686D01*
G01X1454018Y316100D02*
X1453260Y315342D01*
G01X1458800Y316100D02*
X1454018D01*
G01X1460354Y314546D02*
X1458800Y316100D01*
G01X1461202Y314546D02*
X1460354D01*
G01X1443130Y315100D02*
X1438200D01*
G01X1443150Y315080D02*
X1443130Y315100D01*
G01X1461220Y387080D02*
X1471742D01*
G01X1460700Y387600D02*
X1461220Y387080D01*
G01X1456900Y387600D02*
X1460700D01*
G01X1464400Y382720D02*
X1465550Y383870D01*
G01X1464050Y357500D02*
X1466700D01*
G01X1463809Y357259D02*
X1464050Y357500D01*
G01X1463617Y357259D02*
X1463809D01*
G01X1417851Y348859D02*
X1413476Y344484D01*
G01X1417851Y354350D02*
Y348859D01*
G01X1411160Y361041D02*
X1417851Y354350D01*
G01X1411160Y362500D02*
Y361041D01*
G01X1412260Y363600D02*
X1411160Y362500D01*
G01X1412260Y384540D02*
Y363600D01*
G01X1409671Y387129D02*
X1412260Y384540D01*
G01X1409671Y422574D02*
Y387129D01*
G01X1413400Y361300D02*
X1429100D01*
G01X1429700Y360700D02*
X1456000D01*
G01X1429100Y361300D02*
X1429700Y360700D01*
G01X1436450Y358550D02*
X1425828Y347928D01*
G01X1453951Y358550D02*
X1436450D01*
G01X1457821Y354680D02*
X1453951Y358550D01*
G01X1461120Y354680D02*
X1457821D01*
G01X1462100Y353700D02*
X1461120Y354680D01*
G01X1462100Y351416D02*
Y353700D01*
G01X1467666Y345850D02*
X1462100Y351416D01*
G01X1464327Y364320D02*
X1466565D01*
G01X1462556Y366091D02*
X1464327Y364320D01*
G01X1457042Y366091D02*
X1462556D01*
G01X1453811Y369322D02*
X1457042Y366091D01*
G01X1453811Y369748D02*
Y369322D01*
G01X1462747Y355562D02*
X1469121D01*
G01X1458517Y359792D02*
X1462747Y355562D01*
G01X1458517Y361679D02*
Y359792D01*
G01X1457613Y362583D02*
X1458517Y361679D01*
G01X1453082Y362583D02*
X1457613D01*
G01X1453064Y362601D02*
X1453082Y362583D01*
G01X1462302Y380790D02*
X1460154Y382938D01*
G01X1465050Y380790D02*
X1462302D01*
G01X1465273Y381013D02*
X1465050Y380790D01*
G01X1469887Y381013D02*
X1465273D01*
G01X1458612Y382938D02*
X1460154D01*
G01X1456981Y384569D02*
X1458612Y382938D01*
G01X1463921Y371778D02*
X1469000D01*
G01X1462306Y373393D02*
X1463921Y371778D01*
G01X1460868Y373393D02*
X1462306D01*
G01X1456167Y377892D02*
X1454814Y379245D01*
G01X1457818Y377892D02*
X1456167D01*
G01X1460868Y374842D02*
X1457818Y377892D01*
G01X1460868Y373393D02*
Y374842D01*
G01X1407345Y424900D02*
X1409671Y422574D01*
G01X1446270Y522620D02*
Y535916D01*
G01X1435010Y511360D02*
X1446270Y522620D01*
G01X1414310Y511360D02*
X1435010D01*
G01X1404950Y502000D02*
X1414310Y511360D01*
G01X1403828Y515072D02*
Y511528D01*
G01X1407424Y518668D02*
X1403828Y515072D01*
G01X1413248Y518668D02*
X1407424D01*
G01X1414800Y520220D02*
X1413248Y518668D01*
G01X1414800Y521400D02*
Y520220D01*
G01X1442720Y524281D02*
Y533590D01*
G01X1434089Y515650D02*
X1442720Y524281D01*
G01X1413530Y515650D02*
X1434089D01*
G01X1424600Y518000D02*
X1424116Y518484D01*
G01X1432698Y518000D02*
X1424600D01*
G01X1438390Y523692D02*
X1432698Y518000D01*
G01X1438390Y527175D02*
Y523692D01*
G01X1422000Y520600D02*
Y523700D01*
G01X1424116Y518484D02*
X1422000Y520600D01*
G01X1413351Y512960D02*
X1404166Y503775D01*
G01X1413399Y512960D02*
X1413351D01*
G01X1413574Y513135D02*
X1413399Y512960D01*
G01X1434085Y513135D02*
X1413574D01*
G01X1444495Y523545D02*
X1434085Y513135D01*
G01X1444495Y535180D02*
Y523545D01*
G01X1409753Y521500D02*
X1407200D01*
G01X1412753Y524500D02*
X1409753Y521500D01*
G01X1416600Y524500D02*
X1412753D01*
G01X1407200Y521500D02*
X1404296D01*
G01X1404910Y511690D02*
X1405950Y510650D01*
G01X1404910Y514581D02*
Y511690D01*
G01X1407972Y517643D02*
X1404910Y514581D01*
G01X1413753Y517643D02*
X1407972D01*
G01X1417610Y521500D02*
X1413753Y517643D01*
G01X1417800Y521500D02*
X1417610D01*
G01X1442006Y545294D02*
X1439123D01*
G01X1443937Y543363D02*
X1442006Y545294D01*
G01X1443937Y538249D02*
Y543363D01*
G01X1446270Y535916D02*
X1443937Y538249D01*
G01X1437529Y539986D02*
X1436060Y541455D01*
G01X1437529Y539675D02*
Y539986D01*
G01X1439822Y537382D02*
X1437529Y539675D01*
G01X1439822Y536488D02*
Y537382D01*
G01X1442720Y533590D02*
X1439822Y536488D01*
G01X1416600Y528500D02*
Y528000D01*
G01X1419600Y531500D02*
X1416600Y528500D01*
G01X1425600Y527200D02*
X1422000D01*
G01Y533000D02*
Y527200D01*
G01X1423800Y534800D02*
X1422000Y533000D01*
G01X1442162Y537513D02*
X1444495Y535180D01*
G01X1442162Y541148D02*
Y537513D01*
G01X1440525Y542785D02*
X1442162Y541148D01*
G01X1438799Y542785D02*
X1440525D01*
G01X1436629Y544955D02*
X1436060D01*
G01X1438799Y542785D02*
X1436629Y544955D01*
G01X1515000Y-3242D02*
Y-15000D01*
G01X1468000Y16600D02*
Y17100D01*
G01X1469864Y14736D02*
X1468000Y16600D01*
G01X1469864Y12565D02*
Y14736D01*
G01X1465581Y8282D02*
X1469864Y12565D01*
G01X1465581Y-1419D02*
Y8282D01*
G01X1468000Y17100D02*
Y20750D01*
G01X1492000Y-15000D02*
X1487688Y-19312D01*
G01X1516141Y675D02*
X1533479D01*
G01X1512087Y-3379D02*
X1516141Y675D01*
G01X1506107Y-3379D02*
X1512087D01*
G01X1497563Y5165D02*
X1506107Y-3379D01*
G01X1497563Y26737D02*
Y5165D01*
G01X1495800Y28500D02*
X1497563Y26737D01*
G01X1480571Y28500D02*
X1495800D01*
G01X1473886Y35185D02*
X1480571Y28500D01*
G01X1510200Y15800D02*
Y12200D01*
G01X1511100Y16700D02*
X1510200Y15800D01*
G01X1524000Y16700D02*
X1511100D01*
G01X1528482Y12218D02*
X1524000Y16700D01*
G01X1507500Y12200D02*
X1510200D01*
G01X1507159Y12541D02*
X1507500Y12200D01*
G01X1505400Y12541D02*
X1507159D01*
G01X1524137Y18620D02*
X1521092Y21665D01*
G01X1528970Y18620D02*
X1524137D01*
G01X1509500Y37500D02*
Y31900D01*
G01X1517200Y7082D02*
X1513700D01*
G01X1524144Y28918D02*
Y36359D01*
G01X1524154Y28918D02*
X1524144D01*
G01X1516200Y5300D02*
X1514400Y3500D01*
G01X1533375Y5300D02*
X1516200D01*
G01X1522195Y10505D02*
X1527979D01*
G01X1520500Y12200D02*
X1522195Y10505D01*
G01X1517200Y12200D02*
X1520500D01*
G01X1473550Y17069D02*
Y14150D01*
G01X1471500Y19119D02*
X1473550Y17069D01*
G01X1471500Y20750D02*
Y19119D01*
G01X1487336Y-9664D02*
X1492000Y-5000D01*
G01X1469511Y-9664D02*
X1487336D01*
G01X1466800Y-6953D02*
X1469511Y-9664D01*
G01X1466800Y-1594D02*
Y-6953D01*
G01X1466406Y-1200D02*
X1466800Y-1594D01*
G01X1466406Y6305D02*
Y-1200D01*
G01X1473550Y13449D02*
X1466406Y6305D01*
G01X1473550Y14150D02*
Y13449D01*
G01X1510200Y5200D02*
Y7082D01*
G01X1511900Y3500D02*
X1510200Y5200D01*
G01X1511900Y1100D02*
X1510500Y-300D01*
G01X1511900Y3500D02*
Y1100D01*
G01Y31400D02*
Y34100D01*
G01X1506300Y25800D02*
X1511900Y31400D01*
G01X1500300Y25800D02*
X1506300D01*
G01X1498488Y23988D02*
X1500300Y25800D01*
G01X1498488Y5549D02*
Y23988D01*
G01X1506491Y-2454D02*
X1498488Y5549D01*
G01X1511703Y-2454D02*
X1506491D01*
G01X1515758Y1601D02*
X1511703Y-2454D01*
G01X1516567Y1601D02*
X1515758D01*
G01X1516568Y1600D02*
X1516567Y1601D01*
G01X1533863Y1600D02*
X1516568D01*
G01X1506684Y24875D02*
X1516017Y34208D01*
G01X1500684Y24875D02*
X1506684D01*
G01X1499413Y23604D02*
X1500684Y24875D01*
G01X1499413Y5933D02*
Y23604D01*
G01X1503875Y1471D02*
X1499413Y5933D01*
G01X1507371Y1471D02*
X1503875D01*
G01X1509400Y3500D02*
X1507371Y1471D01*
G01X1521900Y27500D02*
Y37082D01*
G01X1524200Y7100D02*
X1520700D01*
G01X1525000Y-15000D02*
Y-1587D01*
G01X1470862Y38209D02*
X1473886Y35185D01*
G01X1513263Y41263D02*
X1509500Y37500D01*
G01X1513263Y79206D02*
Y41263D01*
G01X1515370Y81313D02*
X1513263Y79206D01*
G01X1519580Y81313D02*
X1515370D01*
G01X1525760Y84630D02*
X1529560D01*
G01X1523844Y82714D02*
X1525760Y84630D01*
G01X1523844Y63881D02*
Y82714D01*
G01X1520904Y60941D02*
X1523844Y63881D01*
G01X1520904Y51355D02*
Y60941D01*
G01X1518304Y61714D02*
X1521741Y65151D01*
G01X1518304Y42199D02*
Y61714D01*
G01X1524144Y36359D02*
X1518304Y42199D01*
G01X1522912Y66322D02*
X1521741Y65151D01*
G01X1522912Y83095D02*
Y66322D01*
G01X1525565Y85748D02*
X1522912Y83095D01*
G01X1529753Y85748D02*
X1525565D01*
G01X1526000Y74540D02*
X1528630Y77170D01*
G01X1526000Y64500D02*
Y74540D01*
G01Y62000D02*
Y64500D01*
G01X1527233Y60767D02*
X1526000Y62000D01*
G01X1511900Y37884D02*
Y34100D01*
G01X1514688Y40672D02*
X1511900Y37884D01*
G01X1514688Y76310D02*
Y40672D01*
G01X1517162Y78784D02*
X1514688Y76310D01*
G01X1516017Y74583D02*
X1520314Y78880D01*
G01X1516017Y38841D02*
Y74583D01*
G01Y34208D02*
Y38841D01*
G01X1520904Y44045D02*
Y47855D01*
G01X1520887Y44028D02*
X1520904Y44045D01*
G01X1525204Y45367D02*
X1531959D01*
G01X1523865Y44028D02*
X1525204Y45367D01*
G01X1520887Y44028D02*
X1523865D01*
G01X1525181Y86673D02*
X1530137D01*
G01X1521987Y83479D02*
X1525181Y86673D01*
G01X1521987Y75775D02*
Y83479D01*
G01X1517379Y71167D02*
X1521987Y75775D01*
G01X1517379Y41603D02*
Y71167D01*
G01X1521900Y37082D02*
X1517379Y41603D01*
G01X1490178Y111282D02*
X1486193Y107297D01*
G01X1490178Y112315D02*
Y111282D01*
G01X1526337Y136439D02*
X1528480D01*
G01X1522837Y135563D02*
X1524744Y133656D01*
G01X1522837Y136439D02*
Y135563D01*
G01X1471135Y116525D02*
X1468635Y119025D01*
G01X1474105Y116525D02*
X1471135D01*
G01X1477734Y120154D02*
X1474105Y116525D01*
G01X1477734Y121905D02*
Y120154D01*
G01X1481729Y125900D02*
X1477734Y121905D01*
G01X1483913Y125900D02*
X1481729D01*
G01X1492965Y134952D02*
X1483913Y125900D01*
G01X1495530Y134952D02*
X1492965D01*
G01X1500083Y139505D02*
X1495530Y134952D01*
G01X1505405Y139505D02*
X1500083D01*
G01X1508514Y142614D02*
X1505405Y139505D01*
G01X1510184Y142614D02*
X1508514D01*
G01X1465472Y122188D02*
X1468635Y119025D01*
G01X1479018Y108707D02*
X1471496D01*
G01X1485955Y115644D02*
X1479018Y108707D01*
G01X1485955Y125324D02*
Y115644D01*
G01X1493551Y132920D02*
X1485955Y125324D01*
G01X1496123Y132920D02*
X1493551D01*
G01X1500277Y137074D02*
X1496123Y132920D01*
G01X1510224Y137074D02*
X1500277D01*
G01X1511660Y138510D02*
X1510224Y137074D01*
G01X1518506Y130999D02*
X1518514Y130991D01*
G01X1502622Y130999D02*
X1518506D01*
G01X1502024Y130401D02*
X1502622Y130999D01*
G01X1493831Y130401D02*
X1502024D01*
G01X1487885Y124455D02*
X1493831Y130401D01*
G01X1487885Y114956D02*
Y124455D01*
G01X1479786Y106857D02*
X1487885Y114956D01*
G01X1472264Y106857D02*
X1479786D01*
G01X1472263Y106856D02*
X1472264Y106857D01*
G01X1470729Y106856D02*
X1472263D01*
G01X1470728Y106857D02*
X1470729Y106856D01*
G01X1470579Y106857D02*
X1470728D01*
G01X1486961Y103797D02*
X1486193D01*
G01X1488302Y105138D02*
X1486961Y103797D01*
G01X1489098Y105138D02*
X1488302D01*
G01X1489780Y105820D02*
X1489098Y105138D01*
G01X1482397Y103797D02*
X1481100Y102500D01*
G01X1486193Y103797D02*
X1482397D01*
G01X1512930Y112400D02*
X1513879Y113349D01*
G01X1508700Y112400D02*
X1512930D01*
G01X1518936Y155151D02*
X1514120Y159967D01*
G01X1518936Y154063D02*
Y155151D01*
G01X1518937Y154062D02*
X1518936Y154063D01*
G01X1518937Y152528D02*
Y154062D01*
G01X1518936Y152527D02*
X1518937Y152528D01*
G01X1518936Y146220D02*
Y152527D01*
G01X1520305Y144851D02*
X1518936Y146220D01*
G01X1529652Y144851D02*
X1520305D01*
G01X1473354Y151039D02*
Y153246D01*
G01X1483655Y134837D02*
X1479138Y130320D01*
G01X1485210Y134837D02*
X1483655D01*
G01X1474218Y125400D02*
X1479138Y130320D01*
G01X1471500Y125400D02*
X1474218D01*
G01X1469213Y123113D02*
X1471500Y125400D01*
G01X1489252Y152698D02*
Y152111D01*
G01X1488226Y153724D02*
X1489252Y152698D01*
G01X1484842Y153724D02*
X1488226D01*
G01X1483017Y151899D02*
X1484842Y153724D01*
G01X1483017Y148905D02*
Y151899D01*
G01X1482591Y148479D02*
X1483017Y148905D01*
G01X1480354Y148479D02*
X1482591D01*
G01X1480354D02*
Y145919D01*
G01X1488281Y151140D02*
X1489252Y152111D01*
G01X1486338Y151140D02*
X1488281D01*
G01X1485150Y149952D02*
X1486338Y151140D01*
G01X1485150Y148500D02*
Y149952D01*
G01X1466877Y126600D02*
X1468755Y128478D01*
G01X1482455Y123708D02*
Y124222D01*
G01X1473776Y115029D02*
X1482455Y123708D01*
G01X1469808Y115029D02*
X1473776D01*
G01X1470386Y106032D02*
X1470020D01*
G01X1470387Y106031D02*
X1470386Y106032D01*
G01X1472605Y106031D02*
X1470387D01*
G01X1472606Y106032D02*
X1472605Y106031D01*
G01X1480128Y106032D02*
X1472606D01*
G01X1488710Y114614D02*
X1480128Y106032D01*
G01X1488710Y124113D02*
Y114614D01*
G01X1494173Y129576D02*
X1488710Y124113D01*
G01X1502366Y129576D02*
X1494173D01*
G01X1502964Y130174D02*
X1502366Y129576D01*
G01X1516979Y130174D02*
X1502964D01*
G01X1517825Y129328D02*
X1516979Y130174D01*
G01X1519366Y129328D02*
X1517825D01*
G01X1520846Y130808D02*
X1519366Y129328D01*
G01X1531808Y130808D02*
X1520846D01*
G01X1504616Y152500D02*
X1509197Y157081D01*
G01X1504545Y152500D02*
X1504616D01*
G01X1504498Y152453D02*
X1504545Y152500D01*
G01X1497685Y152453D02*
X1504498D01*
G01X1497638Y152500D02*
X1497685Y152453D01*
G01X1495200Y152500D02*
X1497638D01*
G01X1493100Y150400D02*
X1495200Y152500D01*
G01X1493100Y145288D02*
Y150400D01*
G01X1490998Y143186D02*
X1493100Y145288D01*
G01X1479860Y143186D02*
X1490998D01*
G01X1477112Y140438D02*
X1479860Y143186D01*
G01X1465428Y140438D02*
X1477112D01*
G01X1474145Y114089D02*
X1469439D01*
G01X1482615Y122559D02*
X1474145Y114089D01*
G01X1483719Y122559D02*
X1482615D01*
G01X1484924Y123764D02*
X1483719Y122559D01*
G01X1484924Y125602D02*
Y123764D01*
G01X1493190Y133868D02*
X1484924Y125602D01*
G01X1495755Y133868D02*
X1493190D01*
G01X1500153Y138266D02*
X1495755Y133868D01*
G01X1506400Y138266D02*
X1500153D01*
G01X1508823Y140689D02*
X1506400Y138266D01*
G01X1510611Y140689D02*
X1508823D01*
G01X1511847Y141925D02*
X1510611Y140689D01*
G01X1511847Y143036D02*
Y141925D01*
G01X1517086Y148275D02*
X1511847Y143036D01*
G01X1517086Y153295D02*
Y148275D01*
G01X1513300Y157081D02*
X1517086Y153295D01*
G01X1513676Y150061D02*
X1515358Y151743D01*
G01X1501331Y150061D02*
X1513676D01*
G01X1498921Y147651D02*
X1501331Y150061D01*
G01X1498921Y146532D02*
Y147651D01*
G01X1493746Y141357D02*
X1498921Y146532D01*
G01X1480723Y141357D02*
X1493746D01*
G01X1477203Y137837D02*
X1480723Y141357D01*
G01X1492066Y152834D02*
X1493069D01*
G01X1489200Y155700D02*
X1492066Y152834D01*
G01X1486900Y155700D02*
X1489200D01*
G01X1484800Y157800D02*
X1486900Y155700D01*
G01X1478872Y134244D02*
X1466144D01*
G01X1482578Y137950D02*
X1478872Y134244D01*
G01X1495149Y137950D02*
X1482578D01*
G01X1502332Y145133D02*
X1495149Y137950D01*
G01X1502440Y145133D02*
X1502332D01*
G01X1503502Y146195D02*
X1502440Y145133D01*
G01X1503502Y146303D02*
Y146195D01*
G01X1503716Y146517D02*
X1503502Y146303D01*
G01X1505216Y146517D02*
X1503716D01*
G01X1505617Y146116D02*
X1505216Y146517D01*
G01X1505617Y146346D02*
Y146116D01*
G01X1505673Y146346D02*
X1505617D01*
G01X1518011Y154767D02*
X1514034Y158744D01*
G01X1518011Y153679D02*
Y154767D01*
G01X1518012Y153678D02*
X1518011Y153679D01*
G01X1518012Y152912D02*
Y153678D01*
G01X1518011Y152911D02*
X1518012Y152912D01*
G01X1518011Y134517D02*
Y152911D01*
G01X1515427Y131933D02*
X1518011Y134517D01*
G01X1502247Y131933D02*
X1515427D01*
G01X1501640Y131326D02*
X1502247Y131933D01*
G01X1493447Y131326D02*
X1501640D01*
G01X1486960Y124839D02*
X1493447Y131326D01*
G01X1486960Y115340D02*
Y124839D01*
G01X1479402Y107782D02*
X1486960Y115340D01*
G01X1471880Y107782D02*
X1479402D01*
G01X1471879Y107781D02*
X1471880Y107782D01*
G01X1471113Y107781D02*
X1471879D01*
G01X1469276Y151128D02*
X1467354D01*
G01X1471925Y148479D02*
X1469276Y151128D01*
G01X1473354Y148479D02*
X1471925D01*
G01X1467354Y152246D02*
Y151128D01*
G01X1474717Y110370D02*
X1471142D01*
G01X1481421Y139650D02*
X1477908Y136137D01*
G01X1494444Y139650D02*
X1481421D01*
G01X1501689Y146895D02*
X1494444Y139650D01*
G01X1501689Y147189D02*
Y146895D01*
G01X1502000Y147500D02*
X1501689Y147189D01*
G01X1492013Y157478D02*
Y155610D01*
G01X1524284Y112773D02*
X1531853D01*
G01X1501533Y142486D02*
X1503466D01*
G01X1495002Y135955D02*
X1501533Y142486D01*
G01X1489000Y135955D02*
X1495002D01*
G01X1488455Y136500D02*
X1489000Y135955D01*
G01X1482500Y136500D02*
X1488455D01*
G01X1475082Y129082D02*
X1482500Y136500D01*
G01X1475082Y128280D02*
Y129082D01*
G01X1473127Y126325D02*
X1475082Y128280D01*
G01X1471884Y126325D02*
X1473127D01*
G01X1471883Y126326D02*
X1471884Y126325D01*
G01X1471117Y126326D02*
X1471883D01*
G01X1468829Y124038D02*
X1471117Y126326D01*
G01X1513279Y153800D02*
X1513500D01*
G01X1510625Y151146D02*
X1513279Y153800D01*
G01X1500979Y151146D02*
X1510625D01*
G01X1497813Y147980D02*
X1500979Y151146D01*
G01X1497813Y147426D02*
Y147980D01*
G01X1497574Y147187D02*
X1497813Y147426D01*
G01X1497574Y146352D02*
Y147187D01*
G01X1493483Y142261D02*
X1497574Y146352D01*
G01X1480244Y142261D02*
X1493483D01*
G01X1477496Y139513D02*
X1480244Y142261D01*
G01X1485546Y99818D02*
X1489053Y103325D01*
G01X1484218Y99818D02*
X1485546D01*
G01X1481300Y96900D02*
X1484218Y99818D01*
G01X1515968Y179889D02*
X1513779Y182078D01*
G01X1518979Y179889D02*
X1515968D01*
G01X1518979Y176622D02*
Y179889D01*
G01X1518798Y176441D02*
X1518979Y176622D01*
G01X1518798Y174078D02*
Y176441D01*
G01X1506000Y180750D02*
Y181450D01*
G01X1508750Y178000D02*
X1506000Y180750D01*
G01X1508750Y177000D02*
Y178000D01*
G01X1507990Y184010D02*
X1506000D01*
G01X1508500Y183500D02*
X1507990Y184010D01*
G01X1508500Y182000D02*
Y183500D01*
G01X1507950Y181450D02*
X1508500Y182000D01*
G01X1506000Y181450D02*
X1507950D01*
G01X1470550Y194150D02*
X1467344Y197356D01*
G01X1476822Y194150D02*
X1470550D01*
G01X1479222Y191750D02*
X1476822Y194150D01*
G01X1479222Y186178D02*
Y191750D01*
G01X1480333Y185067D02*
X1479222Y186178D01*
G01X1481962Y185067D02*
X1480333D01*
G01X1510650Y205750D02*
X1506250D01*
G01X1511700Y206800D02*
X1510650Y205750D01*
G01X1513352Y206800D02*
X1511700D01*
G01X1514615Y205537D02*
X1513352Y206800D01*
G01X1516616Y205537D02*
X1514615D01*
G01X1525313Y174112D02*
X1528065D01*
G01X1524561Y173360D02*
X1525313Y174112D01*
G01X1524561Y171622D02*
Y173360D01*
G01X1522539Y169600D02*
X1524561Y171622D01*
G01X1514250Y169600D02*
X1522539D01*
G01X1513522Y170328D02*
X1514250Y169600D01*
G01X1510298Y170328D02*
X1513522D01*
G01X1508750Y172750D02*
Y174000D01*
G01X1508199Y172199D02*
X1508750Y172750D01*
G01X1502151Y172199D02*
X1508199D01*
G01X1502100Y172250D02*
X1502151Y172199D01*
G01X1497600Y172250D02*
X1502100D01*
G01X1510866Y170896D02*
X1510298Y170328D01*
G01X1510866Y173547D02*
Y170896D01*
G01X1510413Y174000D02*
X1510866Y173547D01*
G01X1508750Y174000D02*
X1510413D01*
G01X1490837Y178010D02*
X1489015Y179832D01*
G01X1490837Y175687D02*
Y178010D01*
G01X1491300Y175224D02*
X1490837Y175687D01*
G01X1493670Y175224D02*
X1491300D01*
G01X1495185Y173709D02*
X1493670Y175224D01*
G01X1495185Y173316D02*
Y173709D01*
G01X1496251Y172250D02*
X1495185Y173316D01*
G01X1497600Y172250D02*
X1496251D01*
G01X1477988Y172388D02*
X1477388Y172988D01*
G01X1477988Y170177D02*
Y172388D01*
G01X1515060Y192448D02*
Y192443D01*
G01X1512118Y195390D02*
X1515060Y192448D01*
G01X1498786Y195390D02*
X1512118D01*
G01X1496550Y197626D02*
X1498786Y195390D01*
G01X1496550Y203450D02*
Y197626D01*
G01X1494100Y205900D02*
X1496550Y203450D01*
G01X1491300Y205900D02*
X1494100D01*
G01X1488650Y203250D02*
X1491300Y205900D01*
G01X1484750Y203250D02*
X1488650D01*
G01X1477442Y190859D02*
Y190269D01*
G01X1475851Y192450D02*
X1477442Y190859D01*
G01X1469193Y192450D02*
X1475851D01*
G01X1466400Y195243D02*
X1469193Y192450D01*
G01X1466400Y195300D02*
Y195243D01*
G01X1466044Y195656D02*
X1466400Y195300D01*
G01X1489050Y205750D02*
X1484750D01*
G01X1491100Y207800D02*
X1489050Y205750D01*
G01X1491100Y213800D02*
Y207800D01*
G01X1493860Y216560D02*
X1491100Y213800D01*
G01X1493860Y224259D02*
Y216560D01*
G01X1475564Y197436D02*
Y200130D01*
G01X1476500Y196500D02*
X1475564Y197436D01*
G01X1485572Y196500D02*
X1476500D01*
G01X1488072Y194000D02*
X1485572Y196500D01*
G01X1490500Y194000D02*
X1488072D01*
G01X1479900Y205750D02*
X1484750D01*
G01X1479550Y205400D02*
X1479900Y205750D01*
G01X1477300Y205400D02*
X1479550D01*
G01X1475564Y203664D02*
X1477300Y205400D01*
G01X1475564Y200130D02*
Y203664D01*
G01X1483883Y161617D02*
X1481500D01*
G01X1487037Y158463D02*
X1483883Y161617D01*
G01X1488137Y158463D02*
X1487037D01*
G01X1488300Y158300D02*
X1488137Y158463D01*
G01X1480029Y163088D02*
X1476623D01*
G01X1481500Y161617D02*
X1480029Y163088D01*
G01X1465650Y208550D02*
Y209350D01*
G01X1484324Y187626D02*
X1481962D01*
G01X1485500Y186450D02*
X1484324Y187626D01*
G01X1485500Y184800D02*
Y186450D01*
G01X1487300Y183000D02*
X1485500Y184800D01*
G01X1487300Y173328D02*
Y183000D01*
G01X1487237Y173265D02*
X1487300Y173328D01*
G01X1487237Y172737D02*
Y173265D01*
G01X1484700Y170200D02*
X1487237Y172737D01*
G01X1484700Y166008D02*
Y170200D01*
G01X1488300Y162408D02*
X1484700Y166008D01*
G01X1488300Y161700D02*
Y162408D01*
G01X1480025Y208250D02*
X1479000Y207225D01*
G01X1484750Y208250D02*
X1480025D01*
G01X1491261Y198250D02*
X1492136Y199125D01*
G01X1484750Y198250D02*
X1491261D01*
G01X1522690Y180100D02*
X1563897D01*
G01X1522479Y179889D02*
X1522690Y180100D01*
G01X1470035Y156800D02*
X1466800D01*
G01X1470223Y156988D02*
X1470035Y156800D01*
G01X1472387Y160088D02*
X1473123D01*
G01X1470223Y157924D02*
X1472387Y160088D01*
G01X1470223Y156988D02*
Y157924D01*
G01X1473123Y163088D02*
Y160088D01*
G01X1466800Y156800D02*
X1465400D01*
G01X1489100Y166209D02*
Y168500D01*
G01X1491025Y164284D02*
X1489100Y166209D01*
G01X1491025Y161083D02*
Y164284D01*
G01X1492027Y160081D02*
X1491025Y161083D01*
G01X1492027Y160059D02*
Y160081D01*
G01X1494975Y157111D02*
X1492027Y160059D01*
G01X1495577Y157111D02*
X1494975D01*
G01X1498433Y159967D02*
X1495577Y157111D01*
G01X1514120Y159967D02*
X1498433D01*
G01X1473942Y190269D02*
Y187269D01*
G01X1474008Y181400D02*
X1474883Y182275D01*
G01X1471800Y181400D02*
X1474008D01*
G01X1473942Y183216D02*
Y187269D01*
G01X1474883Y182275D02*
X1473942Y183216D01*
G01X1468600Y217100D02*
X1466001D01*
G01X1471000Y214700D02*
X1468600Y217100D01*
G01X1473705Y214700D02*
X1471000D01*
G01X1474462Y215457D02*
X1473705Y214700D01*
G01X1474462Y217176D02*
Y215457D01*
G01X1474287Y217351D02*
X1474462Y217176D01*
G01X1474287Y221888D02*
Y217351D01*
G01X1480988Y166677D02*
X1477988D01*
G01X1474988D02*
X1477988D01*
G01X1471988D02*
X1474988D01*
G01X1466188Y162300D02*
Y167777D01*
G01X1467288Y161200D02*
X1466188Y162300D01*
G01X1469800Y161200D02*
X1467288D01*
G01X1470500Y161900D02*
X1469800Y161200D01*
G01X1470500Y163700D02*
Y161900D01*
G01Y165189D02*
X1471988Y166677D01*
G01X1470500Y163700D02*
Y165189D01*
G01X1490450Y200750D02*
X1484750D01*
G01X1490600Y200900D02*
X1490450Y200750D01*
G01X1493401Y200900D02*
X1490600D01*
G01X1495100Y199201D02*
X1493401Y200900D01*
G01X1495100Y196898D02*
Y199201D01*
G01X1498148Y193850D02*
X1495100Y196898D01*
G01X1506750Y193850D02*
X1498148D01*
G01X1509544Y191056D02*
X1506750Y193850D01*
G01X1512944Y191056D02*
X1509544D01*
G01X1512945Y191055D02*
X1512944Y191056D01*
G01X1512978Y191055D02*
X1512945D01*
G01X1513516Y190517D02*
X1512978Y191055D01*
G01X1514683Y190517D02*
X1513516D01*
G01X1516000Y189200D02*
X1514683Y190517D01*
G01X1516000Y187499D02*
Y189200D01*
G01X1515665Y187164D02*
X1516000Y187499D01*
G01X1515665Y185466D02*
Y187164D01*
G01X1517241Y183890D02*
X1515665Y185466D01*
G01X1533589Y183890D02*
X1517241D01*
G01X1481206Y210750D02*
X1484750D01*
G01X1479219Y212737D02*
X1481206Y210750D01*
G01X1479219Y217631D02*
Y212737D01*
G01X1477500Y219350D02*
X1479219Y217631D01*
G01X1468200Y211850D02*
X1469700D01*
G01X1465610Y214440D02*
X1468200Y211850D01*
G01X1525400Y214400D02*
Y221776D01*
G01X1523400Y212400D02*
X1525400Y214400D01*
G01X1513500Y210750D02*
X1506250D01*
G01X1514500Y209750D02*
X1513500Y210750D01*
G01X1514500Y208000D02*
Y209750D01*
G01X1515300Y207200D02*
X1514500Y208000D01*
G01X1518550Y207200D02*
X1515300D01*
G01X1523400Y212050D02*
X1518550Y207200D01*
G01X1523400Y212400D02*
Y212050D01*
G01X1511831Y208250D02*
X1512525Y208944D01*
G01X1506250Y208250D02*
X1511831D01*
G01X1501648D02*
X1506250D01*
G01X1501000Y208898D02*
X1501648Y208250D01*
G01X1501000Y216449D02*
Y208898D01*
G01X1505151Y220600D02*
X1501000Y216449D01*
G01X1497440Y184010D02*
X1499000D01*
G01X1496000Y185450D02*
X1497440Y184010D01*
G01X1496000Y187500D02*
Y185450D01*
G01X1493315Y190185D02*
X1496000Y187500D01*
G01X1488962Y190185D02*
X1493315D01*
G01X1474988Y172621D02*
X1473888Y173721D01*
G01X1474988Y170177D02*
Y172621D01*
G01X1509197Y157081D02*
X1513136D01*
G01D02*
X1513300D01*
G01X1516318Y182465D02*
X1560578D01*
G01X1514240Y184543D02*
X1516318Y182465D01*
G01X1514240Y187777D02*
Y184543D01*
G01X1512387Y189630D02*
X1514240Y187777D01*
G01X1508370Y189630D02*
X1512387D01*
G01X1505600Y192400D02*
X1508370Y189630D01*
G01X1496650Y192400D02*
X1505600D01*
G01X1495050Y194000D02*
X1496650Y192400D01*
G01X1494000Y194000D02*
X1495050D01*
G01X1516750Y217098D02*
X1515848Y218000D01*
G01X1516750Y215000D02*
Y217098D01*
G01X1509754Y215750D02*
X1506250D01*
G01X1512004Y218000D02*
X1509754Y215750D01*
G01X1469730Y200060D02*
X1467951Y198281D01*
G01X1469730Y204481D02*
Y200060D01*
G01X1468576Y205635D02*
X1469730Y204481D01*
G01X1467992Y205635D02*
X1468576D01*
G01X1467992Y210658D02*
Y205635D01*
G01X1466590Y212060D02*
X1467992Y210658D01*
G01X1484700Y157700D02*
X1484800Y157800D01*
G01X1481400Y157700D02*
X1484700D01*
G01X1479112Y159988D02*
X1481400Y157700D01*
G01X1478386Y159988D02*
X1479112D01*
G01X1478286Y160088D02*
X1478386Y159988D01*
G01X1476623Y160088D02*
X1478286D01*
G01X1472400Y204009D02*
X1472887Y204496D01*
G01X1472400Y197600D02*
Y204009D01*
G01X1474925Y195075D02*
X1472400Y197600D01*
G01X1484425Y195075D02*
X1474925D01*
G01X1487700Y191800D02*
X1484425Y195075D01*
G01X1494200Y191800D02*
X1487700D01*
G01X1496500Y189500D02*
X1494200Y191800D01*
G01X1498500Y189500D02*
X1496500D01*
G01X1499000Y189000D02*
X1498500Y189500D01*
G01X1499000Y186570D02*
Y189000D01*
G01X1468300Y184400D02*
X1465942Y186758D01*
G01X1468300Y188403D02*
X1467368Y189335D01*
G01X1468300Y184400D02*
Y188403D01*
G01X1502070Y186570D02*
X1499000D01*
G01X1503705Y188205D02*
X1502070Y186570D01*
G01X1511796Y188205D02*
X1503705D01*
G01X1512815Y187186D02*
X1511796Y188205D01*
G01X1512815Y185507D02*
Y187186D01*
G01X1511319Y184011D02*
X1512815Y185507D01*
G01X1511319Y179594D02*
Y184011D01*
G01X1515125Y175788D02*
X1511319Y179594D01*
G01X1515125Y173141D02*
Y175788D01*
G01X1516241Y172025D02*
X1515125Y173141D01*
G01X1520932Y172025D02*
X1516241D01*
G01X1521711Y172804D02*
X1520932Y172025D01*
G01X1521711Y175063D02*
Y172804D01*
G01X1525121Y178473D02*
X1521711Y175063D01*
G01X1538318Y178473D02*
X1525121D01*
G01X1474439Y206048D02*
Y207621D01*
G01X1472887Y204496D02*
X1474439Y206048D01*
G01X1510850Y203250D02*
X1512700Y205100D01*
G01X1506250Y203250D02*
X1510850D01*
G01X1501214Y158744D02*
X1500703Y158233D01*
G01X1514034Y158744D02*
X1501214D01*
G01X1525594Y164094D02*
X1532906D01*
G01X1523500Y162000D02*
X1525594Y164094D01*
G01X1514500Y162000D02*
X1523500D01*
G01X1510638Y165862D02*
X1514500Y162000D01*
G01X1510638Y166240D02*
Y165862D01*
G01X1525003Y165519D02*
X1533497D01*
G01X1522909Y163425D02*
X1525003Y165519D01*
G01X1517075Y163425D02*
X1522909D01*
G01X1512500Y168000D02*
X1517075Y163425D01*
G01X1494080Y168000D02*
X1512500D01*
G01X1489504Y172576D02*
X1494080Y168000D01*
G01X1488900Y172576D02*
X1489504D01*
G01X1490327Y159164D02*
X1492013Y157478D01*
G01X1490327Y159376D02*
Y159164D01*
G01X1489703Y160000D02*
X1490327Y159376D01*
G01X1487001Y160000D02*
X1489703D01*
G01X1483300Y163701D02*
X1487001Y160000D01*
G01X1483300Y169528D02*
Y163701D01*
G01X1482651Y170177D02*
X1483300Y169528D01*
G01X1480988Y170177D02*
X1482651D01*
G01X1513149Y213250D02*
X1506250D01*
G01X1514365Y212034D02*
X1513149Y213250D01*
G01X1514965Y212034D02*
X1514365D01*
G01X1516064Y213134D02*
X1514965Y212034D01*
G01X1516664Y213134D02*
X1516064D01*
G01X1517267Y212531D02*
X1516664Y213134D01*
G01X1517267Y211931D02*
Y212531D01*
G01X1516168Y210831D02*
X1517267Y211931D01*
G01X1516168Y210231D02*
Y210831D01*
G01X1516872Y209527D02*
X1516168Y210231D01*
G01X1516872Y208863D02*
Y209527D01*
G01X1510018Y185193D02*
X1511100Y186275D01*
G01X1510018Y179452D02*
Y185193D01*
G01X1513700Y175770D02*
X1510018Y179452D01*
G01X1513700Y172550D02*
Y175770D01*
G01X1515650Y170600D02*
X1513700Y172550D01*
G01X1521523Y170600D02*
X1515650D01*
G01X1523136Y172213D02*
X1521523Y170600D01*
G01X1523136Y174100D02*
Y172213D01*
G01X1525708Y176672D02*
X1523136Y174100D01*
G01X1528065Y176672D02*
X1525708D01*
G01X1523975Y199100D02*
X1523000D01*
G01X1524400Y198675D02*
X1523975Y199100D01*
G01X1524400Y193700D02*
Y198675D01*
G01X1523500Y192800D02*
X1524400Y193700D01*
G01X1523500Y189000D02*
Y192800D01*
G01X1525500Y185920D02*
X1530149D01*
G01X1525420Y186000D02*
X1525500Y185920D01*
G01X1523500Y186000D02*
X1525420D01*
G01X1523500D02*
Y189000D01*
G01X1521500Y198675D02*
Y194500D01*
G01X1521925Y199100D02*
X1521500Y198675D01*
G01X1523000Y199100D02*
X1521925D01*
G01X1499500Y216965D02*
X1504635Y222100D01*
G01X1499500Y208300D02*
Y216965D01*
G01X1500700Y207100D02*
X1499500Y208300D01*
G01X1500700Y201800D02*
Y207100D01*
G01X1501750Y200750D02*
X1500700Y201800D01*
G01X1506250Y200750D02*
X1501750D01*
G01X1510400D02*
X1506250D01*
G01X1511650Y202000D02*
X1510400Y200750D01*
G01X1515561Y202000D02*
X1511650D01*
G01X1516598Y203037D02*
X1515561Y202000D01*
G01X1518000Y197500D02*
Y194500D01*
G01X1521900Y201400D02*
X1518000Y197500D01*
G01X1521900Y203800D02*
Y201400D01*
G01X1524399Y206299D02*
X1521900Y203800D01*
G01X1524399Y206901D02*
Y206299D01*
G01X1522651Y208649D02*
X1524399Y206901D01*
G01X1522049Y208649D02*
X1522651D01*
G01X1518400Y205000D02*
X1522049Y208649D01*
G01X1518400Y202200D02*
Y205000D01*
G01X1513037Y196837D02*
X1518400Y202200D01*
G01X1499911Y196837D02*
X1513037D01*
G01X1498050Y198698D02*
X1499911Y196837D01*
G01X1498050Y206982D02*
Y198698D01*
G01X1497428Y207604D02*
X1498050Y206982D01*
G01X1493322Y207604D02*
X1497428D01*
G01X1492700Y208226D02*
X1493322Y207604D01*
G01X1492700Y209107D02*
Y208226D01*
G01X1493322Y209729D02*
X1492700Y209107D01*
G01X1497428Y209729D02*
X1493322D01*
G01X1498050Y210351D02*
X1497428Y209729D01*
G01X1498050Y211232D02*
Y210351D01*
G01X1497428Y211854D02*
X1498050Y211232D01*
G01X1493322Y211854D02*
X1497428D01*
G01X1492700Y212476D02*
X1493322Y211854D01*
G01X1492700Y213357D02*
Y212476D01*
G01X1493322Y213979D02*
X1492700Y213357D01*
G01X1494981Y213979D02*
X1493322D01*
G01X1495406Y214404D02*
X1494981Y213979D01*
G01X1495406Y220602D02*
Y214404D01*
G01X1466600Y181400D02*
X1468300D01*
G01X1478000Y265400D02*
Y263500D01*
G01X1475350Y268050D02*
X1478000Y265400D01*
G01X1475350Y275201D02*
Y268050D01*
G01X1473798Y276753D02*
X1475350Y275201D01*
G01X1471313Y249069D02*
X1469330D01*
G01X1472432Y247950D02*
X1471313Y249069D01*
G01X1475832Y247950D02*
X1472432D01*
G01X1476420Y247362D02*
X1475832Y247950D01*
G01X1480416Y247362D02*
X1476420D01*
G01X1481547Y246231D02*
X1480416Y247362D01*
G01X1484146Y246231D02*
X1481547D01*
G01X1484217Y246160D02*
X1484146Y246231D01*
G01X1486808Y246160D02*
X1484217D01*
G01X1486811Y246163D02*
X1486808Y246160D01*
G01X1488189Y246163D02*
X1486811D01*
G01X1488192Y246160D02*
X1488189Y246163D01*
G01X1501309Y246160D02*
X1488192D01*
G01X1508485Y253336D02*
X1501309Y246160D01*
G01X1514264Y253336D02*
X1508485D01*
G01X1517628Y249972D02*
X1514264Y253336D01*
G01X1517628Y244483D02*
Y249972D01*
G01X1517636Y244475D02*
X1517628Y244483D01*
G01X1517636Y242381D02*
Y244475D01*
G01X1518509Y241508D02*
X1517636Y242381D01*
G01X1520768Y241508D02*
X1518509D01*
G01X1522365Y239911D02*
X1520768Y241508D01*
G01X1526159Y239911D02*
X1522365D01*
G01X1527168Y238902D02*
X1526159Y239911D01*
G01X1467001Y249069D02*
X1465850Y250220D01*
G01X1469330Y249069D02*
X1467001D01*
G01X1467750Y227000D02*
Y223500D01*
G01X1466039Y227000D02*
X1467750D01*
G01X1471250Y229369D02*
X1470950Y229669D01*
G01X1471250Y227000D02*
Y229369D01*
G01X1523070Y253530D02*
X1519400Y257200D01*
G01X1529147Y253530D02*
X1523070D01*
G01X1519400Y276088D02*
Y268480D01*
G01X1521962Y278650D02*
X1519400Y276088D01*
G01Y268480D02*
Y257200D01*
G01X1518750Y238050D02*
Y237000D01*
G01X1518095Y238705D02*
X1518750Y238050D01*
G01X1515555Y238705D02*
X1518095D01*
G01X1514453Y239807D02*
X1515555Y238705D01*
G01X1514453Y240788D02*
Y239807D01*
G01X1513479Y241762D02*
X1514453Y240788D01*
G01X1513451Y241762D02*
X1513479D01*
G01X1511956Y243257D02*
X1513451Y241762D01*
G01X1511956Y245073D02*
Y243257D01*
G01X1509814Y247215D02*
X1511956Y245073D01*
G01X1521560Y234190D02*
X1522210D01*
G01X1518750Y237000D02*
X1521560Y234190D01*
G01X1467229Y241841D02*
Y240547D01*
G01X1496637Y227036D02*
X1493860Y224259D01*
G01X1496637Y227151D02*
Y227036D01*
G01X1496656Y227170D02*
X1496637Y227151D01*
G01X1496656Y231853D02*
Y227170D01*
G01X1498478Y233675D02*
X1496656Y231853D01*
G01X1496473Y276324D02*
X1492093Y280704D01*
G01X1496558Y276324D02*
X1496473D01*
G01X1501275Y271607D02*
X1496558Y276324D01*
G01X1501275Y254895D02*
Y271607D01*
G01X1499560Y253180D02*
X1501275Y254895D01*
G01X1497857Y253180D02*
X1499560D01*
G01X1495845Y251168D02*
X1497857Y253180D01*
G01X1486631Y251168D02*
X1495845D01*
G01X1485600Y250137D02*
X1486631Y251168D01*
G01X1484011Y250137D02*
X1485600D01*
G01X1483552Y250596D02*
X1484011Y250137D01*
G01X1481039Y250596D02*
X1483552D01*
G01X1479655Y249212D02*
X1481039Y250596D01*
G01X1477188Y249212D02*
X1479655D01*
G01X1476600Y249800D02*
X1477188Y249212D01*
G01X1474108Y249800D02*
X1476600D01*
G01X1472613Y251295D02*
X1474108Y249800D01*
G01X1472613Y253535D02*
Y251295D01*
G01X1471372Y254776D02*
X1472613Y253535D01*
G01X1470328Y254776D02*
X1471372D01*
G01X1468846Y256258D02*
X1470328Y254776D01*
G01X1468846Y264595D02*
Y256258D01*
G01X1467498Y265943D02*
X1468846Y264595D01*
G01X1467498Y267875D02*
Y265943D01*
G01X1467743Y268120D02*
X1467498Y267875D01*
G01X1467743Y272488D02*
Y268120D01*
G01X1520873Y246769D02*
X1519300Y245196D01*
G01X1520873Y250902D02*
Y246769D01*
G01X1522184Y252213D02*
X1520873Y250902D01*
G01X1529490Y252213D02*
X1522184D01*
G01X1525633Y275167D02*
X1538133D01*
G01X1523700Y277100D02*
X1525633Y275167D01*
G01X1523700Y279400D02*
Y277100D01*
G01X1522500Y280600D02*
X1523700Y279400D01*
G01X1515900Y276200D02*
X1520300Y280600D01*
G01X1515900Y254200D02*
Y276200D01*
G01X1519300Y250800D02*
X1515900Y254200D01*
G01X1519300Y245196D02*
Y250800D01*
G01X1499070Y255560D02*
Y255934D01*
G01X1497210Y253700D02*
X1499070Y255560D01*
G01X1491098Y253700D02*
X1497210D01*
G01X1488651Y256147D02*
X1491098Y253700D01*
G01X1485959Y256147D02*
X1488651D01*
G01X1485612Y255800D02*
X1485959Y256147D01*
G01X1482673Y255800D02*
X1485612D01*
G01X1481000Y257473D02*
X1482673Y255800D01*
G01X1481000Y260000D02*
Y257473D01*
G01X1467469Y275693D02*
Y277500D01*
G01X1468567Y274595D02*
X1467469Y275693D01*
G01X1468567Y267778D02*
Y274595D01*
G01X1468322Y267533D02*
X1468567Y267778D01*
G01X1468322Y266285D02*
Y267533D01*
G01X1469307Y265300D02*
X1468322Y266285D01*
G01X1471200Y265300D02*
X1469307D01*
G01X1472000Y264500D02*
X1471200Y265300D01*
G01X1472000Y263500D02*
Y264500D01*
G01X1467469Y279872D02*
Y277500D01*
G01X1472675Y223500D02*
X1474287Y221888D01*
G01X1471250Y223500D02*
X1472675D01*
G01X1518812Y233573D02*
Y231532D01*
G01X1518107Y234278D02*
X1518812Y233573D01*
G01X1516549Y234278D02*
X1518107D01*
G01X1506340Y270340D02*
X1505500Y269500D01*
G01X1506340Y271586D02*
Y270340D01*
G01X1507003Y272249D02*
X1506340Y271586D01*
G01X1515312Y228149D02*
X1516450Y227011D01*
G01X1515312Y231532D02*
Y228149D01*
G01X1512696Y232250D02*
X1506950D01*
G01X1513414Y231532D02*
X1512696Y232250D01*
G01X1515312Y231532D02*
X1513414D01*
G01X1475000Y264947D02*
X1472824Y267123D01*
G01X1475000Y263500D02*
Y264947D01*
G01X1472250Y269650D02*
Y281504D01*
G01X1472824Y269076D02*
X1472250Y269650D01*
G01X1472824Y267123D02*
Y269076D01*
G01X1524074Y232451D02*
X1539138D01*
G01X1520590Y228967D02*
X1524074Y232451D01*
G01X1520590Y228375D02*
Y228967D01*
G01X1516435Y224220D02*
X1520590Y228375D01*
G01X1514226Y224220D02*
X1516435D01*
G01X1511196Y227250D02*
X1514226Y224220D01*
G01X1506950Y227250D02*
X1511196D01*
G01X1489680Y277560D02*
X1490963Y276277D01*
G01X1488407Y277560D02*
X1489680D01*
G01X1487214Y278753D02*
X1488407Y277560D01*
G01X1487214Y280924D02*
Y278753D01*
G01X1490300Y264650D02*
X1490310Y264640D01*
G01X1487230Y264650D02*
X1490300D01*
G01X1490310Y265720D02*
Y264640D01*
G01X1491090Y266500D02*
X1490310Y265720D01*
G01X1491090Y268110D02*
Y266500D01*
G01X1490253Y268947D02*
X1491090Y268110D01*
G01X1488653Y268947D02*
X1490253D01*
G01X1488039Y269561D02*
X1488653Y268947D01*
G01X1488039Y271078D02*
Y269561D01*
G01X1490963Y274002D02*
X1488039Y271078D01*
G01X1490963Y276277D02*
Y274002D01*
G01X1527024Y233876D02*
X1542868D01*
G01X1526600Y234300D02*
X1527024Y233876D01*
G01X1526150Y234300D02*
X1526600D01*
G01X1526848Y224896D02*
X1527870Y225918D01*
G01X1526848Y223224D02*
Y224896D01*
G01X1525400Y221776D02*
X1526848Y223224D01*
G01X1484890Y271078D02*
Y268660D01*
G01X1485773Y271961D02*
X1484890Y271078D01*
G01X1486886Y271961D02*
X1485773D01*
G01X1487904Y272979D02*
X1486886Y271961D01*
G01X1487904Y276193D02*
Y272979D01*
G01X1486305Y277792D02*
X1487904Y276193D01*
G01X1486305Y279994D02*
Y277792D01*
G01X1484000Y265500D02*
Y263500D01*
G01X1484890Y266390D02*
X1484000Y265500D01*
G01X1484890Y268660D02*
Y266390D01*
G01X1513170Y237000D02*
X1515250D01*
G01X1510420Y239750D02*
X1513170Y237000D01*
G01X1506950Y239750D02*
X1510420D01*
G01X1515009Y220600D02*
X1505151D01*
G01X1516409Y219200D02*
X1515009Y220600D01*
G01X1520890Y219200D02*
X1516409D01*
G01X1522717Y221027D02*
X1520890Y219200D01*
G01X1522717Y223517D02*
Y221027D01*
G01X1525422Y226222D02*
X1522717Y223517D01*
G01X1525422Y227625D02*
Y226222D01*
G01X1524479Y241237D02*
X1525567D01*
G01X1524159Y240917D02*
X1524479Y241237D01*
G01X1522781Y240917D02*
X1524159D01*
G01X1521807Y241891D02*
X1522781Y240917D01*
G01X1521807Y245243D02*
Y241891D01*
G01X1523150Y246586D02*
X1521807Y245243D01*
G01X1523150Y248700D02*
Y246586D01*
G01X1526740Y241237D02*
X1525567D01*
G01X1527003Y241500D02*
X1526740Y241237D01*
G01X1528750Y241500D02*
X1527003D01*
G01X1479600Y222850D02*
X1477500D01*
G01X1480090Y222360D02*
X1479600Y222850D01*
G01X1480090Y221100D02*
Y222360D01*
G01X1480782Y220408D02*
X1480090Y221100D01*
G01X1487765Y220408D02*
X1480782D01*
G01X1495231Y227874D02*
X1487765Y220408D01*
G01X1495231Y237158D02*
Y227874D01*
G01X1501740Y243667D02*
X1495231Y237158D01*
G01X1504953Y243667D02*
X1501740D01*
G01X1508100Y246814D02*
X1504953Y243667D01*
G01X1508100Y249701D02*
Y246814D01*
G01X1509373Y250974D02*
X1508100Y249701D01*
G01X1511440Y250974D02*
X1509373D01*
G01X1516203Y241066D02*
X1516613Y240656D01*
G01X1516203Y249381D02*
Y241066D01*
G01X1514610Y250974D02*
X1516203Y249381D01*
G01X1511440Y250974D02*
X1514610D01*
G01X1510401Y242250D02*
X1506950D01*
G01X1511500Y241151D02*
X1510401Y242250D01*
G01X1511500Y241150D02*
Y241151D01*
G01X1512551Y240099D02*
X1511500Y241150D01*
G01X1512790Y240099D02*
X1512551D01*
G01X1515848Y218000D02*
X1513900D01*
G01D02*
X1512004D01*
G01X1497044Y267665D02*
X1496030D01*
G01X1498387Y266322D02*
X1497044Y267665D01*
G01X1498387Y264666D02*
Y266322D01*
G01X1490310Y261140D02*
X1493450D01*
G01X1498387Y262071D02*
Y264666D01*
G01X1497456Y261140D02*
X1498387Y262071D01*
G01X1493450Y261140D02*
X1497456D01*
G01X1496482Y274983D02*
X1491053Y280412D01*
G01X1496482Y274048D02*
Y274983D01*
G01X1496812Y273718D02*
X1496482Y274048D01*
G01X1478400Y268600D02*
Y267500D01*
G01X1478500Y268700D02*
X1478400Y268600D01*
G01X1478500Y271400D02*
Y268700D01*
G01X1479100Y272000D02*
X1478500Y271400D01*
G01X1481644Y272000D02*
X1479100D01*
G01X1483247Y273603D02*
X1481644Y272000D01*
G01X1481000Y264000D02*
Y263500D01*
G01X1478400Y266600D02*
X1481000Y264000D01*
G01X1478400Y267500D02*
Y266600D01*
G01X1480652Y251800D02*
X1484700D01*
G01X1479189Y250337D02*
X1480652Y251800D01*
G01X1477654Y250337D02*
X1479189D01*
G01X1476183Y251808D02*
X1477654Y250337D01*
G01X1476183Y252429D02*
Y251808D01*
G01X1475209Y253403D02*
X1476183Y252429D01*
G01X1474588Y253403D02*
X1475209D01*
G01X1472400Y255591D02*
X1474588Y253403D01*
G01X1472400Y258000D02*
Y255591D01*
G01X1472000Y258400D02*
X1472400Y258000D01*
G01X1472000Y260000D02*
Y258400D01*
G01X1526508Y276592D02*
X1538724D01*
G01X1525800Y277300D02*
X1526508Y276592D01*
G01X1525800Y279400D02*
Y277300D01*
G01X1521120Y284080D02*
X1525800Y279400D01*
G01X1467040Y257304D02*
Y260357D01*
G01X1467400Y256944D02*
X1467040Y257304D01*
G01X1467400Y254452D02*
Y256944D01*
G01X1466787Y253839D02*
X1467400Y254452D01*
G01X1466787Y251174D02*
Y253839D01*
G01X1467008Y250953D02*
X1466787Y251174D01*
G01X1468438Y250953D02*
X1467008D01*
G01X1468517Y251032D02*
X1468438Y250953D01*
G01X1470659Y251032D02*
X1468517D01*
G01X1472816Y248875D02*
X1470659Y251032D01*
G01X1476216Y248875D02*
X1472816D01*
G01X1476804Y248287D02*
X1476216Y248875D01*
G01X1480039Y248287D02*
X1476804D01*
G01X1481423Y249671D02*
X1480039Y248287D01*
G01X1483168Y249671D02*
X1481423D01*
G01X1483627Y249212D02*
X1483168Y249671D01*
G01X1485984Y249212D02*
X1483627D01*
G01X1486472Y249700D02*
X1485984Y249212D01*
G01X1495686Y249700D02*
X1486472D01*
G01X1498241Y252255D02*
X1495686Y249700D01*
G01X1499944Y252255D02*
X1498241D01*
G01X1502200Y254511D02*
X1499944Y252255D01*
G01X1502200Y272165D02*
Y254511D01*
G01X1504461Y274426D02*
X1502200Y272165D01*
G01X1497969Y277100D02*
X1497082Y277987D01*
G01X1499900Y277100D02*
X1497969D01*
G01X1501700D02*
X1499900D01*
G01X1503496Y278896D02*
X1501700Y277100D01*
G01X1503496Y280694D02*
Y278896D01*
G01X1496848Y258361D02*
X1495696D01*
G01X1500350Y261863D02*
X1496848Y258361D01*
G01X1500350Y267651D02*
Y261863D01*
G01X1495000Y273001D02*
X1500350Y267651D01*
G01X1495000Y275141D02*
Y273001D01*
G01X1491746Y278395D02*
X1495000Y275141D01*
G01X1488922Y278395D02*
X1491746D01*
G01X1488039Y279278D02*
X1488922Y278395D01*
G01X1488039Y280582D02*
Y279278D01*
G01X1465800Y222513D02*
Y224068D01*
G01X1466476Y221837D02*
X1465800Y222513D01*
G01X1467305Y221837D02*
X1466476D01*
G01X1467750Y221392D02*
X1467305Y221837D01*
G01X1467750Y220000D02*
Y221392D01*
G01X1465700Y220000D02*
X1467750D01*
G01X1465600Y219900D02*
X1465700Y220000D01*
G01X1503842Y245887D02*
X1506137Y248182D01*
G01X1503842Y245678D02*
Y245887D01*
G01X1516584Y221216D02*
X1517608D01*
G01X1515700Y222100D02*
X1516584Y221216D01*
G01X1504635Y222100D02*
X1515700D01*
G01X1517608Y222408D02*
Y221216D01*
G01X1522015Y226815D02*
X1517608Y222408D01*
G01X1522015Y228376D02*
Y226815D01*
G01X1524264Y230625D02*
X1522015Y228376D01*
G01X1525422Y230625D02*
X1524264D01*
G01X1497246Y221900D02*
X1498022D01*
G01X1496082Y223064D02*
X1497246Y221900D01*
G01X1496082Y224465D02*
Y223064D01*
G01X1501400Y229783D02*
X1496082Y224465D01*
G01X1501400Y233687D02*
Y229783D01*
G01X1502463Y234750D02*
X1501400Y233687D01*
G01X1506950Y234750D02*
X1502463D01*
G01X1496041Y221237D02*
X1495406Y220602D01*
G01X1497359Y221237D02*
X1496041D01*
G01X1498022Y221900D02*
X1497359Y221237D01*
G01X1482512Y253972D02*
X1487078D01*
G01X1481984Y254500D02*
X1482512Y253972D01*
G01X1479000Y254500D02*
X1481984D01*
G01X1465830Y271083D02*
X1465904D01*
G01D02*
Y272395D01*
G01Y271083D02*
Y267672D01*
G01X1483708Y292960D02*
X1486397Y295649D01*
G01X1482996Y292960D02*
X1483708D01*
G01X1525992Y308678D02*
X1527625D01*
G01X1523810Y310860D02*
X1525992Y308678D01*
G01X1523810Y316190D02*
Y310860D01*
G01X1520760Y319240D02*
X1523810Y316190D01*
G01X1516960Y319240D02*
X1520760D01*
G01X1515050Y317330D02*
X1516960Y319240D01*
G01X1513370Y317330D02*
X1515050D01*
G01X1512390Y316350D02*
X1513370Y317330D01*
G01X1505256Y316350D02*
X1512390D01*
G01X1503538Y318068D02*
X1505256Y316350D01*
G01X1526987Y286243D02*
X1529041Y284189D01*
G01X1526987Y286367D02*
Y286243D01*
G01X1517449Y295905D02*
X1526987Y286367D01*
G01X1510605Y295905D02*
X1517449D01*
G01X1507619Y292919D02*
X1510605Y295905D01*
G01X1503892Y292919D02*
X1507619D01*
G01X1501293Y290320D02*
X1503892Y292919D01*
G01X1498508Y290320D02*
X1501293D01*
G01X1496628Y288440D02*
X1498508Y290320D01*
G01X1505400Y321940D02*
X1504200D01*
G01X1508170Y319170D02*
X1505400Y321940D01*
G01X1509560Y319170D02*
X1508170D01*
G01X1501961Y321940D02*
X1504200D01*
G01X1501500Y322401D02*
X1501961Y321940D01*
G01X1501500Y326210D02*
Y322401D01*
G01X1499010Y328700D02*
X1501500Y326210D01*
G01X1497056Y328700D02*
X1499010D01*
G01X1491993Y333763D02*
X1497056Y328700D01*
G01X1489136Y333763D02*
X1491993D01*
G01X1486150Y336749D02*
X1489136Y333763D01*
G01X1486150Y338330D02*
Y336749D01*
G01X1486340Y338520D02*
X1486150Y338330D01*
G01X1486340Y339578D02*
Y338520D01*
G01X1486195Y339723D02*
X1486340Y339578D01*
G01X1486195Y341101D02*
Y339723D01*
G01X1487813Y342719D02*
X1486195Y341101D01*
G01X1475400Y306646D02*
X1476948Y305098D01*
G01X1475400Y312055D02*
Y306646D01*
G01X1474501Y312954D02*
X1475400Y312055D01*
G01X1472887Y312954D02*
X1474501D01*
G01X1472248Y313593D02*
X1472887Y312954D01*
G01X1472248Y318227D02*
Y313593D01*
G01X1471624Y318851D02*
X1472248Y318227D01*
G01X1471624Y320916D02*
Y318851D01*
G01X1471920Y321212D02*
X1471624Y320916D01*
G01X1471920Y322618D02*
Y321212D01*
G01X1470946Y323592D02*
X1471920Y322618D01*
G01X1469422Y323592D02*
X1470946D01*
G01X1468851Y323021D02*
X1469422Y323592D01*
G01X1466008Y323021D02*
X1468851D01*
G01X1478550Y300400D02*
X1480098Y301948D01*
G01X1478550Y295120D02*
Y300400D01*
G01X1475997Y292567D02*
X1478550Y295120D01*
G01X1521350Y322550D02*
Y322417D01*
G01X1520445Y323455D02*
X1521350Y322550D01*
G01X1509235Y323455D02*
X1520445D01*
G01X1505630Y327060D02*
X1509235Y323455D01*
G01X1504200Y327060D02*
X1505630D01*
G01X1501980D02*
X1504200D01*
G01X1499414Y329626D02*
X1501980Y327060D01*
G01X1497538Y329626D02*
X1499414D01*
G01X1491164Y336000D02*
X1497538Y329626D01*
G01X1490500Y336000D02*
X1491164D01*
G01X1523935Y319832D02*
X1521350Y322417D01*
G01X1523935Y318901D02*
Y319832D01*
G01X1494376Y281476D02*
X1493700D01*
G01X1499093Y286193D02*
X1494376Y281476D01*
G01X1501720Y286193D02*
X1499093D01*
G01X1505227Y289700D02*
X1501720Y286193D01*
G01X1519100Y289700D02*
X1505227D01*
G01X1523768Y285032D02*
X1519100Y289700D01*
G01X1523768Y284908D02*
Y285032D01*
G01X1527708Y280968D02*
X1523768Y284908D01*
G01X1467542Y301991D02*
Y300987D01*
G01X1470649Y305098D02*
X1467542Y301991D01*
G01X1466402Y315400D02*
Y316598D01*
G01X1470405Y311397D02*
X1466402Y315400D01*
G01X1470649Y311397D02*
X1470405D01*
G01X1517463Y297200D02*
X1527913Y286750D01*
G01X1502648Y297200D02*
X1517463D01*
G01X1495021Y289573D02*
X1502648Y297200D01*
G01X1495021Y285831D02*
Y289573D01*
G01X1492093Y282903D02*
X1495021Y285831D01*
G01X1492093Y280704D02*
Y282903D01*
G01X1492499Y322400D02*
X1490500D01*
G01X1492959Y321940D02*
X1492499Y322400D01*
G01X1496800Y321940D02*
X1492959D01*
G01X1474163Y334800D02*
X1472500D01*
G01X1474626Y335263D02*
X1474163Y334800D01*
G01X1483336Y335263D02*
X1474626D01*
G01X1484700Y333899D02*
X1483336Y335263D01*
G01X1484700Y333100D02*
Y333899D01*
G01X1485763Y332037D02*
X1484700Y333100D01*
G01X1485763Y329426D02*
Y332037D01*
G01X1485337Y329000D02*
X1485763Y329426D01*
G01X1485337Y320788D02*
Y329000D01*
G01X1485925Y320200D02*
X1485337Y320788D01*
G01X1489963Y320200D02*
X1485925D01*
G01X1490500Y320737D02*
X1489963Y320200D01*
G01X1490500Y322400D02*
Y320737D01*
G01X1507100Y340630D02*
Y348140D01*
G01X1505948Y339478D02*
X1507100Y340630D01*
G01X1505847Y339478D02*
X1505948D01*
G01X1503269Y336900D02*
X1505847Y339478D01*
G01X1502850Y336900D02*
X1503269D01*
G01X1520300Y280600D02*
X1522500D01*
G01X1490243Y293943D02*
X1489600Y293300D01*
G01X1493268Y293943D02*
X1490243D01*
G01X1481740Y295160D02*
X1478287Y291707D01*
G01X1481740Y296273D02*
Y295160D01*
G01X1482623Y297156D02*
X1481740Y296273D01*
G01X1483736Y297156D02*
X1482623D01*
G01X1484890Y298310D02*
X1483736Y297156D01*
G01X1484890Y302572D02*
Y298310D01*
G01X1485773Y303455D02*
X1484890Y302572D01*
G01X1489155Y303455D02*
X1485773D01*
G01X1494692Y308992D02*
X1489155Y303455D01*
G01X1499266Y308992D02*
X1494692D01*
G01X1501584Y306674D02*
X1499266Y308992D01*
G01X1505935Y306674D02*
X1501584D01*
G01X1470649Y283052D02*
X1467469Y279872D01*
G01X1482585Y341335D02*
Y340856D01*
G01X1485850Y344600D02*
X1482585Y341335D01*
G01X1472250Y281504D02*
X1473798Y283052D01*
G01X1526062Y285859D02*
X1528658Y283263D01*
G01X1526062Y285983D02*
Y285859D01*
G01X1517065Y294980D02*
X1526062Y285983D01*
G01X1511080Y294980D02*
X1517065D01*
G01X1508094Y291994D02*
X1511080Y294980D01*
G01X1504276Y291994D02*
X1508094D01*
G01X1500769Y288487D02*
X1504276Y291994D01*
G01X1499987Y288487D02*
X1500769D01*
G01X1515952Y337792D02*
Y337082D01*
G01X1513390Y340354D02*
X1515952Y337792D01*
G01X1513390Y341910D02*
Y340354D01*
G01X1512514Y337520D02*
X1512952Y337082D01*
G01X1512514Y341086D02*
Y337520D01*
G01X1509975Y343625D02*
X1512514Y341086D01*
G01X1487215Y280925D02*
X1487214Y280924D01*
G01X1487215Y281115D02*
Y280925D01*
G01X1488161Y282061D02*
X1487215Y281115D01*
G01X1488161Y283601D02*
Y282061D01*
G01X1487169Y284593D02*
X1488161Y283601D01*
G01X1484856Y284593D02*
X1487169D01*
G01X1483247Y286202D02*
X1484856Y284593D01*
G01X1502690Y294890D02*
X1501550Y293750D01*
G01X1504217Y294890D02*
X1502690D01*
G01X1501610Y330970D02*
X1504370D01*
G01X1500660Y331920D02*
X1501610Y330970D01*
G01X1498489Y331920D02*
X1500660D01*
G01X1493180Y337229D02*
X1498489Y331920D01*
G01X1493180Y340473D02*
Y337229D01*
G01X1490418Y343235D02*
X1493180Y340473D01*
G01X1522220Y307877D02*
X1531131Y298966D01*
G01X1522220Y312180D02*
Y307877D01*
G01X1518060Y316340D02*
X1522220Y312180D01*
G01X1518060Y317520D02*
Y316340D01*
G01X1483247Y283052D02*
X1486305Y279994D01*
G01X1499723Y299354D02*
Y300106D01*
G01X1496052Y295683D02*
X1499723Y299354D01*
G01X1488562Y295683D02*
X1496052D01*
G01X1483761Y290882D02*
X1488562Y295683D01*
G01X1519160Y300606D02*
X1526900Y292866D01*
G01X1507500Y300606D02*
X1519160D01*
G01X1490254Y302656D02*
X1489546Y301948D01*
G01X1494835Y302656D02*
X1490254D01*
G01X1496862Y304683D02*
X1494835Y302656D01*
G01X1498156Y304683D02*
X1496862D01*
G01X1502233Y300606D02*
X1498156Y304683D01*
G01X1507500Y300606D02*
X1502233D01*
G01X1480500Y320300D02*
Y323500D01*
G01X1482200Y318600D02*
X1480500Y320300D01*
G01Y326500D02*
Y323500D01*
G01X1480281Y326719D02*
X1480500Y326500D01*
G01X1480281Y330195D02*
Y326719D01*
G01X1476531Y338695D02*
Y341847D01*
G01X1489546Y311746D02*
Y311397D01*
G01X1490683Y312883D02*
X1489546Y311746D01*
G01X1497057Y312883D02*
X1490683D01*
G01X1498430Y311510D02*
X1497057Y312883D01*
G01X1486397Y301903D02*
X1489200Y299100D01*
G01X1486397Y301948D02*
Y301903D01*
G01X1502425Y333400D02*
X1502850D01*
G01X1501611Y334214D02*
X1502425Y333400D01*
G01X1501606Y334214D02*
X1501611D01*
G01X1501120Y334700D02*
X1501606Y334214D01*
G01X1501120Y337279D02*
Y334700D01*
G01X1499853Y338546D02*
X1501120Y337279D01*
G01X1497997Y338546D02*
X1499853D01*
G01X1483506Y320935D02*
Y326061D01*
G01X1485141Y319300D02*
X1483506Y320935D01*
G01X1496109Y319300D02*
X1485141D01*
G01X1500109Y315300D02*
X1496109Y319300D01*
G01X1501630Y315300D02*
X1500109D01*
G01X1505500Y311430D02*
X1501630Y315300D01*
G01X1507450Y311430D02*
X1505500D01*
G01X1513755Y305125D02*
X1507450Y311430D01*
G01X1521365Y305125D02*
X1513755D01*
G01X1530620Y295870D02*
X1521365Y305125D01*
G01X1477000Y316824D02*
Y323500D01*
G01X1477393Y316431D02*
X1477000Y316824D01*
G01X1470276Y332502D02*
Y330774D01*
G01X1470911Y333137D02*
X1470276Y332502D01*
G01X1474647Y333137D02*
X1470911D01*
G01X1477000Y330784D02*
X1474647Y333137D01*
G01X1477000Y323500D02*
Y330784D01*
G01X1468450Y306048D02*
X1467613D01*
G01X1470649Y308247D02*
X1468450Y306048D01*
G01X1517794Y341240D02*
X1521952Y337082D01*
G01X1515760Y341240D02*
X1517794D01*
G01X1515189Y341811D02*
X1515760Y341240D01*
G01X1487020Y289351D02*
X1483247D01*
G01X1488354Y288017D02*
X1487020Y289351D01*
G01X1490044Y288017D02*
X1488354D01*
G01X1491053Y287008D02*
X1490044Y288017D01*
G01X1491053Y280412D02*
Y287008D01*
G01X1527409Y310103D02*
X1525677Y311835D01*
G01X1518952Y338278D02*
Y337082D01*
G01X1517470Y339760D02*
X1518952Y338278D01*
G01X1515790Y339760D02*
X1517470D01*
G01X1514350Y341200D02*
X1515790Y339760D01*
G01X1514350Y350897D02*
Y341200D01*
G01X1471568Y325531D02*
X1471562D01*
G01X1473371Y323728D02*
X1471568Y325531D01*
G01X1473371Y322383D02*
Y323728D01*
G01X1474838Y320916D02*
X1473371Y322383D01*
G01X1474838Y315851D02*
Y320916D01*
G01X1478591Y312098D02*
X1474838Y315851D01*
G01X1478591Y310773D02*
Y312098D01*
G01X1479564Y309800D02*
X1478591Y310773D01*
G01X1483825Y309800D02*
X1479564D01*
G01X1484890Y308735D02*
X1483825Y309800D01*
G01X1484890Y307623D02*
Y308735D01*
G01X1485773Y306740D02*
X1484890Y307623D01*
G01X1490474Y306740D02*
X1485773D01*
G01X1493564Y309830D02*
X1490474Y306740D01*
G01X1505603Y309830D02*
X1493564D01*
G01X1505923Y309510D02*
X1505603Y309830D01*
G01X1520632Y284080D02*
X1521120D01*
G01X1518006Y286706D02*
X1520632Y284080D01*
G01X1503519Y282000D02*
Y283694D01*
G01X1503496Y281977D02*
X1503519Y282000D01*
G01X1503496Y280694D02*
Y281977D01*
G01X1489102Y281645D02*
X1488039Y280582D01*
G01X1489102Y284084D02*
Y281645D01*
G01X1487904Y285282D02*
X1489102Y284084D01*
G01X1487904Y286874D02*
Y285282D01*
G01X1487069Y287709D02*
X1487904Y286874D01*
G01X1479474Y287709D02*
X1487069D01*
G01X1478456Y286691D02*
X1479474Y287709D01*
G01X1478456Y282427D02*
Y286691D01*
G01X1477438Y281409D02*
X1478456Y282427D01*
G01X1475305Y281409D02*
X1477438D01*
G01X1473798Y279902D02*
X1475305Y281409D01*
G01X1510584Y327406D02*
Y330640D01*
G01X1512130Y325860D02*
X1510584Y327406D01*
G01X1513328Y325860D02*
X1512130D01*
G01X1513361Y325827D02*
X1513328Y325860D01*
G01X1514739Y325827D02*
X1513361D01*
G01X1514772Y325860D02*
X1514739Y325827D01*
G01X1527230Y325860D02*
X1514772D01*
G01X1469801Y321473D02*
X1470257Y321929D01*
G01X1469801Y318200D02*
Y321473D01*
G01X1469151Y317550D02*
X1469801Y318200D01*
G01X1469151Y315179D02*
Y317550D01*
G01X1469142Y315170D02*
X1469151Y315179D01*
G01X1469142Y313922D02*
Y315170D01*
G01X1470160Y312904D02*
X1469142Y313922D01*
G01X1471273Y312904D02*
X1470160D01*
G01X1472156Y312021D02*
X1471273Y312904D01*
G01X1472156Y310773D02*
Y312021D01*
G01X1471273Y309890D02*
X1472156Y310773D01*
G01X1468898Y309890D02*
X1471273D01*
G01X1468483Y309475D02*
X1468898Y309890D01*
G01X1466832Y309475D02*
X1468483D01*
G01X1465857Y308500D02*
X1466832Y309475D01*
G01X1465857Y307623D02*
Y308500D01*
G01X1521392Y303082D02*
X1528563Y295911D01*
G01X1517700Y303082D02*
X1521392D01*
G01X1493500Y304996D02*
Y304400D01*
G01X1496512Y308008D02*
X1493500Y304996D01*
G01X1498234Y308008D02*
X1496512D01*
G01X1503160Y303082D02*
X1498234Y308008D01*
G01X1517700Y303082D02*
X1503160D01*
G01X1521761Y306320D02*
X1530540Y297541D01*
G01X1516300Y306320D02*
X1521761D01*
G01X1513990Y308630D02*
X1516300Y306320D01*
G01X1513990Y312260D02*
Y308630D01*
G01X1511440Y314810D02*
X1513990Y312260D01*
G01X1503790Y314810D02*
X1511440D01*
G01X1500393Y318207D02*
X1503790Y314810D01*
G01X1500151Y318207D02*
X1500393D01*
G01X1499177Y319181D02*
X1500151Y318207D01*
G01X1499177Y320559D02*
Y319181D01*
G01X1499990Y321372D02*
X1499177Y320559D01*
G01X1499990Y325219D02*
Y321372D01*
G01X1498149Y327060D02*
X1499990Y325219D01*
G01X1496800Y327060D02*
X1498149D01*
G01X1491640Y332100D02*
X1490000D01*
G01X1496680Y327060D02*
X1491640Y332100D01*
G01X1496800Y327060D02*
X1496680D01*
G01X1509025Y339265D02*
Y348874D01*
G01X1511270Y337020D02*
X1509025Y339265D01*
G01X1511270Y332875D02*
Y337020D01*
G01X1510705Y332310D02*
X1511270Y332875D01*
G01X1509870Y332310D02*
X1510705D01*
G01X1508900Y331340D02*
X1509870Y332310D01*
G01X1508900Y325720D02*
Y331340D01*
G01X1510240Y324380D02*
X1508900Y325720D01*
G01X1522740Y324380D02*
X1510240D01*
G01X1526660Y320460D02*
X1522740Y324380D01*
G01X1526660Y315900D02*
Y320460D01*
G01X1474227Y339277D02*
X1472450Y337500D01*
G01X1474227Y342087D02*
Y339277D01*
G01X1509739Y313041D02*
X1508455D01*
G01X1511710Y311070D02*
X1509739Y313041D01*
G01X1491768Y396021D02*
X1493375Y394414D01*
G01X1488563Y396021D02*
X1491768D01*
G01X1486961Y394419D02*
X1488563Y396021D01*
G01X1486961Y393465D02*
Y394419D01*
G01X1485566Y392070D02*
X1486961Y393465D01*
G01X1482992Y392070D02*
X1485566D01*
G01X1477078Y386156D02*
X1482992Y392070D01*
G01X1472666Y386156D02*
X1477078D01*
G01X1471742Y387080D02*
X1472666Y386156D01*
G01X1465550Y383870D02*
X1468190D01*
G01X1494337Y348587D02*
X1493000Y347250D01*
G01X1494337Y351317D02*
Y348587D01*
G01X1496529Y353509D02*
X1494337Y351317D01*
G01X1496529Y358225D02*
Y353509D01*
G01X1498309Y360005D02*
X1496529Y358225D01*
G01X1487813Y353115D02*
Y342719D01*
G01X1491681Y356983D02*
X1487813Y353115D01*
G01X1491681Y363181D02*
Y356983D01*
G01X1499350Y370850D02*
X1491681Y363181D01*
G01X1505075Y376575D02*
X1499350Y370850D01*
G01X1505075Y380894D02*
Y376575D01*
G01X1485294Y380894D02*
X1489475D01*
G01X1480654Y376254D02*
X1485294Y380894D01*
G01X1479255Y376254D02*
X1480654D01*
G01X1526448Y353890D02*
X1527478Y352860D01*
G01X1526448Y357515D02*
Y353890D01*
G01X1524746Y359217D02*
X1526448Y357515D01*
G01X1475199Y358750D02*
X1475500D01*
G01X1473537Y357088D02*
X1475199Y358750D01*
G01X1473537Y354671D02*
Y357088D01*
G01X1472331Y353465D02*
X1473537Y354671D01*
G01X1470467Y353465D02*
X1472331D01*
G01X1497235Y376035D02*
X1495300Y374100D01*
G01X1497235Y378581D02*
Y376035D01*
G01X1499225Y380571D02*
X1497235Y378581D01*
G01X1499225Y384274D02*
Y380571D01*
G01X1466967Y353465D02*
X1470467D01*
G01X1475578Y358750D02*
X1475500D01*
G01X1475578Y360693D02*
Y358750D01*
G01X1476589Y361704D02*
X1475578Y360693D01*
G01X1476589Y362046D02*
Y361704D01*
G01X1478436Y363893D02*
X1476589Y362046D01*
G01X1479166Y363893D02*
X1478436D01*
G01X1482616Y367343D02*
X1479166Y363893D01*
G01X1484675Y367343D02*
X1482616D01*
G01X1486713Y369381D02*
X1484675Y367343D01*
G01X1489703Y369381D02*
X1486713D01*
G01X1490827Y370505D02*
X1489703Y369381D01*
G01X1491705Y370505D02*
X1490827D01*
G01X1495300Y374100D02*
X1491705Y370505D01*
G01X1483497Y374532D02*
Y375917D01*
G01X1482118Y373153D02*
X1483497Y374532D01*
G01X1476403Y373153D02*
X1482118D01*
G01X1469750Y366500D02*
X1476403Y373153D01*
G01X1483497Y375917D02*
Y376500D01*
G01X1501360Y365819D02*
X1498246Y362705D01*
G01X1501360Y367320D02*
Y365819D01*
G01X1501040Y348210D02*
X1502000Y347250D01*
G01X1501040Y359911D02*
Y348210D01*
G01X1498246Y362705D02*
X1501040Y359911D01*
G01X1479000Y392900D02*
X1476100Y390000D01*
G01X1479000Y394900D02*
Y392900D01*
G01Y398400D02*
Y394900D01*
G01X1480296Y398400D02*
X1479000D01*
G01X1481313Y397383D02*
X1480296Y398400D01*
G01X1482923Y397383D02*
X1481313D01*
G01X1483334Y397794D02*
X1482923Y397383D01*
G01X1487525Y397794D02*
X1483334D01*
G01X1504600Y368034D02*
Y372200D01*
G01X1505887Y366747D02*
X1504600Y368034D01*
G01X1505887Y365808D02*
Y366747D01*
G01X1505900Y365795D02*
X1505887Y365808D01*
G01X1505900Y362368D02*
Y365795D01*
G01X1504900Y361368D02*
X1505900Y362368D01*
G01X1504900Y356270D02*
Y361368D01*
G01X1504540Y355910D02*
X1504900Y356270D01*
G01X1504540Y351392D02*
Y355910D01*
G01X1504633Y351299D02*
X1504540Y351392D01*
G01X1504633Y350607D02*
Y351299D01*
G01X1507100Y348140D02*
X1504633Y350607D01*
G01X1504600Y372768D02*
X1507880Y376048D01*
G01X1504600Y372200D02*
Y372768D01*
G01X1475980Y384030D02*
X1472940D01*
G01X1476150Y383860D02*
X1475980Y384030D01*
G01X1469000Y345850D02*
X1467666D01*
G01X1523700Y363741D02*
Y366200D01*
G01X1524300Y363141D02*
X1523700Y363741D01*
G01X1524300Y361298D02*
Y363141D01*
G01X1522917Y359915D02*
X1524300Y361298D01*
G01X1522917Y353451D02*
Y359915D01*
G01X1523891Y352477D02*
X1522917Y353451D01*
G01X1523891Y349359D02*
Y352477D01*
G01X1526000Y347250D02*
X1523891Y349359D01*
G01X1523700Y374500D02*
Y366200D01*
G01X1524500Y375300D02*
X1523700Y374500D01*
G01X1524500Y378000D02*
Y375300D01*
G01X1526500Y380000D02*
X1524500Y378000D01*
G01X1526500Y381926D02*
Y380000D01*
G01X1528475Y383901D02*
X1526500Y381926D01*
G01X1517000Y347232D02*
Y346650D01*
G01X1519119Y349351D02*
X1517000Y347232D01*
G01X1519119Y350747D02*
Y349351D01*
G01X1517028Y352838D02*
X1519119Y350747D01*
G01X1517028Y355117D02*
Y352838D01*
G01X1516603Y355542D02*
X1517028Y355117D01*
G01X1514265Y355542D02*
X1516603D01*
G01X1525783Y372872D02*
X1530425Y377514D01*
G01X1525783Y360717D02*
Y372872D01*
G01X1527873Y358627D02*
X1525783Y360717D01*
G01X1498246Y349496D02*
Y352305D01*
G01X1496000Y347250D02*
X1498246Y349496D01*
G01X1513250Y369592D02*
Y374794D01*
G01X1510870Y367212D02*
X1513250Y369592D01*
G01X1510870Y353168D02*
Y367212D01*
G01X1512847Y351191D02*
X1510870Y353168D01*
G01X1512847Y349447D02*
Y351191D01*
G01X1512000Y348600D02*
X1512847Y349447D01*
G01X1512000Y346100D02*
Y348600D01*
G01Y343300D02*
X1513390Y341910D01*
G01X1512000Y346100D02*
Y343300D01*
G01X1480215Y377964D02*
X1483552Y381301D01*
G01X1471964Y377964D02*
X1480215D01*
G01X1471424Y377424D02*
X1471964Y377964D01*
G01X1471424Y372624D02*
Y377424D01*
G01X1469750Y370950D02*
X1471424Y372624D01*
G01X1469750Y369500D02*
Y370950D01*
G01X1509975Y349275D02*
Y343625D01*
G01X1509320Y349930D02*
X1509975Y349275D01*
G01X1509320Y351430D02*
Y349930D01*
G01X1510012Y352122D02*
X1509320Y351430D01*
G01X1510012Y372088D02*
Y352122D01*
G01X1509800Y372300D02*
X1510012Y372088D01*
G01X1511800Y374300D02*
Y375089D01*
G01X1509800Y372300D02*
X1511800Y374300D01*
G01X1470100Y361030D02*
Y360500D01*
G01X1472565Y363495D02*
X1470100Y361030D01*
G01X1472565Y366389D02*
Y363495D01*
G01X1474931Y368755D02*
X1472565Y366389D01*
G01X1480355Y368755D02*
X1474931D01*
G01X1481999Y370399D02*
X1480355Y368755D01*
G01X1483658Y370399D02*
X1481999D01*
G01X1485799Y372540D02*
X1483658Y370399D01*
G01X1488699Y372540D02*
X1485799D01*
G01X1491802Y375643D02*
X1488699Y372540D01*
G01X1490418Y347913D02*
Y343235D01*
G01X1491700Y349195D02*
X1490418Y347913D01*
G01X1491700Y352120D02*
Y349195D01*
G01X1493600Y354020D02*
X1491700Y352120D01*
G01X1494023Y354443D02*
Y358353D01*
G01X1493600Y354020D02*
X1494023Y354443D01*
G01X1502800Y354757D02*
Y356420D01*
G01X1502810Y354747D02*
X1502800Y354757D01*
G01X1502810Y350770D02*
Y354747D01*
G01X1502970Y350610D02*
X1502810Y350770D01*
G01X1505000Y348580D02*
X1502970Y350610D01*
G01X1505000Y347250D02*
Y348580D01*
G01X1500000Y348250D02*
Y353010D01*
G01X1499000Y347250D02*
X1500000Y348250D01*
G01Y355751D02*
X1498246Y357505D01*
G01X1500000Y353010D02*
Y355751D01*
G01X1481401Y355910D02*
X1481081Y356230D01*
G01X1483024Y355910D02*
X1481401D01*
G01X1483867Y356753D02*
X1483024Y355910D01*
G01X1481164Y357855D02*
Y359387D01*
G01X1481081Y357772D02*
X1481164Y357855D01*
G01X1481081Y356230D02*
Y357772D01*
G01X1475466Y370800D02*
X1477800D01*
G01X1471413Y366747D02*
X1475466Y370800D01*
G01X1471413Y365226D02*
Y366747D01*
G01X1470850Y364663D02*
X1471413Y365226D01*
G01X1466908Y364663D02*
X1470850D01*
G01X1466565Y364320D02*
X1466908Y364663D01*
G01X1485789Y374619D02*
Y375791D01*
G01X1483136Y371966D02*
X1485789Y374619D01*
G01X1481125Y371966D02*
X1483136D01*
G01X1479959Y370800D02*
X1481125Y371966D01*
G01X1477800Y370800D02*
X1479959D01*
G01X1484499Y350500D02*
X1485850D01*
G01X1482750Y348751D02*
X1484499Y350500D01*
G01X1482750Y344250D02*
Y348751D01*
G01X1481750Y343250D02*
X1482750Y344250D01*
G01X1481000Y343250D02*
X1481750D01*
G01X1477934D02*
X1481000D01*
G01X1476531Y341847D02*
X1477934Y343250D01*
G01X1496834Y371134D02*
X1500134Y374434D01*
G01X1496834Y370566D02*
Y371134D01*
G01X1490142Y363874D02*
X1496834Y370566D01*
G01X1490142Y357042D02*
Y363874D01*
G01X1486800Y353700D02*
X1490142Y357042D01*
G01X1486800Y351300D02*
Y353700D01*
G01X1486000Y350500D02*
X1486800Y351300D01*
G01X1485850Y350500D02*
X1486000D01*
G01X1470200Y356641D02*
Y357500D01*
G01X1469121Y355562D02*
X1470200Y356641D01*
G01X1474626Y361607D02*
Y362517D01*
G01X1471112Y358093D02*
X1474626Y361607D01*
G01X1471112Y358081D02*
Y358093D01*
G01X1471106Y358075D02*
X1471112Y358081D01*
G01X1471075Y358075D02*
X1471106D01*
G01X1470500Y357500D02*
X1471075Y358075D01*
G01X1470200Y357500D02*
X1470500D01*
G01X1489031Y371078D02*
X1493449Y375496D01*
G01X1486425Y371078D02*
X1489031D01*
G01X1484218Y368871D02*
X1486425Y371078D01*
G01X1482560Y368871D02*
X1484218D01*
G01X1480918Y367229D02*
X1482560Y368871D01*
G01X1476514Y367229D02*
X1480918D01*
G01X1476112Y366827D02*
X1476514Y367229D01*
G01X1476112Y364003D02*
Y366827D01*
G01X1474626Y362517D02*
X1476112Y364003D01*
G01X1515189Y351231D02*
Y341811D01*
G01X1512580Y353840D02*
X1515189Y351231D01*
G01X1512580Y364481D02*
Y353840D01*
G01X1517150Y369051D02*
X1512580Y364481D01*
G01X1471283Y382409D02*
X1469887Y381013D01*
G01X1473610Y382409D02*
X1471283D01*
G01X1474619Y381400D02*
X1473610Y382409D01*
G01X1477560Y381400D02*
X1474619D01*
G01X1478730Y382570D02*
X1477560Y381400D01*
G01X1478730Y386594D02*
Y382570D01*
G01X1480967Y388831D02*
X1478730Y386594D01*
G01X1482811Y388831D02*
X1480967D01*
G01X1483022Y388620D02*
X1482811Y388831D01*
G01X1484536Y388620D02*
X1483022D01*
G01X1489475Y393559D02*
X1484536Y388620D01*
G01X1489475Y394414D02*
Y393559D01*
G01X1523000Y351945D02*
Y347250D01*
G01X1522092Y352853D02*
X1523000Y351945D01*
G01X1522092Y359588D02*
Y352853D01*
G01X1520517Y361163D02*
X1522092Y359588D01*
G01X1520517Y362889D02*
Y361163D01*
G01X1521500Y363872D02*
X1520517Y362889D01*
G01X1521500Y367410D02*
Y363872D01*
G01X1521050Y367860D02*
X1521500Y367410D01*
G01X1521050Y371700D02*
Y367860D01*
G01Y374500D02*
Y371700D01*
G01X1479807Y378788D02*
X1482734Y381715D01*
G01X1471388Y378788D02*
X1479807D01*
G01X1470600Y378000D02*
X1471388Y378788D01*
G01X1470600Y373378D02*
Y378000D01*
G01X1469000Y371778D02*
X1470600Y373378D01*
G01X1511730Y353517D02*
X1514350Y350897D01*
G01X1511730Y365937D02*
Y353517D01*
G01X1515183Y369390D02*
X1511730Y365937D01*
G01X1515183Y372400D02*
Y369390D01*
G01Y374643D02*
X1515860Y375320D01*
G01X1515183Y372400D02*
Y374643D01*
G01X1502800Y362099D02*
Y359920D01*
G01X1503878Y363177D02*
X1502800Y362099D01*
G01X1503878Y364717D02*
Y363177D01*
G01X1493881Y370568D02*
X1491000Y367687D01*
G01X1494932Y370568D02*
X1493881D01*
G01X1499457Y375093D02*
X1494932Y370568D01*
G01X1487187Y367687D02*
X1491000D01*
G01X1485913Y366413D02*
X1487187Y367687D01*
G01X1485913Y356446D02*
Y366413D01*
G01X1482967Y353500D02*
X1485913Y356446D01*
G01X1482140Y353500D02*
X1482967D01*
G01X1480890Y352250D02*
X1482140Y353500D01*
G01X1477500Y352250D02*
X1480890D01*
G01X1496035Y365405D02*
X1498183D01*
G01X1494023Y363393D02*
X1496035Y365405D01*
G01X1494023Y361853D02*
Y363393D01*
G01X1481411Y401900D02*
X1479200D01*
G01X1483476Y399835D02*
X1481411Y401900D01*
G01X1487981Y399835D02*
X1483476D01*
G01X1488555Y399261D02*
X1487981Y399835D01*
G01X1490289Y399261D02*
X1488555D01*
G01X1490734Y399706D02*
X1490289Y399261D01*
G01X1492182Y399706D02*
X1490734D01*
G01X1492601Y399287D02*
X1492182Y399706D01*
G01X1494074Y399287D02*
X1492601D01*
G01X1494532Y399745D02*
X1494074Y399287D01*
G01X1496034Y399745D02*
X1494532D01*
G01X1496602Y399177D02*
X1496034Y399745D01*
G01X1497906Y399177D02*
X1496602D01*
G01X1498279Y399550D02*
X1497906Y399177D01*
G01X1499988Y399550D02*
X1498279D01*
G01X1501175Y398363D02*
X1499988Y399550D01*
G01X1501175Y394414D02*
Y398363D01*
G01X1518245Y363971D02*
Y361300D01*
G01X1517521Y364695D02*
X1518245Y363971D01*
G01X1517521Y366667D02*
Y364695D01*
G01X1519000Y368146D02*
X1517521Y366667D01*
G01X1519000Y374500D02*
Y368146D01*
G01X1519500Y375000D02*
X1519000Y374500D01*
G01X1520000Y351775D02*
Y347250D01*
G01X1518245Y353530D02*
X1520000Y351775D01*
G01X1518245Y361300D02*
Y353530D01*
G01X1479829Y362887D02*
X1478612Y361670D01*
G01X1481164Y362887D02*
X1479829D01*
G01X1507800Y362800D02*
Y366600D01*
G01X1509000Y361600D02*
X1507800Y362800D01*
G01X1509000Y352500D02*
Y361600D01*
G01X1508306Y351806D02*
X1509000Y352500D01*
G01X1508306Y349593D02*
Y351806D01*
G01X1509025Y348874D02*
X1508306Y349593D01*
G01X1507800Y373698D02*
X1508507Y374405D01*
G01X1507800Y366600D02*
Y373698D01*
G01X1526962Y361129D02*
X1529522Y358569D01*
G01X1526962Y370962D02*
Y361129D01*
G01X1528339Y372339D02*
X1526962Y370962D01*
G01X1477500Y345360D02*
X1474227Y342087D01*
G01X1477500Y348750D02*
Y345360D01*
G01X1475437Y347389D02*
X1474049D01*
G01X1476798Y348750D02*
X1475437Y347389D01*
G01X1477500Y348750D02*
X1476798D01*
G01X1502302Y409787D02*
Y410686D01*
G01X1504155Y407934D02*
X1502302Y409787D01*
G01X1505075Y407934D02*
X1504155D01*
G01X1506800Y449231D02*
Y451000D01*
G01X1505714Y448145D02*
X1506800Y449231D01*
G01X1524300Y517100D02*
X1531264D01*
G01X1520747Y513547D02*
X1524300Y517100D01*
G01X1520747Y508200D02*
Y513547D01*
G01Y497948D02*
Y508200D01*
G01X1518350Y495551D02*
X1520747Y497948D01*
G01X1518350Y491628D02*
Y495551D01*
G01X1521806Y498636D02*
X1522870Y499700D01*
G01X1521806Y497705D02*
Y498636D01*
G01X1520300Y496199D02*
X1521806Y497705D01*
G01X1520300Y494000D02*
Y496199D01*
G01Y492331D02*
Y494000D01*
G01X1475883Y618787D02*
Y619217D01*
G01X1477800Y616870D02*
X1475883Y618787D01*
G01X1477800Y615500D02*
Y616870D01*
G01X1480994Y615500D02*
X1477800D01*
G01X1481778Y614716D02*
X1480994Y615500D01*
G01X1512484Y616032D02*
X1512100Y616416D01*
G01X1516158Y616032D02*
X1512484D01*
G01X1512100Y619160D02*
Y616416D01*
G01X1511204Y620056D02*
X1512100Y619160D01*
G01X1576998Y30416D02*
Y51531D01*
G01X1574012Y27430D02*
X1576998Y30416D01*
G01X1555065Y27430D02*
X1574012D01*
G01X1553725Y26090D02*
X1555065Y27430D01*
G01X1553725Y24565D02*
Y26090D01*
G01X1554434Y23856D02*
X1553725Y24565D01*
G01X1580398Y5400D02*
Y2300D01*
G01D02*
Y-600D01*
G01X1545000Y-10846D02*
Y-15000D01*
G01X1533479Y675D02*
X1545000Y-10846D01*
G01X1550100Y-20100D02*
X1545000Y-15000D01*
G01X1566743Y-20100D02*
X1550100D01*
G01X1566818Y-20025D02*
X1566743Y-20100D01*
G01X1617723Y-20025D02*
X1566818D01*
G01X1531200Y12218D02*
X1528482D01*
G01X1583256Y26343D02*
Y29400D01*
G01X1575413Y18500D02*
X1583256Y26343D01*
G01X1539890Y18500D02*
X1575413D01*
G01X1533608Y12218D02*
X1539890Y18500D01*
G01X1531200Y12218D02*
X1533608D01*
G01X1583256Y31856D02*
X1584700Y33300D01*
G01X1583256Y29400D02*
Y31856D01*
G01X1531520Y21170D02*
X1528970Y18620D01*
G01X1531520Y24982D02*
Y21170D01*
G01X1537838Y31300D02*
X1531520Y24982D01*
G01X1568685Y31300D02*
X1537838D01*
G01X1569553Y32168D02*
X1568685Y31300D01*
G01X1570763Y33378D02*
X1569553Y32168D01*
G01X1546800Y5130D02*
X1547716Y6046D01*
G01X1546800Y3400D02*
Y5130D01*
G01X1533900Y5825D02*
X1533375Y5300D01*
G01X1533900Y9054D02*
Y5825D01*
G01X1533295Y9659D02*
X1533900Y9054D01*
G01X1531200Y9659D02*
X1533295D01*
G01X1528825D02*
X1531200D01*
G01X1527979Y10505D02*
X1528825Y9659D01*
G01X1549550Y-14087D02*
X1533863Y1600D01*
G01X1549550Y-15084D02*
Y-14087D01*
G01X1553475Y-19009D02*
X1549550Y-15084D01*
G01X1617391Y-19009D02*
X1553475D01*
G01X1535000Y-6220D02*
X1530367Y-1587D01*
G01X1535000Y-15000D02*
Y-6220D01*
G01X1584000Y-14000D02*
Y-16100D01*
G01X1584700Y-13300D02*
X1584000Y-14000D01*
G01X1586600Y-13300D02*
X1584700D01*
G01X1549183Y20100D02*
X1545111Y24172D01*
G01X1575443Y20100D02*
X1549183D01*
G01X1581260Y25917D02*
X1575443Y20100D01*
G01X1581260Y47999D02*
Y25917D01*
G01X1583938Y-11637D02*
X1583001Y-10700D01*
G01X1589337Y-11637D02*
X1583938D01*
G01X1576073Y30868D02*
Y51147D01*
G01X1573560Y28355D02*
X1576073Y30868D01*
G01X1554395Y28355D02*
X1573560D01*
G01X1552700Y26660D02*
X1554395Y28355D01*
G01X1552700Y24722D02*
Y26660D01*
G01X1551834Y23856D02*
X1552700Y24722D01*
G01X1585800Y27331D02*
Y57100D01*
G01X1575869Y17400D02*
X1585800Y27331D01*
G01X1540346Y17400D02*
X1575869D01*
G01X1536641Y13695D02*
X1540346Y17400D01*
G01X1536641Y11159D02*
Y13695D01*
G01X1539100Y8700D02*
X1536641Y11159D01*
G01X1560700Y8700D02*
X1539100D01*
G01X1566000Y3400D02*
X1560700Y8700D01*
G01X1571298Y76183D02*
X1570511Y75396D01*
G01X1571298Y76786D02*
Y76183D01*
G01X1570535Y77549D02*
X1571298Y76786D01*
G01X1569138Y77549D02*
X1570535D01*
G01X1568713Y77124D02*
X1569138Y77549D01*
G01X1568713Y70348D02*
Y77124D01*
G01X1570476Y68585D02*
X1568713Y70348D01*
G01X1570476Y60285D02*
Y68585D01*
G01X1572778Y57983D02*
X1570476Y60285D01*
G01X1572778Y55751D02*
Y57983D01*
G01X1576998Y51531D02*
X1572778Y55751D01*
G01X1581652Y71208D02*
X1590293Y62567D01*
G01X1581652Y75086D02*
Y71208D01*
G01X1582407Y75841D02*
X1581652Y75086D01*
G01X1565565Y83569D02*
Y101116D01*
G01X1557248Y75252D02*
X1565565Y83569D01*
G01X1554055Y75252D02*
X1557248D01*
G01X1548547Y69744D02*
X1554055Y75252D01*
G01X1548547Y65716D02*
Y69744D01*
G01X1586200Y78688D02*
X1588962Y75926D01*
G01X1586200Y82200D02*
Y78688D01*
G01X1585100Y83300D02*
X1586200Y82200D01*
G01X1582400Y83300D02*
X1585100D01*
G01X1576900Y77800D02*
X1582400Y83300D01*
G01X1576900Y70708D02*
Y77800D01*
G01X1576337Y70145D02*
X1576900Y70708D01*
G01X1576337Y65007D02*
Y70145D01*
G01X1584700Y56644D02*
X1576337Y65007D01*
G01X1584700Y33300D02*
Y56644D01*
G01X1570763Y56740D02*
Y33378D01*
G01X1568626Y58877D02*
X1570763Y56740D01*
G01X1568626Y67817D02*
Y58877D01*
G01X1566863Y69580D02*
X1568626Y67817D01*
G01X1566863Y79095D02*
Y69580D01*
G01X1568891Y81123D02*
X1566863Y79095D01*
G01X1568891Y91944D02*
Y81123D01*
G01X1572586Y95639D02*
X1568891Y91944D01*
G01X1545987Y45008D02*
X1548050Y42945D01*
G01X1545987Y49536D02*
Y45008D01*
G01X1543842Y42945D02*
X1548050D01*
G01X1543200Y42303D02*
X1543842Y42945D01*
G01X1549004Y38491D02*
X1548050Y39445D01*
G01X1549004Y37105D02*
Y38491D01*
G01X1551975Y34134D02*
X1549004Y37105D01*
G01X1557744Y34134D02*
X1551975D01*
G01X1565637Y42027D02*
X1557744Y34134D01*
G01X1565637Y52524D02*
Y42027D01*
G01X1559909Y70928D02*
Y68218D01*
G01X1561179Y72198D02*
X1559909Y70928D01*
G01X1561179Y74835D02*
Y72198D01*
G01X1562575Y76231D02*
X1561179Y74835D01*
G01X1562613Y76231D02*
X1562575D01*
G01X1564572Y74272D02*
X1562613Y76231D01*
G01X1564572Y69028D02*
Y74272D01*
G01X1566276Y67324D02*
X1564572Y69028D01*
G01X1566276Y58209D02*
Y67324D01*
G01X1565637Y57570D02*
X1566276Y58209D01*
G01X1565637Y52524D02*
Y57570D01*
G01X1544814Y82298D02*
Y80985D01*
G01X1544707Y82405D02*
X1544814Y82298D01*
G01X1544707Y85047D02*
Y82405D01*
G01X1547030Y87370D02*
X1544707Y85047D01*
G01X1547030Y89280D02*
Y87370D01*
G01X1547838Y90088D02*
X1547030Y89280D01*
G01X1547838Y99149D02*
Y90088D01*
G01X1544784Y80955D02*
X1544814Y80985D01*
G01X1543119Y80955D02*
X1544784D01*
G01X1542364Y81710D02*
X1543119Y80955D01*
G01X1532480Y81710D02*
X1542364D01*
G01X1529560Y84630D02*
X1532480Y81710D01*
G01X1552350Y81200D02*
X1555450D01*
G01X1552100Y83247D02*
Y86000D01*
G01X1552350Y82997D02*
X1552100Y83247D01*
G01X1552350Y81200D02*
Y82997D01*
G01X1532866Y82635D02*
X1529753Y85748D01*
G01X1540956Y82635D02*
X1532866D01*
G01X1545250Y86929D02*
X1540956Y82635D01*
G01X1545250Y88360D02*
Y86929D01*
G01X1545987Y68493D02*
Y65716D01*
G01X1553671Y76177D02*
X1545987Y68493D01*
G01X1556864Y76177D02*
X1553671D01*
G01X1564640Y83953D02*
X1556864Y76177D01*
G01X1564640Y101500D02*
Y83953D01*
G01X1537030Y75453D02*
X1539299Y73184D01*
G01X1537030Y79875D02*
Y75453D01*
G01X1536125Y80780D02*
X1537030Y79875D01*
G01X1532638Y80780D02*
X1536125D01*
G01X1531137Y79279D02*
X1532638Y80780D01*
G01X1531137Y78487D02*
Y79279D01*
G01X1529820Y77170D02*
X1531137Y78487D01*
G01X1528630Y77170D02*
X1529820D01*
G01X1527233Y57198D02*
Y60767D01*
G01X1543427Y69056D02*
Y65716D01*
G01X1539299Y73184D02*
X1543427Y69056D01*
G01X1550030Y38425D02*
X1551050Y39445D01*
G01X1550030Y37506D02*
Y38425D01*
G01X1552102Y35434D02*
X1550030Y37506D01*
G01X1557501Y35434D02*
X1552102D01*
G01X1564710Y42643D02*
X1557501Y35434D01*
G01X1564710Y50675D02*
Y42643D01*
G01X1563674Y51711D02*
X1564710Y50675D01*
G01X1563674Y58840D02*
Y51711D01*
G01X1564100Y59266D02*
X1563674Y58840D01*
G01X1565270Y60436D02*
X1564100Y59266D01*
G01X1565270Y66980D02*
Y60436D01*
G01X1564032Y68218D02*
X1565270Y66980D01*
G01X1562909Y68218D02*
X1564032D01*
G01X1562909Y73583D02*
X1562850Y73642D01*
G01X1562909Y68218D02*
Y73583D01*
G01X1567966Y81507D02*
Y98268D01*
G01X1565938Y79479D02*
X1567966Y81507D01*
G01X1565938Y68971D02*
Y79479D01*
G01X1567201Y67708D02*
X1565938Y68971D01*
G01X1567201Y58367D02*
Y67708D01*
G01X1569838Y55730D02*
X1567201Y58367D01*
G01X1569838Y36338D02*
Y55730D01*
G01X1566600Y33100D02*
X1569838Y36338D01*
G01X1549380Y33100D02*
X1566600D01*
G01X1545572Y36908D02*
X1549380Y33100D01*
G01X1545572Y38188D02*
Y36908D01*
G01X1532353Y53208D02*
Y57198D01*
G01X1532826Y52735D02*
X1532353Y53208D01*
G01X1537352Y52735D02*
X1532826D01*
G01X1541153Y56536D02*
X1537352Y52735D01*
G01X1548747Y56536D02*
X1541153D01*
G01X1554900Y62689D02*
X1548747Y56536D01*
G01X1554900Y72929D02*
Y62689D01*
G01X1556281Y74310D02*
X1554900Y72929D01*
G01X1557640Y74310D02*
X1556281D01*
G01X1566674Y83344D02*
X1557640Y74310D01*
G01X1566674Y100916D02*
Y83344D01*
G01X1581409Y58090D02*
Y48148D01*
G01X1575018Y64481D02*
X1581409Y58090D01*
G01X1575018Y71213D02*
Y64481D01*
G01X1581409Y48148D02*
X1581260Y47999D01*
G01X1532353Y44973D02*
Y41018D01*
G01X1531959Y45367D02*
X1532353Y44973D01*
G01X1545917Y90767D02*
Y98703D01*
G01X1545180Y90030D02*
X1545917Y90767D01*
G01X1544560Y90030D02*
X1545180D01*
G01X1543340Y88810D02*
X1544560Y90030D01*
G01X1543340Y86430D02*
Y88810D01*
G01X1540587Y83677D02*
X1543340Y86430D01*
G01X1533133Y83677D02*
X1540587D01*
G01X1530137Y86673D02*
X1533133Y83677D01*
G01X1572223Y76181D02*
X1573076Y75328D01*
G01X1572223Y77170D02*
Y76181D01*
G01X1570919Y78474D02*
X1572223Y77170D01*
G01X1568740Y78474D02*
X1570919D01*
G01X1567788Y77522D02*
X1568740Y78474D01*
G01X1567788Y69964D02*
Y77522D01*
G01X1569551Y68201D02*
X1567788Y69964D01*
G01X1569551Y59725D02*
Y68201D01*
G01X1571853Y57423D02*
X1569551Y59725D01*
G01X1571853Y55367D02*
Y57423D01*
G01X1576073Y51147D02*
X1571853Y55367D01*
G01X1548547Y45448D02*
X1551050Y42945D01*
G01X1548547Y49536D02*
Y45448D01*
G01X1554231Y42945D02*
X1555623Y41553D01*
G01X1551050Y42945D02*
X1554231D01*
G01X1589268Y62283D02*
X1583861Y67690D01*
G01X1580664Y74984D02*
X1579807Y75841D01*
G01X1580664Y70887D02*
Y74984D01*
G01X1583861Y67690D02*
X1580664Y70887D01*
G01X1582821Y81319D02*
X1583374D01*
G01X1578000Y76498D02*
X1582821Y81319D01*
G01X1578000Y70252D02*
Y76498D01*
G01X1577437Y69689D02*
X1578000Y70252D01*
G01X1577437Y65463D02*
Y69689D01*
G01X1585800Y57100D02*
X1577437Y65463D01*
G01X1586561Y142000D02*
X1588000D01*
G01X1584599Y140038D02*
X1586561Y142000D01*
G01X1588000D02*
X1589901D01*
G01X1528480Y136439D02*
X1529449Y137408D01*
G01X1586344Y134254D02*
X1589283D01*
G01X1585000Y135598D02*
X1586344Y134254D01*
G01X1585000Y137000D02*
Y135598D01*
G01X1561693Y138827D02*
Y136074D01*
G01X1561509Y139011D02*
X1561693Y138827D01*
G01X1561509Y139436D02*
Y139011D01*
G01X1560052Y140893D02*
X1561509Y139436D01*
G01X1560052Y142259D02*
Y140893D01*
G01X1559168Y143143D02*
X1560052Y142259D01*
G01X1552857Y143143D02*
X1559168D01*
G01X1552400Y143600D02*
X1552857Y143143D01*
G01X1552400Y145900D02*
Y143600D01*
G01X1549113Y146200D02*
X1547400D01*
G01X1549413Y145900D02*
X1549113Y146200D01*
G01X1552400Y145900D02*
X1549413D01*
G01X1554500Y114386D02*
Y112500D01*
G01X1553500Y115386D02*
X1554500Y114386D01*
G01X1553500Y117500D02*
Y115386D01*
G01X1561693Y129558D02*
Y136074D01*
G01X1559913Y127778D02*
X1561693Y129558D01*
G01X1559913Y122439D02*
Y127778D01*
G01X1560163Y122189D02*
X1559913Y122439D01*
G01X1560163Y121972D02*
Y122189D01*
G01X1560046Y121855D02*
X1560163Y121972D01*
G01X1560046Y120694D02*
Y121855D01*
G01X1559189Y119837D02*
X1560046Y120694D01*
G01X1557811Y119837D02*
X1559189D01*
G01X1557474Y119500D02*
X1557811Y119837D01*
G01X1554352Y119500D02*
X1557474D01*
G01X1553500Y118648D02*
X1554352Y119500D01*
G01X1553500Y117500D02*
Y118648D01*
G01X1571083Y136505D02*
X1567981Y139607D01*
G01X1571083Y131783D02*
Y136505D01*
G01X1570610Y131310D02*
X1571083Y131783D01*
G01X1570610Y125735D02*
Y131310D01*
G01X1568352Y123477D02*
X1570610Y125735D01*
G01X1568352Y118875D02*
Y123477D01*
G01X1570708Y116519D02*
X1568352Y118875D01*
G01X1570708Y106259D02*
Y116519D01*
G01X1565565Y101116D02*
X1570708Y106259D01*
G01X1566500Y111500D02*
X1568000D01*
G01X1565500Y110500D02*
X1566500Y111500D01*
G01X1565500Y109000D02*
Y110500D01*
G01X1563880Y107380D02*
X1565500Y109000D01*
G01X1561900Y107380D02*
X1563880D01*
G01X1568000Y115020D02*
X1567820Y115200D01*
G01X1568000Y111500D02*
Y115020D01*
G01X1566393Y116627D02*
X1567820Y115200D01*
G01X1566393Y124136D02*
Y116627D01*
G01X1568758Y126501D02*
X1566393Y124136D01*
G01X1568758Y132076D02*
Y126501D01*
G01X1569233Y132551D02*
X1568758Y132076D01*
G01X1569233Y133993D02*
Y132551D01*
G01X1568207Y135019D02*
X1569233Y133993D01*
G01X1567279Y135019D02*
X1568207D01*
G01X1566305Y135993D02*
X1567279Y135019D01*
G01X1566305Y140283D02*
Y135993D01*
G01X1567626Y141604D02*
X1566305Y140283D01*
G01X1568725Y141604D02*
X1567626D01*
G01X1570388Y143267D02*
X1568725Y141604D01*
G01X1570388Y162158D02*
Y143267D01*
G01X1552400Y151600D02*
Y153300D01*
G01X1554000Y150000D02*
X1552400Y151600D01*
G01X1558500Y150000D02*
X1554000D01*
G01X1561000Y152500D02*
X1558500Y150000D01*
G01X1562500Y152500D02*
X1561000D01*
G01X1552400Y155500D02*
X1551000Y156900D01*
G01X1552400Y153300D02*
Y155500D01*
G01X1584450Y155600D02*
Y152600D01*
G01X1586500D02*
X1584450D01*
G01X1588600Y150500D02*
X1586500Y152600D01*
G01X1590046Y149054D02*
X1588600Y150500D01*
G01X1584450Y149200D02*
Y146100D01*
G01X1586966Y149200D02*
X1584450D01*
G01X1588490Y147676D02*
X1586966Y149200D01*
G01X1590224Y147676D02*
X1588490D01*
G01X1561709Y125024D02*
X1563108Y126423D01*
G01X1561709Y124081D02*
Y125024D01*
G01X1533117Y141386D02*
X1529652Y144851D01*
G01X1535338Y141386D02*
X1533117D01*
G01X1536900Y139824D02*
X1535338Y141386D01*
G01X1541387Y139824D02*
X1536900D01*
G01X1541434Y139871D02*
X1541387Y139824D01*
G01X1562469Y120581D02*
X1561709D01*
G01X1563388Y121500D02*
X1562469Y120581D01*
G01X1563388Y123764D02*
Y121500D01*
G01X1564771Y125147D02*
X1563388Y123764D01*
G01X1564771Y127126D02*
Y125147D01*
G01X1563672Y128225D02*
X1564771Y127126D01*
G01X1563672Y142816D02*
Y128225D01*
G01X1563506Y142982D02*
X1563672Y142816D01*
G01X1556008Y107380D02*
X1554500D01*
G01X1559213Y110585D02*
X1556008Y107380D01*
G01X1559213Y113550D02*
Y110585D01*
G01X1560800Y115137D02*
X1559213Y113550D01*
G01X1562294Y115137D02*
X1560800D01*
G01X1563502Y116345D02*
X1562294Y115137D01*
G01X1563502Y117500D02*
Y116345D01*
G01X1559600Y145900D02*
X1557520D01*
G01X1562518Y142982D02*
X1559600Y145900D01*
G01X1563506Y142982D02*
X1562518D01*
G01X1563502Y118788D02*
X1561709Y120581D01*
G01X1563502Y117500D02*
Y118788D01*
G01X1543872Y103115D02*
X1547838Y99149D01*
G01X1543872Y107080D02*
Y103115D01*
G01X1537249Y113703D02*
X1543872Y107080D01*
G01X1537249Y118153D02*
Y113703D01*
G01X1542000Y124906D02*
Y126246D01*
G01X1537249Y120155D02*
X1542000Y124906D01*
G01X1537249Y118153D02*
Y120155D01*
G01X1585227Y143666D02*
X1592144D01*
G01X1584599Y143038D02*
X1585227Y143666D01*
G01X1588000Y136301D02*
X1587620Y135921D01*
G01X1588000Y138500D02*
Y136301D01*
G01X1536000Y135000D02*
X1531808Y130808D01*
G01X1537498Y136498D02*
X1536000Y135000D01*
G01X1541390Y136498D02*
X1537498D01*
G01X1565500Y154500D02*
Y152500D01*
G01X1562500Y157500D02*
X1565500Y154500D01*
G01X1557520Y155500D02*
X1559520Y157500D01*
G01X1557520Y153300D02*
Y155500D01*
G01X1567500Y153000D02*
Y158100D01*
G01X1567000Y152500D02*
X1567500Y153000D01*
G01X1565500Y152500D02*
X1567000D01*
G01X1531390Y147595D02*
X1531985Y147000D01*
G01X1528346Y147595D02*
X1531390D01*
G01X1569783Y106643D02*
X1564640Y101500D01*
G01X1569783Y116135D02*
Y106643D01*
G01X1567427Y118491D02*
X1569783Y116135D01*
G01X1567427Y123861D02*
Y118491D01*
G01X1569684Y126118D02*
X1567427Y123861D01*
G01X1569684Y131693D02*
Y126118D01*
G01X1570158Y132167D02*
X1569684Y131693D01*
G01X1570158Y134492D02*
Y132167D01*
G01X1567968Y136682D02*
X1570158Y134492D01*
G01X1566381Y127554D02*
X1566481Y127454D01*
G01X1565652Y127554D02*
X1566381D01*
G01X1564597Y128609D02*
X1565652Y127554D01*
G01X1564597Y140947D02*
Y128609D01*
G01X1566260Y142610D02*
X1564597Y140947D01*
G01X1568422Y142610D02*
X1566260D01*
G01X1569442Y143630D02*
X1568422Y142610D01*
G01X1569442Y157266D02*
Y143630D01*
G01X1564407Y112500D02*
X1561900D01*
G01X1565130Y113223D02*
X1564407Y112500D01*
G01X1565130Y116191D02*
Y113223D01*
G01X1565165Y116226D02*
X1565130Y116191D01*
G01X1565165Y118774D02*
Y116226D01*
G01X1564313Y119626D02*
X1565165Y118774D01*
G01X1564313Y123365D02*
Y119626D01*
G01X1566536Y125588D02*
X1564313Y123365D01*
G01X1566536Y127399D02*
Y125588D01*
G01X1566481Y127454D02*
X1566536Y127399D01*
G01X1567966Y98268D02*
X1568950Y99252D01*
G01X1572337Y148155D02*
Y162989D01*
G01X1573442Y147050D02*
X1572337Y148155D01*
G01X1576288Y147050D02*
X1573442D01*
G01X1578169Y145169D02*
X1576288Y147050D01*
G01X1578169Y142727D02*
Y145169D01*
G01X1577186Y141744D02*
X1578169Y142727D01*
G01X1576253Y141744D02*
X1577186D01*
G01X1572974Y138465D02*
X1576253Y141744D01*
G01X1572974Y131056D02*
Y138465D01*
G01X1572476Y130558D02*
X1572974Y131056D01*
G01X1572476Y125925D02*
Y130558D01*
G01X1572460Y125925D02*
X1572476D01*
G01X1572460Y124967D02*
Y125925D01*
G01X1570202Y122709D02*
X1572460Y124967D01*
G01X1570202Y119699D02*
Y122709D01*
G01X1572558Y117343D02*
X1570202Y119699D01*
G01X1572558Y114587D02*
Y117343D01*
G01X1575269Y111876D02*
X1572558Y114587D01*
G01X1575269Y109819D02*
Y111876D01*
G01X1572702Y107252D02*
X1575269Y109819D01*
G01X1572702Y105635D02*
Y107252D01*
G01X1568950Y101883D02*
X1572702Y105635D01*
G01X1568950Y99252D02*
Y101883D01*
G01X1571777Y106019D02*
X1566674Y100916D01*
G01X1571777Y107676D02*
Y106019D01*
G01X1574344Y110243D02*
X1571777Y107676D01*
G01X1574344Y111380D02*
Y110243D01*
G01X1571633Y114091D02*
X1574344Y111380D01*
G01X1571633Y116959D02*
Y114091D01*
G01X1569277Y119315D02*
X1571633Y116959D01*
G01X1569277Y123093D02*
Y119315D01*
G01X1571535Y125351D02*
X1569277Y123093D01*
G01X1571535Y130926D02*
Y125351D01*
G01X1572049Y131440D02*
X1571535Y130926D01*
G01X1572049Y138959D02*
Y131440D01*
G01X1576506Y143416D02*
X1572049Y138959D01*
G01X1552171Y130471D02*
Y133000D01*
G01X1580950Y152600D02*
X1577950D01*
G01X1552171Y125391D02*
X1553353Y124209D01*
G01X1552171Y126971D02*
Y125391D01*
G01X1545917Y98703D02*
X1535061Y109559D01*
G01Y109565D02*
Y109559D01*
G01X1531853Y112773D02*
X1535061Y109565D01*
G01X1547400Y156100D02*
Y149700D01*
G01X1542581Y160919D02*
X1547400Y156100D01*
G01X1578089Y149200D02*
X1577770Y149519D01*
G01X1580950Y149200D02*
X1578089D01*
G01X1545500Y141623D02*
X1543169Y143954D01*
G01X1545500Y138500D02*
Y141623D01*
G01X1543839Y138500D02*
X1545500D01*
G01X1543547Y138208D02*
X1543839Y138500D01*
G01X1534602Y138208D02*
X1543547D01*
G01X1531678Y135284D02*
X1534602Y138208D01*
G01X1553500Y160000D02*
Y157000D01*
G01X1558743Y165243D02*
X1553500Y160000D01*
G01X1562743Y165243D02*
X1558743D01*
G01X1563830Y166330D02*
X1562743Y165243D01*
G01X1563830Y169766D02*
Y166330D01*
G01X1571501Y177437D02*
X1563830Y169766D01*
G01X1571501Y180031D02*
Y177437D01*
G01X1553088Y174212D02*
X1548628D01*
G01X1554300Y173000D02*
X1553088Y174212D01*
G01X1554300Y168800D02*
Y173000D01*
G01X1555800Y167300D02*
X1554300Y168800D01*
G01X1535065Y174112D02*
X1528065D01*
G01X1535165Y174212D02*
X1535065Y174112D01*
G01X1541628Y174212D02*
X1535165D01*
G01X1548628D02*
X1541628D01*
G01X1568488Y164058D02*
X1570388Y162158D01*
G01X1574320Y205920D02*
X1574500Y206100D01*
G01X1567299Y205920D02*
X1574320D01*
G01X1545173Y161525D02*
X1545023Y161675D01*
G01X1547975Y161525D02*
X1545173D01*
G01X1549000Y160500D02*
X1547975Y161525D01*
G01X1550000Y160500D02*
X1549000D01*
G01X1551000Y159500D02*
X1550000Y160500D01*
G01X1551000Y156900D02*
Y159500D01*
G01X1565067Y181270D02*
X1566486D01*
G01X1563897Y180100D02*
X1565067Y181270D01*
G01X1551650Y171652D02*
X1552051Y172053D01*
G01X1548628Y171652D02*
X1551650D01*
G01X1535425Y185726D02*
X1533589Y183890D01*
G01X1535425Y188016D02*
Y185726D01*
G01X1585537Y201527D02*
Y225343D01*
G01X1582627Y198617D02*
X1585537Y201527D01*
G01X1567299Y190920D02*
X1575420D01*
G01Y191410D02*
X1582627Y198617D01*
G01X1575420Y190920D02*
Y191410D01*
G01X1555514Y191309D02*
Y220357D01*
G01X1557979Y188844D02*
X1555514Y191309D01*
G01X1550923Y211622D02*
Y231291D01*
G01X1550301Y211000D02*
X1550923Y211622D01*
G01X1549420Y211000D02*
X1550301D01*
G01X1548798Y211622D02*
X1549420Y211000D01*
G01X1548798Y231291D02*
Y211622D01*
G01X1546673D02*
Y231291D01*
G01X1546051Y211000D02*
X1546673Y211622D01*
G01X1545170Y211000D02*
X1546051D01*
G01X1544548Y211622D02*
X1545170Y211000D01*
G01X1544548Y231291D02*
Y211622D01*
G01X1542423D02*
Y231291D01*
G01X1541801Y211000D02*
X1542423Y211622D01*
G01X1540920Y211000D02*
X1541801D01*
G01X1540298Y211622D02*
X1540920Y211000D01*
G01X1540298Y231291D02*
Y211622D01*
G01X1584250Y169000D02*
X1589700D01*
G01X1567500Y159154D02*
Y158100D01*
G01X1565822Y160832D02*
X1567500Y159154D01*
G01X1565822Y169677D02*
Y160832D01*
G01X1585599Y189454D02*
X1565822Y169677D01*
G01X1585599Y196060D02*
Y189454D01*
G01X1588204Y198665D02*
X1585599Y196060D01*
G01X1588204Y227304D02*
Y198665D01*
G01X1559520Y157500D02*
X1562500D01*
G01X1588622Y166622D02*
X1592448D01*
G01X1588000Y166000D02*
X1588622Y166622D01*
G01X1584250Y166000D02*
X1588000D01*
G01X1569463Y157287D02*
X1569442Y157266D01*
G01X1569463Y160362D02*
Y157287D01*
G01X1566825Y163000D02*
X1569463Y160362D01*
G01X1566825Y169086D02*
Y163000D01*
G01X1572876Y175137D02*
X1566825Y169086D01*
G01X1588847Y175137D02*
X1572876D01*
G01X1562780Y185920D02*
X1567299D01*
G01X1561985Y186715D02*
X1562780Y185920D01*
G01X1546625Y186715D02*
X1561985D01*
G01X1546200Y186290D02*
X1546625Y186715D01*
G01X1546200Y185015D02*
Y186290D01*
G01X1546625Y184590D02*
X1546200Y185015D01*
G01X1560578Y184590D02*
X1546625D01*
G01X1561200Y183968D02*
X1560578Y184590D01*
G01X1561200Y183087D02*
Y183968D01*
G01X1560578Y182465D02*
X1561200Y183087D01*
G01X1574080Y185920D02*
X1567299D01*
G01X1574600Y185400D02*
X1574080Y185920D01*
G01X1580993Y171789D02*
X1591551D01*
G01X1578933Y173849D02*
X1580993Y171789D01*
G01X1574339Y173849D02*
X1578933D01*
G01X1568631Y168141D02*
X1574339Y173849D01*
G01X1568631Y166695D02*
Y168141D01*
G01X1572337Y162989D02*
X1568631Y166695D01*
G01X1575600Y166000D02*
X1580750D01*
G01X1573700D02*
X1575600D01*
G01X1572316Y167384D02*
X1573700Y166000D01*
G01X1570294Y167384D02*
X1572316D01*
G01X1538656Y178135D02*
X1538318Y178473D01*
G01X1538656Y177108D02*
Y178135D01*
G01X1538992Y176772D02*
X1538656Y177108D01*
G01X1541628Y176772D02*
X1538992D01*
G01X1592767Y159838D02*
X1584099D01*
G01X1588799Y162838D02*
X1584099D01*
G01X1552400Y166500D02*
X1553500Y165400D01*
G01X1544500Y166500D02*
X1552400D01*
G01X1542000Y164000D02*
X1544500Y166500D01*
G01X1541500Y164000D02*
X1542000D01*
G01X1538500Y161000D02*
X1541500Y164000D01*
G01X1536000Y161000D02*
X1538500D01*
G01X1532906Y164094D02*
X1536000Y161000D01*
G01X1535065Y164300D02*
Y171552D01*
G01X1534716Y164300D02*
X1535065D01*
G01X1533497Y165519D02*
X1534716Y164300D01*
G01X1574820Y195920D02*
X1574900Y196000D01*
G01X1567299Y195920D02*
X1574820D01*
G01X1561500Y169000D02*
X1561000Y168500D01*
G01X1561500Y170633D02*
Y169000D01*
G01X1564283Y173416D02*
X1561500Y170633D01*
G01X1564283Y175283D02*
Y173416D01*
G01X1571583Y182583D02*
X1564283Y175283D01*
G01X1576916Y182583D02*
X1571583D01*
G01X1584476Y190143D02*
X1576916Y182583D01*
G01X1584476Y196476D02*
Y190143D01*
G01X1586962Y198962D02*
X1584476Y196476D01*
G01X1586962Y226354D02*
Y198962D01*
G01X1542581Y162575D02*
Y160919D01*
G01X1542591Y162575D02*
X1542581D01*
G01X1544709Y164693D02*
X1542591Y162575D01*
G01X1551081Y164693D02*
X1544709D01*
G01X1552625Y163149D02*
X1551081Y164693D01*
G01X1555148Y163149D02*
X1552625D01*
G01X1559533Y167534D02*
X1555148Y163149D01*
G01X1560034Y167534D02*
X1559533D01*
G01X1561000Y168500D02*
X1560034Y167534D01*
G01X1591606Y196057D02*
X1587549Y192000D01*
G01X1533519Y215920D02*
X1537840Y220241D01*
G01X1530149Y215920D02*
X1533519D01*
G01X1579700Y206430D02*
X1576040Y210090D01*
G01X1579700Y206200D02*
Y206430D01*
G01X1574377Y210090D02*
X1576040D01*
G01X1573547Y210920D02*
X1574377Y210090D01*
G01X1567299Y210920D02*
X1573547D01*
G01X1578541Y171209D02*
X1580750Y169000D01*
G01X1576679Y171209D02*
X1578541D01*
G01X1574116D02*
X1576679D01*
G01X1572817Y169910D02*
X1574116Y171209D01*
G01X1574520Y200920D02*
X1574700Y201100D01*
G01X1567299Y200920D02*
X1574520D01*
G01X1540851Y238902D02*
X1527168D01*
G01X1542690Y237063D02*
X1540851Y238902D01*
G01X1542690Y236050D02*
Y237063D01*
G01X1563860Y263000D02*
X1561400D01*
G01X1567000Y259860D02*
X1563860Y263000D01*
G01X1567000Y259560D02*
Y259860D01*
G01X1543375Y253472D02*
X1540650D01*
G01X1543800Y253897D02*
X1543375Y253472D01*
G01X1543800Y264342D02*
Y253897D01*
G01X1540217Y267925D02*
X1543800Y264342D01*
G01X1537425Y267925D02*
X1540217D01*
G01X1536000Y266500D02*
X1537425Y267925D01*
G01X1536000Y260500D02*
Y266500D01*
G01X1532976Y257359D02*
X1529147Y253530D01*
G01X1535318Y257359D02*
X1532976D01*
G01X1536000Y258041D02*
X1535318Y257359D01*
G01X1536000Y260500D02*
Y258041D01*
G01X1586736Y240740D02*
X1595245D01*
G01X1579546Y247930D02*
X1586736Y240740D01*
G01X1579546Y249110D02*
Y247930D01*
G01X1579547Y249111D02*
X1579546Y249110D01*
G01X1579547Y252588D02*
Y249111D01*
G01X1577250Y254885D02*
X1579547Y252588D01*
G01X1577250Y255272D02*
Y254885D01*
G01X1577251Y255273D02*
X1577250Y255272D01*
G01X1577251Y257173D02*
Y255273D01*
G01X1577252Y257174D02*
X1577251Y257173D01*
G01X1577252Y257940D02*
Y257174D01*
G01X1575613Y259579D02*
X1577252Y257940D01*
G01X1575613Y261512D02*
Y259579D01*
G01X1566483Y270642D02*
X1575613Y261512D01*
G01X1563263Y270642D02*
X1566483D01*
G01X1561431Y272474D02*
X1563263Y270642D01*
G01X1560120Y272474D02*
X1561431D01*
G01X1560119Y272473D02*
X1560120Y272474D01*
G01X1556989Y272473D02*
X1560119D01*
G01X1556987Y272475D02*
X1556989Y272473D01*
G01X1555409Y272475D02*
X1556987D01*
G01X1546749Y281135D02*
X1555409Y272475D01*
G01X1575930Y277500D02*
X1571263Y282167D01*
G01X1594500Y277500D02*
X1575930D01*
G01X1586436Y236486D02*
X1587500D01*
G01X1576327Y246595D02*
X1586436Y236486D01*
G01X1576327Y251254D02*
Y246595D01*
G01X1574031Y253550D02*
X1576327Y251254D01*
G01X1574031Y256607D02*
Y253550D01*
G01X1572394Y258244D02*
X1574031Y256607D01*
G01X1572394Y260177D02*
Y258244D01*
G01X1565149Y267422D02*
X1572394Y260177D01*
G01X1564106Y267422D02*
X1565149D01*
G01X1564105Y267423D02*
X1564106Y267422D01*
G01X1561928Y267423D02*
X1564105D01*
G01X1560097Y269254D02*
X1561928Y267423D01*
G01X1555654Y269254D02*
X1560097D01*
G01X1555652Y269256D02*
X1555654Y269254D01*
G01X1554074Y269256D02*
X1555652D01*
G01X1545430Y277900D02*
X1554074Y269256D01*
G01X1543400Y277900D02*
X1545430D01*
G01X1587500Y236486D02*
X1589103Y234883D01*
G01X1529900Y278900D02*
X1527832Y280968D01*
G01X1539661Y278900D02*
X1529900D01*
G01X1540661Y277900D02*
X1539661Y278900D01*
G01X1543400Y277900D02*
X1540661D01*
G01X1555986Y273914D02*
X1546379Y283521D01*
G01X1556194Y273914D02*
X1555986D01*
G01X1556207Y273900D02*
X1556194Y273914D01*
G01X1557578Y273900D02*
X1556207D01*
G01X1557580Y273898D02*
X1557578Y273900D01*
G01X1559528Y273898D02*
X1557580D01*
G01X1559529Y273899D02*
X1559528Y273898D01*
G01X1561359Y273899D02*
X1559529D01*
G01X1561360Y273900D02*
X1561359Y273899D01*
G01X1562021Y273900D02*
X1561360D01*
G01X1563854Y272067D02*
X1562021Y273900D01*
G01X1567074Y272067D02*
X1563854D01*
G01X1577039Y262102D02*
X1567074Y272067D01*
G01X1577039Y260922D02*
Y262102D01*
G01X1577038Y260921D02*
X1577039Y260922D01*
G01X1577038Y260170D02*
Y260921D01*
G01X1578677Y258531D02*
X1577038Y260170D01*
G01X1578677Y256583D02*
Y258531D01*
G01X1578676Y256582D02*
X1578677Y256583D01*
G01X1578676Y255475D02*
Y256582D01*
G01X1580972Y253179D02*
X1578676Y255475D01*
G01X1580972Y248520D02*
Y253179D01*
G01X1587327Y242165D02*
X1580972Y248520D01*
G01X1594654Y242165D02*
X1587327D01*
G01X1587978Y267522D02*
X1597265Y258235D01*
G01X1574944Y267522D02*
X1587978D01*
G01X1568049Y274417D02*
X1574944Y267522D01*
G01X1564829Y274417D02*
X1568049D01*
G01X1562995Y276251D02*
X1564829Y274417D01*
G01X1562334Y276251D02*
X1562995D01*
G01X1562333Y276250D02*
X1562334Y276251D01*
G01X1560702Y276250D02*
X1562333D01*
G01X1547432Y289520D02*
X1560702Y276250D01*
G01X1532652Y253711D02*
X1532650Y253713D01*
G01X1532652Y251429D02*
Y253711D01*
G01X1532650Y251427D02*
X1532652Y251429D01*
G01X1533075Y251002D02*
X1532650Y251427D01*
G01X1538308Y251002D02*
X1533075D01*
G01X1540040Y249270D02*
X1538308Y251002D01*
G01X1540040Y246970D02*
Y249270D01*
G01X1538829Y245759D02*
X1540040Y246970D01*
G01X1537300Y245759D02*
X1538829D01*
G01X1537836Y255650D02*
X1538217Y256031D01*
G01X1533320Y255650D02*
X1537836D01*
G01X1532616Y254946D02*
X1533320Y255650D01*
G01X1532616Y253747D02*
Y254946D01*
G01X1532650Y253713D02*
X1532616Y253747D01*
G01X1540650Y256031D02*
X1538217D01*
G01X1538395Y265323D02*
X1538443Y265371D01*
G01X1538395Y261586D02*
Y265323D01*
G01X1537806Y260997D02*
X1538395Y261586D01*
G01X1537806Y256442D02*
Y260997D01*
G01X1538217Y256031D02*
X1537806Y256442D01*
G01X1530990Y253713D02*
X1529490Y252213D01*
G01X1532650Y253713D02*
X1530990D01*
G01X1552500Y265400D02*
Y264000D01*
G01X1550163Y267737D02*
X1552500Y265400D01*
G01X1545563Y267737D02*
X1550163D01*
G01X1538133Y275167D02*
X1545563Y267737D01*
G01X1545510Y260918D02*
X1552508D01*
G01X1544987Y260395D02*
X1545510Y260918D01*
G01X1544987Y249005D02*
Y260395D01*
G01X1544300Y248318D02*
X1544987Y249005D01*
G01X1548996Y264430D02*
X1552508Y260918D01*
G01X1548996Y265700D02*
Y264430D01*
G01X1579900Y223500D02*
X1574500D01*
G01Y220500D02*
Y223500D01*
G01X1572500Y220500D02*
X1574500D01*
G01X1572080Y220920D02*
X1572500Y220500D01*
G01X1567299Y220920D02*
X1572080D01*
G01X1533819D02*
X1530149D01*
G01X1534300Y221401D02*
X1533819Y220920D01*
G01X1534300Y226201D02*
Y221401D01*
G01X1533301Y227200D02*
X1534300Y226201D01*
G01X1532526Y227200D02*
X1533301D01*
G01X1531000Y227625D02*
X1528922D01*
G01X1531425Y227200D02*
X1531000Y227625D01*
G01X1532526Y227200D02*
X1531425D01*
G01X1566817Y245848D02*
Y243681D01*
G01X1568365Y247396D02*
X1566817Y245848D01*
G01X1568365Y247761D02*
Y247396D01*
G01X1562981Y243681D02*
X1566817D01*
G01X1562900Y243600D02*
X1562981Y243681D01*
G01X1561118Y257250D02*
X1556000D01*
G01X1565601Y252767D02*
X1561118Y257250D01*
G01X1565601Y249646D02*
Y252767D01*
G01X1560937Y244982D02*
X1565601Y249646D01*
G01X1560937Y238527D02*
Y244982D01*
G01X1568679Y230785D02*
X1560937Y238527D01*
G01X1580095Y230785D02*
X1568679D01*
G01X1585537Y225343D02*
X1580095Y230785D01*
G01X1586352Y239815D02*
X1595629D01*
G01X1578621Y247546D02*
X1586352Y239815D01*
G01X1578621Y249494D02*
Y247546D01*
G01X1578622Y249495D02*
X1578621Y249494D01*
G01X1578622Y252204D02*
Y249495D01*
G01X1576325Y254501D02*
X1578622Y252204D01*
G01X1576325Y255656D02*
Y254501D01*
G01X1576326Y255657D02*
X1576325Y255656D01*
G01X1576326Y257557D02*
Y255657D01*
G01X1574688Y259195D02*
X1576326Y257557D01*
G01X1574688Y261128D02*
Y259195D01*
G01X1566099Y269717D02*
X1574688Y261128D01*
G01X1562879Y269717D02*
X1566099D01*
G01X1561047Y271549D02*
X1562879Y269717D01*
G01X1560504Y271549D02*
X1561047D01*
G01X1560503Y271548D02*
X1560504Y271549D01*
G01X1556605Y271548D02*
X1560503D01*
G01X1556603Y271550D02*
X1556605Y271548D01*
G01X1555025Y271550D02*
X1556603D01*
G01X1546381Y280194D02*
X1555025Y271550D01*
G01X1574500Y228852D02*
Y227000D01*
G01X1574075Y229277D02*
X1574500Y228852D01*
G01X1565386Y229277D02*
X1574075D01*
G01X1563994Y230669D02*
X1565386Y229277D01*
G01X1554776Y230669D02*
X1563994D01*
G01X1553532Y231913D02*
X1554776Y230669D01*
G01X1562157Y227000D02*
X1574500D01*
G01X1555514Y220357D02*
X1562157Y227000D01*
G01X1551545Y231913D02*
X1553532D01*
G01X1550923Y231291D02*
X1551545Y231913D01*
G01X1548176D02*
X1548798Y231291D01*
G01X1547295Y231913D02*
X1548176D01*
G01X1546673Y231291D02*
X1547295Y231913D01*
G01X1543926D02*
X1544548Y231291D01*
G01X1543045Y231913D02*
X1543926D01*
G01X1542423Y231291D02*
X1543045Y231913D01*
G01X1539138Y232451D02*
X1540298Y231291D01*
G01X1582699Y248809D02*
Y252646D01*
G01X1587918Y243590D02*
X1582699Y248809D01*
G01X1594063Y243590D02*
X1587918D01*
G01X1554667Y234255D02*
X1561104D01*
G01X1553037Y235885D02*
X1554667Y234255D01*
G01X1544877Y235885D02*
X1553037D01*
G01X1542868Y233876D02*
X1544877Y235885D01*
G01X1531935Y224409D02*
Y224160D01*
G01X1530426Y225918D02*
X1531935Y224409D01*
G01X1527870Y225918D02*
X1530426D01*
G01X1566861Y279317D02*
X1561778Y284400D01*
G01X1570081Y279317D02*
X1566861D01*
G01X1576370Y273028D02*
X1570081Y279317D01*
G01X1612326Y273028D02*
X1576370D01*
G01X1589954Y229054D02*
X1588204Y227304D01*
G01X1532973Y243200D02*
X1537300D01*
G01X1532959Y243214D02*
X1532973Y243200D01*
G01X1530149Y243214D02*
X1532959D01*
G01X1528750Y241815D02*
X1530149Y243214D01*
G01X1528750Y241500D02*
Y241815D01*
G01X1561676Y278601D02*
X1548220Y292057D01*
G01X1563970Y278601D02*
X1561676D01*
G01X1565804Y276767D02*
X1563970Y278601D01*
G01X1569024Y276767D02*
X1565804D01*
G01X1575727Y270064D02*
X1569024Y276767D01*
G01X1589736Y270064D02*
X1575727D01*
G01X1562982Y260918D02*
X1556008D01*
G01X1565337Y258563D02*
X1562982Y260918D01*
G01X1565337Y256963D02*
Y258563D01*
G01X1566260Y256040D02*
X1565337Y256963D01*
G01X1567800Y254500D02*
X1566260Y256040D01*
G01X1568808Y254500D02*
X1567800D01*
G01X1570312Y252996D02*
X1568808Y254500D01*
G01X1570312Y252008D02*
Y252996D01*
G01X1572600Y249720D02*
X1570312Y252008D01*
G01X1572600Y243200D02*
Y249720D01*
G01X1574900Y240900D02*
X1572600Y243200D01*
G01X1556000Y260926D02*
X1556008Y260918D01*
G01X1556000Y264000D02*
Y260926D01*
G01X1586132Y248441D02*
X1592053D01*
G01X1585287Y249286D02*
X1586132Y248441D01*
G01X1585287Y253719D02*
Y249286D01*
G01X1583772Y255234D02*
X1585287Y253719D01*
G01X1582242Y255234D02*
X1583772D01*
G01X1581027Y256449D02*
X1582242Y255234D01*
G01X1581027Y259506D02*
Y256449D01*
G01X1579867Y260666D02*
X1581027Y259506D01*
G01X1579867Y265445D02*
Y260666D01*
G01X1576192Y275222D02*
X1570672Y280742D01*
G01X1612148Y275222D02*
X1576192D01*
G01X1588152Y232589D02*
X1595695D01*
G01X1588041Y232700D02*
X1588152Y232589D01*
G01X1586977Y232700D02*
X1588041D01*
G01X1574033Y245644D02*
X1586977Y232700D01*
G01X1574033Y250303D02*
Y245644D01*
G01X1571737Y252599D02*
X1574033Y250303D01*
G01X1571737Y253587D02*
Y252599D01*
G01X1570100Y255224D02*
X1571737Y253587D01*
G01X1570100Y259226D02*
Y255224D01*
G01X1564198Y265128D02*
X1570100Y259226D01*
G01X1563155Y265128D02*
X1564198D01*
G01X1563154Y265129D02*
X1563155Y265128D01*
G01X1560977Y265129D02*
X1563154D01*
G01X1559146Y266960D02*
X1560977Y265129D01*
G01X1553051Y266960D02*
X1559146D01*
G01X1544781Y275230D02*
X1553051Y266960D01*
G01X1540086Y275230D02*
X1544781D01*
G01X1538724Y276592D02*
X1540086Y275230D01*
G01X1580976Y232340D02*
X1586962Y226354D01*
G01X1569318Y232340D02*
X1580976D01*
G01X1568140Y233518D02*
X1569318Y232340D01*
G01X1568140Y238791D02*
Y233518D01*
G01X1570317Y240968D02*
X1568140Y238791D01*
G01X1570317Y243681D02*
Y240968D01*
G01Y249513D02*
Y243681D01*
G01X1568120Y251710D02*
X1570317Y249513D01*
G01X1537840Y228548D02*
X1537150Y229238D01*
G01X1537840Y220241D02*
Y228548D01*
G01X1535763Y230625D02*
X1528922D01*
G01X1537150Y229238D02*
X1535763Y230625D01*
G01X1581500Y235100D02*
X1579600D01*
G01X1584900Y231700D02*
X1581500Y235100D01*
G01X1587732Y231700D02*
X1584900D01*
G01X1587768Y231664D02*
X1587732Y231700D01*
G01X1596079Y231664D02*
X1587768D01*
G01X1577120Y235100D02*
X1579600D01*
G01X1574560Y237660D02*
X1577120Y235100D01*
G01X1588762Y268639D02*
X1598091Y259310D01*
G01X1575136Y268639D02*
X1588762D01*
G01X1568433Y275342D02*
X1575136Y268639D01*
G01X1565213Y275342D02*
X1568433D01*
G01X1563379Y277176D02*
X1565213Y275342D01*
G01X1561950Y277176D02*
X1563379D01*
G01X1561949Y277175D02*
X1561950Y277176D01*
G01X1561086Y277175D02*
X1561949D01*
G01X1547801Y290460D02*
X1561086Y277175D01*
G01X1576092Y271290D02*
X1591610D01*
G01X1569490Y277892D02*
X1576092Y271290D01*
G01X1566270Y277892D02*
X1569490D01*
G01X1564436Y279726D02*
X1566270Y277892D01*
G01X1585748Y247516D02*
X1592656D01*
G01X1584362Y248902D02*
X1585748Y247516D01*
G01X1584362Y253335D02*
Y248902D01*
G01X1583388Y254309D02*
X1584362Y253335D01*
G01X1581858Y254309D02*
X1583388D01*
G01X1580102Y256065D02*
X1581858Y254309D01*
G01X1580102Y259122D02*
Y256065D01*
G01X1578464Y260760D02*
X1580102Y259122D01*
G01X1578464Y262693D02*
Y260760D01*
G01X1567665Y273492D02*
X1578464Y262693D01*
G01X1564445Y273492D02*
X1567665D01*
G01X1562612Y275325D02*
X1564445Y273492D01*
G01X1556591Y275325D02*
X1562612D01*
G01X1548199Y283717D02*
X1556591Y275325D01*
G01X1559000Y255400D02*
X1559350Y255050D01*
G01X1552850Y255400D02*
X1559000D01*
G01X1552500Y255750D02*
X1552850Y255400D01*
G01X1552500Y257250D02*
Y255750D01*
G01X1551496Y257250D02*
X1552500D01*
G01X1550156Y258590D02*
X1551496Y257250D01*
G01X1547650Y258590D02*
X1550156D01*
G01X1575276Y279463D02*
X1615555D01*
G01X1571647Y283092D02*
X1575276Y279463D01*
G01X1588851Y249366D02*
X1586950Y251267D01*
G01X1577468Y313332D02*
X1576168D01*
G01X1585120Y305680D02*
X1577468Y313332D01*
G01X1589000Y305680D02*
X1585120D01*
G01X1569926Y309026D02*
Y308064D01*
G01X1570000Y309100D02*
X1569926Y309026D01*
G01X1570105Y309100D02*
X1570000D01*
G01X1574337Y313332D02*
X1570105Y309100D01*
G01X1576168Y313332D02*
X1574337D01*
G01X1588553Y333507D02*
X1600573D01*
G01X1586376Y331330D02*
X1588553Y333507D01*
G01X1575957Y331330D02*
X1586376D01*
G01X1568826Y324199D02*
X1575957Y331330D01*
G01X1556831Y324199D02*
X1568826D01*
G01X1549763Y331267D02*
X1556831Y324199D01*
G01X1549763Y342889D02*
Y331267D01*
G01X1566000Y338250D02*
Y341000D01*
G01D02*
X1568600Y343600D01*
G01X1580365Y341293D02*
X1581000Y341928D01*
G01X1538742Y296758D02*
X1542972D01*
G01X1538584Y296916D02*
X1538742Y296758D01*
G01X1538584Y296941D02*
Y296916D01*
G01X1535595Y299930D02*
X1538584Y296941D01*
G01X1535570Y299930D02*
X1535595D01*
G01X1535008Y300492D02*
X1535570Y299930D01*
G01X1531621Y300492D02*
X1535008D01*
G01X1528599Y303514D02*
X1531621Y300492D01*
G01X1528599Y307704D02*
Y303514D01*
G01X1527625Y308678D02*
X1528599Y307704D01*
G01X1550242Y296758D02*
X1550800Y296200D01*
G01X1542972Y296758D02*
X1550242D01*
G01X1541980Y281135D02*
X1546749D01*
G01X1540996Y282119D02*
X1541980Y281135D01*
G01X1531235Y282119D02*
X1540996D01*
G01X1529165Y284189D02*
X1531235Y282119D01*
G01X1529041Y284189D02*
X1529165D01*
G01X1565000Y290260D02*
Y290500D01*
G01X1564630Y289890D02*
X1565000Y290260D01*
G01X1564630Y285580D02*
Y289890D01*
G01X1568043Y282167D02*
X1564630Y285580D01*
G01X1571263Y282167D02*
X1568043D01*
G01X1527832Y280968D02*
X1527708D01*
G01X1530110Y330890D02*
Y333680D01*
G01X1531565Y329435D02*
X1530110Y330890D01*
G01X1531565Y323895D02*
Y329435D01*
G01X1535540Y319920D02*
X1531565Y323895D01*
G01X1535540Y314340D02*
Y319920D01*
G01X1538481Y311399D02*
X1535540Y314340D01*
G01X1543864Y311399D02*
X1538481D01*
G01X1528000Y339820D02*
Y341400D01*
G01X1530110Y337710D02*
X1528000Y339820D01*
G01X1530110Y336680D02*
Y337710D01*
G01X1546550Y287812D02*
X1546612D01*
G01X1546550Y287750D02*
Y287812D01*
G01X1546379Y287579D02*
X1546550Y287750D01*
G01X1546379Y283521D02*
Y287579D01*
G01X1530110Y336680D02*
Y333680D01*
G01X1565849Y303120D02*
X1565235Y303734D01*
G01X1572820Y303120D02*
X1565849D01*
G01X1544845Y289520D02*
X1547432D01*
G01X1538369Y283044D02*
X1544845Y289520D01*
G01X1531619Y283044D02*
X1538369D01*
G01X1529549Y285114D02*
X1531619Y283044D01*
G01X1529425Y285114D02*
X1529549D01*
G01X1527913Y286626D02*
X1529425Y285114D01*
G01X1527913Y286750D02*
Y286626D01*
G01X1587042Y334350D02*
X1602588D01*
G01X1584932Y332240D02*
X1587042Y334350D01*
G01X1574899Y332240D02*
X1584932D01*
G01X1568142Y325483D02*
X1574899Y332240D01*
G01X1557407Y325483D02*
X1568142D01*
G01X1551785Y331105D02*
X1557407Y325483D01*
G01X1551785Y343201D02*
Y331105D01*
G01X1588576Y322953D02*
X1589476D01*
G01X1586978Y324551D02*
X1588576Y322953D01*
G01X1586978Y326786D02*
Y324551D01*
G01X1588708Y328516D02*
X1586978Y326786D01*
G01X1603931Y328516D02*
X1588708D01*
G01X1542000Y335200D02*
Y340750D01*
G01X1541563Y334763D02*
X1542000Y335200D01*
G01X1541563Y331982D02*
Y334763D01*
G01X1546366Y327179D02*
X1541563Y331982D01*
G01X1549331Y327179D02*
X1546366D01*
G01X1555386Y321124D02*
X1549331Y327179D01*
G01X1570340Y321124D02*
X1555386D01*
G01X1574786Y325570D02*
X1570340Y321124D01*
G01X1584334Y325570D02*
X1574786D01*
G01X1589646Y320258D02*
X1584334Y325570D01*
G01X1544797Y280194D02*
X1546381D01*
G01X1544781Y280210D02*
X1544797Y280194D01*
G01X1541596Y280210D02*
X1544781D01*
G01X1540612Y281194D02*
X1541596Y280210D01*
G01X1530851Y281194D02*
X1540612D01*
G01X1528782Y283263D02*
X1530851Y281194D01*
G01X1528658Y283263D02*
X1528782D01*
G01X1584161Y338400D02*
X1583794Y338767D01*
G01X1587300Y338400D02*
X1584161D01*
G01X1537500Y293400D02*
Y292800D01*
G01X1538707Y294607D02*
X1537500Y293400D01*
G01X1542456Y294607D02*
X1538707D01*
G01X1542457Y294608D02*
X1542456Y294607D01*
G01X1547064Y294608D02*
X1542457D01*
G01X1547065Y294607D02*
X1547064Y294608D01*
G01X1547500Y294607D02*
X1547065D01*
G01X1547501Y294608D02*
X1547500Y294607D01*
G01X1549613Y294608D02*
X1547501D01*
G01X1549614Y294607D02*
X1549613Y294608D01*
G01X1549793Y294607D02*
X1549614D01*
G01X1552052Y292348D02*
X1549793Y294607D01*
G01X1555452Y292348D02*
X1552052D01*
G01X1557837Y289963D02*
X1555452Y292348D01*
G01X1557837Y289233D02*
Y289963D01*
G01X1559116Y287954D02*
X1557837Y289233D01*
G01X1560546Y287954D02*
X1559116D01*
G01X1561779Y286721D02*
X1560546Y287954D01*
G01X1561779Y285581D02*
Y286721D01*
G01X1561778Y285580D02*
X1561779Y285581D01*
G01X1561778Y284400D02*
Y285580D01*
G01X1537158Y293142D02*
X1537500Y292800D01*
G01X1537158Y296351D02*
Y293142D01*
G01X1535004Y298505D02*
X1537158Y296351D01*
G01X1531593Y298505D02*
X1535004D01*
G01X1531132Y298966D02*
X1531593Y298505D01*
G01X1531131Y298966D02*
X1531132D01*
G01X1532080Y309720D02*
Y310820D01*
G01X1534700Y307100D02*
X1532080Y309720D01*
G01X1536900Y307100D02*
X1534700D01*
G01X1538206Y305794D02*
X1536900Y307100D01*
G01X1538206Y303741D02*
Y305794D01*
G01X1530160Y313800D02*
Y315900D01*
G01X1532080Y311880D02*
X1530160Y313800D01*
G01X1532080Y310820D02*
Y311880D01*
G01X1564710Y310800D02*
X1564427Y311083D01*
G01X1569400Y310800D02*
X1564710D01*
G01X1574400Y315800D02*
X1569400Y310800D01*
G01X1581891Y315800D02*
X1574400D01*
G01X1584461Y318370D02*
X1581891Y315800D01*
G01X1586203Y318370D02*
X1584461D01*
G01X1588549Y316024D02*
X1586203Y318370D01*
G01X1588549Y314736D02*
Y316024D01*
G01X1589523Y313762D02*
X1588549Y314736D01*
G01X1585276Y285736D02*
X1620519D01*
G01X1582407Y282867D02*
X1585276Y285736D01*
G01X1577471Y282867D02*
X1582407D01*
G01X1577461Y282877D02*
X1577471Y282867D01*
G01X1573171Y282877D02*
X1577461D01*
G01X1571293Y284755D02*
X1573171Y282877D01*
G01X1530620Y295610D02*
Y295870D01*
G01X1537030Y289200D02*
X1530620Y295610D01*
G01X1540656Y289200D02*
X1537030D01*
G01X1543513Y292057D02*
X1540656Y289200D01*
G01X1548220Y292057D02*
X1543513D01*
G01X1546337Y332762D02*
X1547398Y333823D01*
G01X1546337Y330672D02*
Y332762D01*
G01X1547311Y329698D02*
X1546337Y330672D01*
G01X1549997Y329698D02*
X1547311D01*
G01X1556321Y323374D02*
X1549997Y329698D01*
G01X1569408Y323374D02*
X1556321D01*
G01X1573854Y327820D02*
X1569408Y323374D01*
G01X1584830Y327820D02*
X1573854D01*
G01X1588854Y331844D02*
X1584830Y327820D01*
G01X1565618Y300560D02*
X1565244Y300934D01*
G01X1572820Y300560D02*
X1565618D01*
G01X1539000Y340750D02*
Y337000D01*
G01X1536000Y337052D02*
X1535966Y337018D01*
G01X1536000Y340750D02*
Y337052D01*
G01X1576241Y336200D02*
X1604894D01*
G01X1567578Y327537D02*
X1576241Y336200D01*
G01X1559335Y327537D02*
X1567578D01*
G01X1558340Y328532D02*
X1559335Y327537D01*
G01X1558340Y331060D02*
Y328532D01*
G01X1558311Y331089D02*
X1558340Y331060D01*
G01X1558311Y331560D02*
Y331089D01*
G01X1556500Y333371D02*
X1558311Y331560D01*
G01X1556500Y334750D02*
Y333371D01*
G01X1528216Y310103D02*
X1527409D01*
G01X1530024Y308295D02*
X1528216Y310103D01*
G01X1530024Y304424D02*
Y308295D01*
G01X1532531Y301917D02*
X1530024Y304424D01*
G01X1534417Y301917D02*
X1532531D01*
G01X1534418Y301918D02*
X1534417Y301917D01*
G01X1535598Y301918D02*
X1534418D01*
G01X1536161Y301355D02*
X1535598Y301918D01*
G01X1536186Y301355D02*
X1536161D01*
G01X1537574Y299967D02*
X1536186Y301355D01*
G01X1552488Y299967D02*
X1537574D01*
G01X1557467Y294988D02*
X1552488Y299967D01*
G01X1557467Y294856D02*
Y294988D01*
G01X1563204Y289119D02*
X1557467Y294856D01*
G01X1563204Y284990D02*
Y289119D01*
G01X1567452Y280742D02*
X1563204Y284990D01*
G01X1570672Y280742D02*
X1567452D01*
G01X1533000Y329353D02*
X1535813Y326540D01*
G01X1533000Y340750D02*
Y329353D01*
G01X1537190Y325163D02*
X1535813Y326540D01*
G01X1537190Y317610D02*
Y325163D01*
G01X1538500Y316300D02*
X1537190Y317610D01*
G01X1542243Y316300D02*
X1538500D01*
G01X1547143Y311400D02*
X1542243Y316300D01*
G01X1549969Y311400D02*
X1547143D01*
G01X1557269Y318700D02*
X1549969Y311400D01*
G01X1576701Y318700D02*
X1557269D01*
G01X1580196Y322195D02*
X1576701Y318700D01*
G01X1586118Y322195D02*
X1580196D01*
G01X1589180Y319133D02*
X1586118Y322195D01*
G01X1568497Y287063D02*
X1568230Y287330D01*
G01X1572336Y287063D02*
X1568497D01*
G01X1563000Y338250D02*
Y341000D01*
G01Y341300D02*
X1565500Y343800D01*
G01X1563000Y341000D02*
Y341300D01*
G01X1554800Y341100D02*
X1553500Y342400D01*
G01Y339800D02*
X1554800Y341100D01*
G01X1553500Y338250D02*
Y339800D01*
G01X1533960Y319130D02*
X1527230Y325860D01*
G01X1533960Y313723D02*
Y319130D01*
G01X1539970Y307713D02*
X1533960Y313723D01*
G01X1553146Y307713D02*
X1539970D01*
G01X1562433Y317000D02*
X1553146Y307713D01*
G01X1577017Y317000D02*
X1562433D01*
G01X1580271Y320254D02*
X1577017Y317000D01*
G01X1586042Y320254D02*
X1580271D01*
G01X1588588Y317708D02*
X1586042Y320254D01*
G01X1594984Y317708D02*
X1588588D01*
G01X1589000Y303120D02*
X1583500D01*
G01X1582000Y293348D02*
Y292500D01*
G01X1583963Y295311D02*
X1582000Y293348D01*
G01X1583963Y296887D02*
Y295311D01*
G01X1581837Y299013D02*
X1583963Y296887D01*
G01X1581837Y301637D02*
Y299013D01*
G01X1583320Y303120D02*
X1581837Y301637D01*
G01X1583500Y303120D02*
X1583320D01*
G01X1543932Y290460D02*
X1547801D01*
G01X1537441Y283969D02*
X1543932Y290460D01*
G01X1532003Y283969D02*
X1537441D01*
G01X1529933Y286039D02*
X1532003Y283969D01*
G01X1529809Y286039D02*
X1529933D01*
G01X1528837Y287011D02*
X1529809Y286039D01*
G01X1528837Y287135D02*
Y287011D01*
G01X1528563Y287409D02*
X1528837Y287135D01*
G01X1528563Y295911D02*
Y287409D01*
G01X1562574Y279726D02*
X1564436D01*
G01X1549118Y293182D02*
X1562574Y279726D01*
G01X1549023Y293182D02*
X1549118D01*
G01X1549022Y293183D02*
X1549023Y293182D01*
G01X1548092Y293183D02*
X1549022D01*
G01X1548091Y293182D02*
X1548092Y293183D01*
G01X1546474Y293182D02*
X1548091D01*
G01X1546473Y293183D02*
X1546474Y293182D01*
G01X1543048Y293183D02*
X1546473D01*
G01X1543047Y293182D02*
X1543048Y293183D01*
G01X1541600Y293182D02*
X1543047D01*
G01X1538918Y290500D02*
X1541600Y293182D01*
G01X1537322Y290500D02*
X1538918D01*
G01X1531745Y296077D02*
X1537322Y290500D01*
G01X1531745Y296337D02*
Y296077D01*
G01X1530541Y297541D02*
X1531745Y296337D01*
G01X1530540Y297541D02*
X1530541D01*
G01X1548199Y285830D02*
Y283717D01*
G01X1589000Y300560D02*
X1583500D01*
G01X1585000Y297300D02*
Y292500D01*
G01X1583425Y298875D02*
X1585000Y297300D01*
G01X1583425Y300485D02*
Y298875D01*
G01X1583500Y300560D02*
X1583425Y300485D01*
G01X1568932Y283092D02*
X1571647D01*
G01X1565555Y286469D02*
X1568932Y283092D01*
G01X1565555Y287825D02*
Y286469D01*
G01X1567000Y289270D02*
X1565555Y287825D01*
G01X1567000Y291200D02*
Y289270D01*
G01X1565002Y293198D02*
X1567000Y291200D01*
G01X1561141Y293198D02*
X1565002D01*
G01X1558893Y295446D02*
X1561141Y293198D01*
G01X1558893Y295578D02*
Y295446D01*
G01X1553079Y301392D02*
X1558893Y295578D01*
G01X1538165Y301392D02*
X1553079D01*
G01X1536777Y302780D02*
X1538165Y301392D01*
G01X1536752Y302780D02*
X1536777D01*
G01X1536189Y303343D02*
X1536752Y302780D01*
G01X1535028Y303343D02*
X1536189D01*
G01X1534421Y303950D02*
X1535028Y303343D01*
G01X1532850Y303950D02*
X1534421D01*
G01X1545000Y336900D02*
Y340750D01*
G01Y336456D02*
Y336900D01*
G01X1543241Y334697D02*
X1545000Y336456D01*
G01X1543241Y333319D02*
Y334697D01*
G01X1544215Y332345D02*
X1543241Y333319D01*
G01X1544303Y332345D02*
X1544215D01*
G01X1545212Y331436D02*
X1544303Y332345D01*
G01X1545212Y330206D02*
Y331436D01*
G01X1547114Y328304D02*
X1545212Y330206D01*
G01X1549797Y328304D02*
X1547114D01*
G01X1555852Y322249D02*
X1549797Y328304D01*
G01X1569874Y322249D02*
X1555852D01*
G01X1574320Y326695D02*
X1569874Y322249D01*
G01X1585296Y326695D02*
X1574320D01*
G01X1588242Y329641D02*
X1585296Y326695D01*
G01X1603465Y329641D02*
X1588242D01*
G01X1553500Y333500D02*
Y334750D01*
G01X1553058Y333058D02*
X1553500Y333500D01*
G01X1553058Y331693D02*
Y333058D01*
G01X1558139Y326612D02*
X1553058Y331693D01*
G01X1567962Y326612D02*
X1558139D01*
G01X1575587Y334237D02*
X1567962Y326612D01*
G01X1582659Y334237D02*
X1575587D01*
G01X1586128Y335275D02*
X1602972D01*
G01X1585090Y334237D02*
X1586128Y335275D01*
G01X1582659Y334237D02*
X1585090D01*
G01X1556500Y342200D02*
X1557600Y341100D01*
G01D02*
X1557550D01*
G01X1556500Y340000D02*
X1557600Y341100D01*
G01X1556500Y338250D02*
Y340000D01*
G01X1546032Y354532D02*
Y352846D01*
G01X1546182Y354682D02*
X1546032Y354532D01*
G01X1546182Y355446D02*
Y354682D01*
G01X1557534Y353566D02*
X1555100Y356000D01*
G01X1557534Y353400D02*
Y353566D01*
G01X1548789Y343863D02*
X1549763Y342889D01*
G01X1548779Y343863D02*
X1548789D01*
G01X1546688Y345954D02*
X1548779Y343863D01*
G01X1544824Y345954D02*
X1546688D01*
G01X1544250Y346528D02*
X1544824Y345954D01*
G01X1544250Y346532D02*
Y346528D01*
G01X1540957Y349825D02*
X1544250Y346532D01*
G01X1540953Y349825D02*
X1540957D01*
G01X1540644Y350134D02*
X1540953Y349825D01*
G01X1540644Y356080D02*
Y350134D01*
G01X1539024Y357700D02*
X1540644Y356080D01*
G01X1537811Y357700D02*
X1539024D01*
G01X1536734Y358777D02*
X1537811Y357700D01*
G01X1536734Y363234D02*
Y358777D01*
G01X1538200Y364700D02*
X1536734Y363234D01*
G01X1568600Y343600D02*
Y344050D01*
G01X1581000Y341928D02*
Y343750D01*
G01X1570348Y347800D02*
X1571800D01*
G01X1570098Y347550D02*
X1570348Y347800D01*
G01X1568600Y347550D02*
X1570098D01*
G01X1553593Y362607D02*
X1550417D01*
G01X1562190Y354010D02*
X1553593Y362607D01*
G01X1563169Y354010D02*
X1562190D01*
G01X1565188Y351991D02*
X1563169Y354010D01*
G01X1568600Y348596D02*
Y347550D01*
G01X1565205Y351991D02*
X1568600Y348596D01*
G01X1565188Y351991D02*
X1565205D01*
G01X1529000Y348198D02*
Y347250D01*
G01X1529869Y349067D02*
X1529000Y348198D01*
G01X1529869Y350977D02*
Y349067D01*
G01X1527986Y352860D02*
X1529869Y350977D01*
G01X1527478Y352860D02*
X1527986D01*
G01X1582733Y385500D02*
X1589250D01*
G01X1579706Y388527D02*
X1582733Y385500D01*
G01X1579706Y390104D02*
Y388527D01*
G01X1578750Y391060D02*
X1579706Y390104D01*
G01X1577206Y392604D02*
X1578750Y391060D01*
G01X1575675Y392604D02*
X1577206D01*
G01X1572254Y396025D02*
X1575675Y392604D01*
G01X1568534Y396025D02*
X1572254D01*
G01X1567475Y397084D02*
X1568534Y396025D01*
G01X1567475Y401174D02*
Y397084D01*
G01X1573346Y387654D02*
X1571375D01*
G01X1581525Y379475D02*
X1573346Y387654D01*
G01X1583635Y379475D02*
X1581525D01*
G01X1585349Y377761D02*
X1583635Y379475D01*
G01X1594026Y377761D02*
X1585349D01*
G01X1529000Y342400D02*
Y343750D01*
G01X1528000Y341400D02*
X1529000Y342400D01*
G01X1549532Y348196D02*
Y347696D01*
G01X1548800Y348928D02*
X1549532Y348196D01*
G01X1548800Y352114D02*
Y348928D01*
G01X1549532Y352846D02*
X1548800Y352114D01*
G01X1549532Y345454D02*
X1551785Y343201D01*
G01X1549532Y347696D02*
Y345454D01*
G01X1528475Y387654D02*
Y383901D01*
G01X1551875Y373578D02*
X1554150Y371303D01*
G01X1551875Y380894D02*
Y373578D01*
G01X1577250Y351000D02*
X1581000Y347250D01*
G01X1571991Y351000D02*
X1577250D01*
G01X1564131Y358860D02*
X1571991Y351000D01*
G01X1564131Y365829D02*
Y358860D01*
G01X1560493Y369467D02*
X1564131Y365829D01*
G01X1555986Y369467D02*
X1560493D01*
G01X1554150Y371303D02*
X1555986Y369467D01*
G01X1559500Y348648D02*
Y347250D01*
G01X1558837Y349311D02*
X1559500Y348648D01*
G01X1558837Y349341D02*
Y349311D01*
G01X1549303Y358875D02*
X1558837Y349341D01*
G01X1547278Y360900D02*
X1549303Y358875D01*
G01X1543300Y360900D02*
X1547278D01*
G01X1583866Y383013D02*
X1585298D01*
G01X1574111Y392768D02*
X1583866Y383013D01*
G01X1571159Y392768D02*
X1574111D01*
G01X1569425Y391034D02*
X1571159Y392768D01*
G01X1585811Y382500D02*
X1589250D01*
G01X1585298Y383013D02*
X1585811Y382500D01*
G01X1527873Y355417D02*
Y358627D01*
G01X1531567Y351723D02*
X1527873Y355417D01*
G01X1531567Y347933D02*
Y351723D01*
G01X1533000Y346500D02*
X1531567Y347933D01*
G01X1533000Y344250D02*
Y346500D01*
G01X1562500Y347300D02*
X1565500D01*
G01X1546350Y363400D02*
X1543300D01*
G01X1547100D02*
X1546350D01*
G01X1549600Y360900D02*
X1547100Y363400D01*
G01X1553100Y360900D02*
X1549600D01*
G01X1565500Y348500D02*
X1553100Y360900D01*
G01X1565500Y347300D02*
Y348500D01*
G01X1586277Y348800D02*
X1597900D01*
G01X1583221Y351856D02*
X1586277Y348800D01*
G01X1578870Y351856D02*
X1583221D01*
G01X1573229Y357497D02*
X1578870Y351856D01*
G01X1573229Y361979D02*
Y357497D01*
G01X1570101Y365107D02*
X1573229Y361979D01*
G01X1570101Y367583D02*
Y365107D01*
G01X1568036Y369648D02*
X1570101Y367583D01*
G01X1567150Y369648D02*
X1568036D01*
G01X1567149Y369649D02*
X1567150Y369648D01*
G01X1566467Y369649D02*
X1567149D01*
G01X1566466Y369648D02*
X1566467Y369649D01*
G01X1564477Y369648D02*
X1566466D01*
G01X1559497Y374628D02*
X1564477Y369648D01*
G01X1559497Y378420D02*
Y374628D01*
G01X1557508Y380409D02*
X1559497Y378420D01*
G01X1557508Y381736D02*
Y380409D01*
G01X1555714Y383530D02*
X1557508Y381736D01*
G01X1555714Y384779D02*
Y383530D01*
G01X1553646Y386847D02*
X1555714Y384779D01*
G01X1553646Y388135D02*
Y386847D01*
G01X1555519Y390008D02*
X1553646Y388135D01*
G01X1555519Y391646D02*
Y390008D01*
G01X1557725Y393852D02*
X1555519Y391646D01*
G01X1557725Y397794D02*
Y393852D01*
G01X1534000Y369561D02*
Y371500D01*
G01X1531719Y367280D02*
X1534000Y369561D01*
G01X1531719Y359987D02*
Y367280D01*
G01X1535500Y356206D02*
X1531719Y359987D01*
G01X1535500Y349549D02*
Y356206D01*
G01X1537474Y347575D02*
X1535500Y349549D01*
G01X1540025Y347575D02*
X1537474D01*
G01X1542000Y345600D02*
X1540025Y347575D01*
G01X1542000Y344250D02*
Y345600D01*
G01X1534000Y374726D02*
Y371500D01*
G01X1534679Y375405D02*
X1534000Y374726D01*
G01X1571700Y382230D02*
X1571585D01*
G01X1571700Y382150D02*
Y382230D01*
G01X1571931Y382150D02*
X1571700D01*
G01X1576129Y377952D02*
X1571931Y382150D01*
G01X1581655Y372426D02*
X1576129Y377952D01*
G01X1587574Y372426D02*
X1581655D01*
G01X1588750Y371250D02*
X1587574Y372426D01*
G01X1588750Y370882D02*
Y371250D01*
G01X1588852Y370780D02*
X1588750Y370882D01*
G01X1529400Y370200D02*
Y367200D01*
G01X1532278Y373078D02*
X1529400Y370200D01*
G01X1534375Y348875D02*
X1539000Y344250D01*
G01X1534375Y352097D02*
Y348875D01*
G01X1530683Y355789D02*
X1534375Y352097D01*
G01X1530683Y358999D02*
Y355789D01*
G01X1529490Y360192D02*
X1530683Y358999D01*
G01X1529490Y360206D02*
Y360192D01*
G01X1528166Y361530D02*
X1529490Y360206D01*
G01X1528166Y363766D02*
Y361530D01*
G01X1529400Y365000D02*
X1528166Y363766D01*
G01X1529400Y367200D02*
Y365000D01*
G01X1573633Y353400D02*
X1571598Y355435D01*
G01X1576017Y353400D02*
X1573633D01*
G01X1579006Y350411D02*
X1576017Y353400D01*
G01X1580839Y350411D02*
X1579006D01*
G01X1584000Y347250D02*
X1580839Y350411D01*
G01X1551875Y397375D02*
Y401174D01*
G01X1550000Y395500D02*
X1551875Y397375D01*
G01X1550000Y393500D02*
Y395500D01*
G01X1552015Y391485D02*
X1550000Y393500D01*
G01X1552015Y390404D02*
Y391485D01*
G01X1550096Y388485D02*
X1552015Y390404D01*
G01X1550096Y386847D02*
Y388485D01*
G01X1552066Y384877D02*
X1550096Y386847D01*
G01X1552066Y383218D02*
Y384877D01*
G01X1553665Y381619D02*
X1552066Y383218D01*
G01X1553665Y380371D02*
Y381619D01*
G01X1555733Y378303D02*
X1553665Y380371D01*
G01X1555733Y374636D02*
Y378303D01*
G01X1559224Y371145D02*
X1555733Y374636D01*
G01X1560766Y371145D02*
X1559224D01*
G01X1563088Y368823D02*
X1560766Y371145D01*
G01X1566808Y368823D02*
X1563088D01*
G01X1568998Y366633D02*
X1566808Y368823D01*
G01X1568998Y358035D02*
Y366633D01*
G01X1571598Y355435D02*
X1568998Y358035D01*
G01X1569584Y372425D02*
Y378002D01*
G01X1585320Y356689D02*
X1569584Y372425D01*
G01X1593708Y356689D02*
X1585320D01*
G01X1553067Y395606D02*
X1551875Y394414D01*
G01X1553909Y395606D02*
X1553067D01*
G01X1556009Y397706D02*
X1553909Y395606D01*
G01X1556009Y398350D02*
Y397706D01*
G01X1557060Y399401D02*
X1556009Y398350D01*
G01X1562290Y399401D02*
X1557060D01*
G01X1563851Y397840D02*
X1562290Y399401D01*
G01X1563851Y396542D02*
Y397840D01*
G01X1565182Y395211D02*
X1563851Y396542D01*
G01X1565182Y393347D02*
Y395211D01*
G01X1563344Y391509D02*
X1565182Y393347D01*
G01X1563344Y390169D02*
Y391509D01*
G01X1561643Y388468D02*
X1563344Y390169D01*
G01X1561643Y386671D02*
Y388468D01*
G01X1563868Y384446D02*
X1561643Y386671D01*
G01X1563868Y383659D02*
Y384446D01*
G01X1563912Y383615D02*
X1563868Y383659D01*
G01X1563912Y383606D02*
Y383615D01*
G01X1564857Y382661D02*
X1563912Y383606D01*
G01X1566193Y382661D02*
X1564857D01*
G01X1566232Y382700D02*
X1566193Y382661D01*
G01X1567941Y382700D02*
X1566232D01*
G01X1572484Y378157D02*
X1567941Y382700D01*
G01X1572484Y374943D02*
Y378157D01*
G01X1576305Y371122D02*
X1572484Y374943D01*
G01X1588750Y366015D02*
X1588852Y366117D01*
G01X1588750Y365424D02*
Y366015D01*
G01X1587780Y364454D02*
X1588750Y365424D01*
G01X1584078Y364454D02*
X1587780D01*
G01X1583689Y364843D02*
X1584078Y364454D01*
G01X1583689Y366522D02*
Y364843D01*
G01X1582345Y367866D02*
X1583689Y366522D01*
G01X1579561Y367866D02*
X1582345D01*
G01X1576305Y371122D02*
X1579561Y367866D01*
G01X1546032Y349942D02*
Y347696D01*
G01X1544791Y351183D02*
X1546032Y349942D01*
G01X1544758Y351183D02*
X1544791D01*
G01X1544369Y351572D02*
X1544758Y351183D01*
G01X1544369Y351605D02*
Y351572D01*
G01X1543528Y352446D02*
X1544369Y351605D01*
G01X1540300Y373500D02*
Y371800D01*
G01X1539800Y374000D02*
X1540300Y373500D01*
G01X1539800Y375960D02*
Y374000D01*
G01X1553500Y347798D02*
Y347250D01*
G01X1554333Y348631D02*
X1553500Y347798D01*
G01X1554333Y351227D02*
Y348631D01*
G01X1550592Y354968D02*
X1554333Y351227D01*
G01X1549056Y354968D02*
X1550592D01*
G01X1546431Y357593D02*
X1549056Y354968D01*
G01X1542733Y357593D02*
X1546431D01*
G01X1540299Y360027D02*
X1542733Y357593D01*
G01X1540299Y360875D02*
Y360027D01*
G01X1540300Y360876D02*
X1540299Y360875D01*
G01X1540300Y371800D02*
Y360876D01*
G01X1579159Y352876D02*
X1593639D01*
G01X1574154Y357881D02*
X1579159Y352876D01*
G01X1574154Y362363D02*
Y357881D01*
G01X1570926Y365591D02*
X1574154Y362363D01*
G01X1570926Y368001D02*
Y365591D01*
G01X1563321Y375606D02*
X1570926Y368001D01*
G01X1563321Y378381D02*
Y375606D01*
G01X1561819Y379883D02*
X1563321Y378381D01*
G01X1561819Y381483D02*
Y379883D01*
G01X1559673Y383629D02*
X1561819Y381483D01*
G01X1559673Y385052D02*
Y383629D01*
G01X1557742Y386983D02*
X1559673Y385052D01*
G01X1557742Y388408D02*
Y386983D01*
G01X1559966Y390632D02*
X1557742Y388408D01*
G01X1559966Y391997D02*
Y390632D01*
G01X1562383Y394414D02*
X1559966Y391997D01*
G01X1563575Y394414D02*
X1562383D01*
G01X1587099Y389001D02*
X1585650D01*
G01X1587600Y388500D02*
X1587099Y389001D01*
G01X1589250Y388500D02*
X1587600D01*
G01X1569290Y401984D02*
X1568189Y403085D01*
G01X1569290Y400382D02*
Y401984D01*
G01X1575785Y393887D02*
X1569290Y400382D01*
G01X1578718Y393887D02*
X1575785D01*
G01X1580700Y391905D02*
X1578718Y393887D01*
G01X1580700Y388927D02*
Y391905D01*
G01X1581934Y387693D02*
X1580700Y388927D01*
G01X1583266Y387693D02*
X1581934D01*
G01X1583269Y387696D02*
X1583266Y387693D01*
G01X1583275Y387696D02*
X1583269D01*
G01X1584580Y389001D02*
X1583275Y387696D01*
G01X1585650Y389001D02*
X1584580D01*
G01X1543651Y373807D02*
Y368755D01*
G01X1556500Y350369D02*
Y347250D01*
G01X1550706Y356163D02*
X1556500Y350369D01*
G01X1549213Y356163D02*
X1550706D01*
G01X1546801Y358575D02*
X1549213Y356163D01*
G01X1543201Y358575D02*
X1546801D01*
G01X1541325Y360451D02*
X1543201Y358575D01*
G01X1541325Y366429D02*
Y360451D01*
G01X1543651Y368755D02*
X1541325Y366429D01*
G01X1581433Y354900D02*
X1580029Y356304D01*
G01X1586500Y354900D02*
X1581433D01*
G01X1581861Y383700D02*
X1580253D01*
G01X1583731Y381830D02*
X1581861Y383700D01*
G01X1583731Y381042D02*
Y381830D01*
G01X1585273Y379500D02*
X1583731Y381042D01*
G01X1589250Y379500D02*
X1585273D01*
G01X1569763Y394414D02*
X1571375D01*
G01X1567818Y392469D02*
X1569763Y394414D01*
G01X1567818Y390369D02*
Y392469D01*
G01X1568760Y389427D02*
X1567818Y390369D01*
G01X1574526Y389427D02*
X1568760D01*
G01X1580253Y383700D02*
X1574526Y389427D01*
G01X1553500Y342400D02*
Y343750D01*
G01X1581822Y363298D02*
Y365770D01*
G01X1584873Y360247D02*
X1581822Y363298D01*
G01X1592746Y360247D02*
X1584873D01*
G01X1530814Y374814D02*
X1528339Y372339D01*
G01X1536000Y345500D02*
Y344250D01*
G01X1532883Y348617D02*
X1536000Y345500D01*
G01X1532883Y351998D02*
Y348617D01*
G01X1529522Y355359D02*
X1532883Y351998D01*
G01X1529522Y358569D02*
Y355359D01*
G01X1556500Y343750D02*
Y342200D01*
G01X1565525Y387332D02*
Y391034D01*
G01X1565868Y386989D02*
X1565525Y387332D01*
G01X1565868Y386988D02*
Y386989D01*
G01X1566809Y386047D02*
X1565868Y386988D01*
G01X1571776Y386047D02*
X1566809D01*
G01X1581643Y376180D02*
X1571776Y386047D01*
G01X1584620Y376180D02*
X1581643D01*
G01X1585600Y375200D02*
X1584620Y376180D01*
G01X1587024Y373776D02*
X1585600Y375200D01*
G01X1590193Y373776D02*
X1587024D01*
G01X1536800Y365489D02*
Y367300D01*
G01X1535534Y364223D02*
X1536800Y365489D01*
G01X1535534Y358000D02*
Y364223D01*
G01X1536815Y356719D02*
X1535534Y358000D01*
G01X1536815Y349837D02*
Y356719D01*
G01X1537952Y348700D02*
X1536815Y349837D01*
G01X1540491Y348700D02*
X1537952D01*
G01X1543125Y346066D02*
X1540491Y348700D01*
G01X1543125Y346062D02*
Y346066D01*
G01X1544937Y344250D02*
X1543125Y346062D01*
G01X1545000Y344250D02*
X1544937D01*
G01X1536800Y370453D02*
Y367300D01*
G01X1538000Y371653D02*
X1536800Y370453D01*
G01X1538000Y375000D02*
Y371653D01*
G01X1537286Y375714D02*
X1538000Y375000D01*
G01X1573877Y449267D02*
Y451641D01*
G01X1573350Y448740D02*
X1573877Y449267D01*
G01X1572082Y448740D02*
X1573350D01*
G01X1572041Y448699D02*
X1572082Y448740D01*
G01X1570709Y448699D02*
X1572041D01*
G01X1570668Y448740D02*
X1570709Y448699D01*
G01X1568182Y448740D02*
X1570668D01*
G01X1568141Y448699D02*
X1568182Y448740D01*
G01X1567298Y448699D02*
X1568141D01*
G01X1565525Y446926D02*
X1567298Y448699D01*
G01X1588074Y431743D02*
X1589317Y430500D01*
G01X1588074Y431757D02*
Y431743D01*
G01X1587238Y432593D02*
X1588074Y431757D01*
G01X1583280Y447080D02*
X1582300Y446100D01*
G01X1583280Y449100D02*
Y447080D01*
G01X1583060Y449320D02*
X1583280Y449100D01*
G01X1580844Y451536D02*
X1583060Y449320D01*
G01X1577782Y451536D02*
X1580844D01*
G01X1580595Y425250D02*
X1581939Y426594D01*
G01X1579500Y425250D02*
X1580595D01*
G01X1584200Y464010D02*
Y462610D01*
G01X1582810Y465400D02*
X1584200Y464010D01*
G01X1577782Y463682D02*
X1579500Y465400D01*
G01X1577782Y461336D02*
Y463682D01*
G01X1583208Y415208D02*
Y416752D01*
G01X1581250Y413250D02*
X1583208Y415208D01*
G01X1579000Y413250D02*
X1581250D01*
G01X1559194Y403085D02*
X1557725Y404554D01*
G01X1568189Y403085D02*
X1559194D01*
G01X1580370Y459716D02*
Y462090D01*
G01X1578490Y457836D02*
X1580370Y459716D01*
G01X1577782Y457836D02*
X1578490D01*
G01X1576525D02*
X1577782D01*
G01X1576100Y458261D02*
X1576525Y457836D01*
G01X1576100Y461000D02*
Y458261D01*
G01X1575659Y461441D02*
X1576100Y461000D01*
G01X1574377Y461441D02*
X1575659D01*
G01X1534020Y514344D02*
Y511930D01*
G01X1531264Y517100D02*
X1534020Y514344D01*
G01X1581000Y465400D02*
X1582810D01*
G01X1579500D02*
X1581000D01*
G01X1567437Y601563D02*
X1570660D01*
G01X1567300Y601700D02*
X1567437Y601563D01*
G01X1579200Y600500D02*
X1581000D01*
G01X1578000Y599300D02*
X1579200Y600500D01*
G01X1572923Y599300D02*
X1578000D01*
G01X1570660Y601563D02*
X1572923Y599300D01*
G01X1579407Y592132D02*
X1585830D01*
G01X1578069Y590794D02*
X1579407Y592132D01*
G01X1578069Y589228D02*
Y590794D01*
G01X1588667Y593048D02*
X1590968D01*
G01X1587751Y592132D02*
X1588667Y593048D01*
G01X1585830Y592132D02*
X1587751D01*
G01X1579033Y603500D02*
X1581000D01*
G01X1577133Y601600D02*
X1579033Y603500D01*
G01X1573260Y601600D02*
X1577133D01*
G01X1571982Y589228D02*
X1574569D01*
G01X1571080Y590130D02*
X1571982Y589228D01*
G01X1571080Y591445D02*
Y590130D01*
G01Y592956D02*
Y591445D01*
G01X1572074Y593950D02*
X1571080Y592956D01*
G01X1572950Y593950D02*
X1572074D01*
G01X1557039Y610479D02*
Y614627D01*
G01X1556630Y610070D02*
X1557039Y610479D01*
G01X1556060Y609500D02*
X1556630Y610070D01*
G01X1544900Y609500D02*
X1556060D01*
G01X1540700Y613700D02*
X1544900Y609500D01*
G01X1595004Y-16296D02*
Y-17346D01*
G01X1595587Y-15713D02*
X1595004Y-16296D01*
G01X1596874Y-15713D02*
X1595587D01*
G01X1597400Y-15187D02*
X1596874Y-15713D01*
G01X1597400Y-7500D02*
Y-15187D01*
G01X1596700Y-6800D02*
X1597400Y-7500D01*
G01X1596700Y1535D02*
Y-6800D01*
G01X1598602Y3437D02*
X1596700Y1535D01*
G01X1601502Y3437D02*
X1598602D01*
G01X1621500Y19800D02*
Y22250D01*
G01X1623400Y17900D02*
X1621500Y19800D01*
G01X1623400Y17500D02*
Y17900D01*
G01X1623950Y22250D02*
X1621500D01*
G01X1624400Y22700D02*
X1623950Y22250D01*
G01X1624400Y24000D02*
Y22700D01*
G01X1624800Y24400D02*
X1624400Y24000D01*
G01X1628500Y24400D02*
X1624800D01*
G01X1619300Y22250D02*
X1621500D01*
G01X1617750Y23800D02*
X1619300Y22250D01*
G01X1615968Y23800D02*
X1617750D01*
G01X1591607Y32792D02*
X1595477Y36662D01*
G01X1591607Y25682D02*
Y32792D01*
G01X1592829Y24460D02*
X1591607Y25682D01*
G01X1613000Y-6218D02*
Y-10718D01*
G01X1610582D02*
X1608500Y-12800D01*
G01X1613000Y-10718D02*
X1610582D01*
G01X1644000Y17306D02*
Y22250D01*
G01X1644806Y16500D02*
X1644000Y17306D01*
G01X1647500Y16500D02*
X1644806D01*
G01X1646410Y22250D02*
X1644000D01*
G01X1647182Y23022D02*
X1646410Y22250D01*
G01X1647182Y25036D02*
Y23022D01*
G01X1648087Y25941D02*
X1647182Y25036D01*
G01X1651250Y25941D02*
X1648087D01*
G01X1618248Y-19500D02*
X1617723Y-20025D01*
G01X1618325Y-19500D02*
X1618248D01*
G01X1622829Y-14996D02*
X1618325Y-19500D01*
G01X1622829Y-12493D02*
Y-14996D01*
G01X1636522Y1200D02*
X1622829Y-12493D01*
G01X1638776Y1200D02*
X1636522D01*
G01X1650717Y13141D02*
X1638776Y1200D01*
G01X1650096Y16500D02*
X1650717Y15879D01*
G01X1647500Y16500D02*
X1650096D01*
G01X1630750Y17000D02*
X1634250D01*
G01X1630750Y12950D02*
X1631500Y12200D01*
G01X1630750Y17000D02*
Y12950D01*
G01X1634250Y25400D02*
X1637000Y28150D01*
G01X1634250Y17000D02*
Y25400D01*
G01X1597800Y24727D02*
Y24300D01*
G01X1598707Y25634D02*
X1597800Y24727D01*
G01X1598707Y42237D02*
Y25634D01*
G01X1610004Y-15096D02*
Y-17346D01*
G01X1610882Y-14218D02*
X1610004Y-15096D01*
G01X1613000Y-14218D02*
X1610882D01*
G01X1620000Y32750D02*
X1621500D01*
G01X1618050Y34700D02*
X1620000Y32750D01*
G01X1617050Y32450D02*
Y34700D01*
G01X1615968Y31368D02*
X1617050Y32450D01*
G01X1615968Y28300D02*
Y31368D01*
G01X1621904Y-14496D02*
X1617391Y-19009D01*
G01X1621904Y-12109D02*
Y-14496D01*
G01X1628063Y-5950D02*
X1621904Y-12109D01*
G01X1628063Y5346D02*
Y-5950D01*
G01X1627335Y6074D02*
X1628063Y5346D01*
G01X1627335Y7576D02*
Y6074D01*
G01X1629163Y9404D02*
X1627335Y7576D01*
G01X1629163Y13037D02*
Y9404D01*
G01X1627250Y14950D02*
X1629163Y13037D01*
G01X1627250Y17000D02*
Y14950D01*
G01X1599259Y-11741D02*
X1601600D01*
G01X1598700Y-12300D02*
X1599259Y-11741D01*
G01X1598700Y-16042D02*
Y-12300D01*
G01X1600004Y-17346D02*
X1598700Y-16042D01*
G01X1623041Y-3659D02*
X1620000D01*
G01X1623900Y-2800D02*
X1623041Y-3659D01*
G01X1623900Y4600D02*
Y-2800D01*
G01X1592400Y-14300D02*
X1594600D01*
G01X1591400Y-13300D02*
X1592400Y-14300D01*
G01X1590100Y-13300D02*
X1591400D01*
G01X1590100Y-12400D02*
X1589337Y-11637D01*
G01X1590100Y-13300D02*
Y-12400D01*
G01X1590582Y25487D02*
Y33489D01*
G01X1589623Y24528D02*
X1590582Y25487D01*
G01X1590293Y44641D02*
Y51938D01*
G01X1595477Y39457D02*
X1590293Y44641D01*
G01X1595477Y36662D02*
Y39457D01*
G01X1590293Y62567D02*
Y51938D01*
G01X1625799Y44800D02*
X1627330D01*
G01X1624310Y43311D02*
X1625799Y44800D01*
G01X1622750Y43311D02*
X1624310D01*
G01X1622237Y46763D02*
X1621227D01*
G01X1622750Y46250D02*
X1622237Y46763D01*
G01X1622750Y43311D02*
Y46250D01*
G01X1630386Y43414D02*
Y41448D01*
G01X1629000Y44800D02*
X1630386Y43414D01*
G01X1627330Y44800D02*
X1629000D01*
G01X1624750Y73669D02*
Y72000D01*
G01X1625826Y74745D02*
X1624750Y73669D01*
G01X1625826Y75718D02*
Y74745D01*
G01X1626833Y76725D02*
X1625826Y75718D01*
G01X1626833Y81719D02*
Y76725D01*
G01X1628100Y82986D02*
X1626833Y81719D01*
G01X1628100Y88200D02*
Y82986D01*
G01X1629075Y89175D02*
X1628100Y88200D01*
G01X1629075Y97513D02*
Y89175D01*
G01X1652279Y60221D02*
X1648400D01*
G01X1628500Y81400D02*
Y80300D01*
G01X1629500Y82400D02*
X1628500Y81400D01*
G01X1629500Y86761D02*
Y82400D01*
G01X1630826Y88087D02*
X1629500Y86761D01*
G01X1596050Y75350D02*
Y75400D01*
G01X1593180Y72480D02*
X1596050Y75350D01*
G01X1592026Y72480D02*
X1593180D01*
G01X1590952Y71406D02*
X1592026Y72480D01*
G01X1590952Y68916D02*
Y71406D01*
G01X1594350Y65518D02*
X1590952Y68916D01*
G01X1594350Y50950D02*
Y65518D01*
G01X1597244Y48056D02*
X1594350Y50950D01*
G01X1597244Y43700D02*
Y48056D01*
G01Y43700D02*
X1598707Y42237D01*
G01X1604984Y64984D02*
X1603000Y63000D01*
G01X1604984Y65700D02*
Y64984D01*
G01X1607000Y67716D02*
X1604984Y65700D01*
G01X1607000Y71532D02*
Y67716D01*
G01X1606606Y71926D02*
X1607000Y71532D01*
G01X1606606Y72003D02*
Y71926D01*
G01X1606533Y72076D02*
X1606606Y72003D01*
G01X1606533Y73608D02*
Y72076D01*
G01X1607425Y74500D02*
X1606533Y73608D01*
G01X1611000Y74500D02*
X1607425D01*
G01X1612650Y72850D02*
X1611000Y74500D01*
G01X1621122Y72850D02*
X1612650D01*
G01X1623200Y74928D02*
X1621122Y72850D01*
G01X1623200Y75800D02*
Y74928D01*
G01X1603550Y56750D02*
Y58200D01*
G01X1603800Y56500D02*
X1603550Y56750D01*
G01X1603800Y54950D02*
Y56500D01*
G01X1603550Y59622D02*
Y58200D01*
G01X1603000Y60172D02*
X1603550Y59622D01*
G01X1603000Y63000D02*
Y60172D01*
G01X1609000Y58060D02*
X1611900D01*
G01X1608860Y58200D02*
X1609000Y58060D01*
G01X1607050Y58200D02*
X1608860D01*
G01X1611900Y61400D02*
X1614000Y63500D01*
G01X1611900Y58060D02*
Y61400D01*
G01X1635000Y76500D02*
X1638580D01*
G01X1632000Y73500D02*
X1635000Y76500D01*
G01X1645025Y50610D02*
X1650658D01*
G01X1644600Y51035D02*
X1645025Y50610D01*
G01X1644600Y53046D02*
Y51035D01*
G01X1643587Y54059D02*
X1644600Y53046D01*
G01X1643587Y74313D02*
Y54059D01*
G01X1641400Y76500D02*
X1643587Y74313D01*
G01X1638580Y76500D02*
X1641400D01*
G01X1617050Y34700D02*
X1618050D01*
G01X1617050Y38150D02*
X1615400Y39800D01*
G01X1617050Y34700D02*
Y38150D01*
G01X1614638Y46763D02*
X1614559Y46684D01*
G01X1617727Y46763D02*
X1614638D01*
G01X1624500Y49500D02*
Y50890D01*
G01X1624000Y49000D02*
X1624500Y49500D01*
G01X1618152Y49000D02*
X1624000D01*
G01X1617727Y48575D02*
X1618152Y49000D01*
G01X1617727Y46763D02*
Y48575D01*
G01X1623860Y52940D02*
X1619300D01*
G01X1624500Y52300D02*
X1623860Y52940D01*
G01X1624500Y50890D02*
Y52300D01*
G01X1623614Y60086D02*
X1635841Y47859D01*
G01X1623614Y63162D02*
Y60086D01*
G01X1621076Y65700D02*
X1623614Y63162D01*
G01X1612692Y65700D02*
X1621076D01*
G01X1610853Y63861D02*
X1612692Y65700D01*
G01X1640700Y43000D02*
X1675100D01*
G01X1635841Y47859D02*
X1640700Y43000D01*
G01X1638500Y90500D02*
X1641600D01*
G01X1636008Y92592D02*
X1638100Y90500D01*
G01X1636008Y104883D02*
Y92592D01*
G01X1638100Y90500D02*
X1638500D01*
G01X1644000D02*
X1646000Y92500D01*
G01X1641600Y90500D02*
X1644000D01*
G01X1620450Y62950D02*
X1619750Y63650D01*
G01X1620450Y60850D02*
Y62950D01*
G01X1619300Y59700D02*
X1620450Y60850D01*
G01X1619300Y58060D02*
Y59700D01*
G01X1614216Y52940D02*
X1611900D01*
G01X1614852Y53576D02*
X1614216Y52940D01*
G01X1614852Y59651D02*
Y53576D01*
G01X1618851Y63650D02*
X1614852Y59651D01*
G01X1619750Y63650D02*
X1618851D01*
G01X1602000Y87250D02*
Y84500D01*
G01X1638500Y87500D02*
X1641600D01*
G01X1633874Y91245D02*
X1637619Y87500D01*
G01X1633874Y98661D02*
Y91245D01*
G01X1637619Y87500D02*
X1638500D01*
G01X1646000Y84800D02*
X1648700Y82100D01*
G01X1646000Y87500D02*
Y84800D01*
G01X1641600Y87500D02*
X1646000D01*
G01X1615115Y69027D02*
Y70786D01*
G01X1616429Y67713D02*
X1615115Y69027D01*
G01X1622495Y67713D02*
X1616429D01*
G01X1626040Y64168D02*
X1622495Y67713D01*
G01X1626040Y60461D02*
Y64168D01*
G01X1640880Y45621D02*
X1626040Y60461D01*
G01X1648900Y45621D02*
X1640880D01*
G01X1640000Y53207D02*
Y60000D01*
G01X1643522Y49685D02*
X1640000Y53207D01*
G01X1651042Y49685D02*
X1643522D01*
G01X1630000Y91689D02*
Y95851D01*
G01X1632789Y88900D02*
X1630000Y91689D01*
G01X1632789Y85081D02*
Y88900D01*
G01X1634200Y83670D02*
X1632789Y85081D01*
G01X1634200Y78700D02*
Y83670D01*
G01X1630263Y74763D02*
X1634200Y78700D01*
G01X1630263Y72702D02*
Y74763D01*
G01X1631194Y71771D02*
X1630263Y72702D01*
G01X1640529Y71771D02*
X1631194D01*
G01X1642662Y69638D02*
X1640529Y71771D01*
G01X1642662Y62662D02*
Y69638D01*
G01X1640000Y60000D02*
X1642662Y62662D01*
G01X1589268Y44357D02*
Y62283D01*
G01X1594338Y39287D02*
X1589268Y44357D01*
G01X1594338Y37245D02*
Y39287D01*
G01X1590582Y33489D02*
X1594338Y37245D01*
G01X1622400Y69600D02*
X1621100D01*
G01X1623000Y69000D02*
X1622400Y69600D01*
G01X1624750Y69000D02*
X1623000D01*
G01X1628250D02*
Y72000D01*
G01X1640900Y68801D02*
Y66900D01*
G01X1639627Y70074D02*
X1640900Y68801D01*
G01X1631166Y70074D02*
X1639627D01*
G01X1630092Y69000D02*
X1631166Y70074D01*
G01X1628250Y69000D02*
X1630092D01*
G01X1603900Y43450D02*
Y41300D01*
G01X1595937Y51413D02*
X1603900Y43450D01*
G01X1595937Y66135D02*
Y51413D01*
G01X1592715Y69357D02*
X1595937Y66135D01*
G01X1592715Y70817D02*
Y69357D01*
G01X1613550Y37849D02*
Y34700D01*
G01X1610749Y40650D02*
X1613550Y37849D01*
G01X1604550Y40650D02*
X1610749D01*
G01X1603900Y41300D02*
X1604550Y40650D01*
G01X1646000Y100214D02*
Y97500D01*
G01X1646200Y100414D02*
X1646000Y100214D01*
G01X1646200Y103800D02*
Y100414D01*
G01X1638500Y102500D02*
X1641600D01*
G01X1638500Y105142D02*
Y102500D01*
G01X1635718Y107924D02*
X1638500Y105142D01*
G01X1635718Y108782D02*
Y107924D01*
G01X1633731Y110769D02*
X1635718Y108782D01*
G01X1631061Y110769D02*
X1633731D01*
G01X1629489Y112341D02*
X1631061Y110769D01*
G01X1645612Y104388D02*
X1646200Y103800D01*
G01X1644488Y104388D02*
X1645612D01*
G01X1642600Y102500D02*
X1644488Y104388D01*
G01X1641600Y102500D02*
X1642600D01*
G01X1616186Y128089D02*
X1616891D01*
G01X1614330Y129945D02*
X1616186Y128089D01*
G01X1613101Y129945D02*
X1614330D01*
G01X1612192Y129036D02*
X1613101Y129945D01*
G01X1612192Y127289D02*
Y129036D01*
G01X1611354Y126451D02*
X1612192Y127289D01*
G01X1609774Y126451D02*
X1611354D01*
G01X1608953Y127272D02*
X1609774Y126451D01*
G01X1608953Y139022D02*
Y127272D01*
G01X1606099Y141876D02*
X1608953Y139022D01*
G01X1603066Y141876D02*
X1606099D01*
G01X1601116Y139926D02*
X1603066Y141876D01*
G01X1594718Y139926D02*
X1601116D01*
G01X1594173Y140471D02*
X1594718Y139926D01*
G01X1592510Y140471D02*
X1594173D01*
G01X1591430D02*
X1592510D01*
G01X1589901Y142000D02*
X1591430Y140471D01*
G01X1589283Y134254D02*
X1589880Y134851D01*
G01X1602850Y132088D02*
X1604939D01*
G01X1601526Y133412D02*
X1602850Y132088D01*
G01X1595712Y133412D02*
X1601526D01*
G01X1594600Y132300D02*
X1595712Y133412D01*
G01X1594600Y131600D02*
Y132300D01*
G01X1593131Y131600D02*
X1594600D01*
G01X1589880Y134851D02*
X1593131Y131600D01*
G01X1602129Y146096D02*
X1603804D01*
G01X1601261Y146964D02*
X1602129Y146096D01*
G01X1599345Y146964D02*
X1601261D01*
G01X1598252Y145871D02*
X1599345Y146964D01*
G01X1596865Y145871D02*
X1598252D01*
G01X1604412Y146096D02*
X1603804D01*
G01X1606775Y148459D02*
X1604412Y146096D01*
G01X1608241Y148459D02*
X1606775D01*
G01X1608913Y147787D02*
X1608241Y148459D01*
G01X1608913Y146387D02*
Y147787D01*
G01X1609909Y145391D02*
X1608913Y146387D01*
G01X1612187Y145391D02*
X1609909D01*
G01X1613878Y143700D02*
X1612187Y145391D01*
G01X1616720Y143700D02*
X1613878D01*
G01X1616900Y143880D02*
X1616720Y143700D01*
G01X1628788Y97800D02*
X1629075Y97513D01*
G01X1628788Y100388D02*
Y97800D01*
G01X1630300Y101900D02*
X1628788Y100388D01*
G01X1604000Y126539D02*
Y124750D01*
G01X1601939Y128600D02*
X1604000Y126539D01*
G01X1607252Y124750D02*
X1607441Y124939D01*
G01X1604000Y124750D02*
X1607252D01*
G01X1609771Y112341D02*
X1610591D01*
G01X1607430Y110000D02*
X1609771Y112341D01*
G01X1606500Y110000D02*
X1607430D01*
G01X1592041Y149054D02*
X1590046D01*
G01X1594176Y146919D02*
X1592041Y149054D01*
G01X1594176Y144944D02*
Y146919D01*
G01X1595247Y143873D02*
X1594176Y144944D01*
G01X1605173Y143873D02*
X1595247D01*
G01X1606649Y145349D02*
X1605173Y143873D01*
G01X1608451Y145349D02*
X1606649D01*
G01X1610017Y143783D02*
X1608451Y145349D01*
G01X1610645Y143783D02*
X1610017D01*
G01X1592699Y145201D02*
X1591700Y146200D01*
G01X1592699Y144301D02*
Y145201D01*
G01X1594738Y142262D02*
X1592699Y144301D01*
G01X1600148Y142262D02*
X1594738D01*
G01X1591700Y146200D02*
X1590224Y147676D01*
G01X1610591Y130401D02*
Y128089D01*
G01X1612103Y131913D02*
X1610591Y130401D01*
G01X1612103Y131920D02*
Y131913D01*
G01Y138686D02*
Y131920D01*
G01X1611613Y139176D02*
X1612103Y138686D01*
G01X1609965Y139176D02*
X1611613D01*
G01X1606441Y142700D02*
X1609965Y139176D01*
G01X1602724Y142700D02*
X1606441D01*
G01X1600774Y140750D02*
X1602724Y142700D01*
G01X1595060Y140750D02*
X1600774D01*
G01X1592144Y143666D02*
X1595060Y140750D01*
G01X1613741Y127280D02*
Y128089D01*
G01X1612144Y125683D02*
X1613741Y127280D01*
G01X1612144Y124147D02*
Y125683D01*
G01X1611386Y123389D02*
X1612144Y124147D01*
G01X1609931Y123389D02*
X1611386D01*
G01X1609058Y124262D02*
X1609931Y123389D01*
G01X1609058Y125500D02*
Y124262D01*
G01X1605970Y128588D02*
X1609058Y125500D01*
G01X1604939Y128588D02*
X1605970D01*
G01X1650519Y152988D02*
G02X1652312Y154064I896J538D01*
G01X1652829Y149137D02*
X1650519Y152988D01*
G01X1649109Y109191D02*
X1648387D01*
G01X1652149Y106151D02*
X1649109Y109191D01*
G01X1615328Y151700D02*
X1616891Y150137D01*
G01X1609700Y151700D02*
X1615328D01*
G01X1609052Y152348D02*
X1609700Y151700D01*
G01X1609052Y153948D02*
Y152348D01*
G01X1608149Y154851D02*
X1609052Y153948D01*
G01X1606732Y154851D02*
X1608149D01*
G01X1605804Y155779D02*
X1606732Y154851D01*
G01X1605804Y157062D02*
Y155779D01*
G01X1635384Y105507D02*
X1636008Y104883D01*
G01X1633218Y107673D02*
X1635384Y105507D01*
G01X1631094Y107673D02*
X1633218D01*
G01X1639440Y106227D02*
X1640732D01*
G01X1633326Y112341D02*
X1639440Y106227D01*
G01X1632638Y112341D02*
X1633326D01*
G01X1648782Y106227D02*
X1640732D01*
G01X1651009Y104000D02*
X1648782Y106227D01*
G01X1649000Y107600D02*
X1651575Y105025D01*
G01X1642869Y107600D02*
X1649000D01*
G01X1639711Y110758D02*
X1642869Y107600D01*
G01X1636758Y110758D02*
X1639711D01*
G01X1632638Y114878D02*
X1636758Y110758D01*
G01X1632638Y115491D02*
Y114878D01*
G01X1596676Y153876D02*
X1593500Y157052D01*
G01X1597221Y153876D02*
X1596676D01*
G01X1597222Y153875D02*
X1597221Y153876D01*
G01X1602997Y153875D02*
X1597222D01*
G01X1607559Y149313D02*
X1602997Y153875D01*
G01X1608109Y149313D02*
X1607559D01*
G01X1608110Y149312D02*
X1608109Y149313D01*
G01X1609278Y149312D02*
X1608110D01*
G01X1609965Y148625D02*
X1609278Y149312D01*
G01X1610175Y148625D02*
X1609965D01*
G01X1610591Y148209D02*
X1610175Y148625D01*
G01X1610591Y146987D02*
Y148209D01*
G01X1597364Y154700D02*
X1594800Y157264D01*
G01X1603741Y154700D02*
X1597364D01*
G01X1608304Y150137D02*
X1603741Y154700D01*
G01X1610591Y150137D02*
X1608304D01*
G01X1605378Y120278D02*
X1604400Y119300D01*
G01X1612229Y120278D02*
X1605378D01*
G01X1613741Y121790D02*
X1612229Y120278D01*
G01X1602737Y119300D02*
X1604400D01*
G01X1602337Y118900D02*
X1602737Y119300D01*
G01X1598477Y118900D02*
X1602337D01*
G01X1597000D02*
X1598477D01*
G01X1596600Y118500D02*
X1597000Y118900D01*
G01X1595250Y118500D02*
X1596600D01*
G01X1632215Y100320D02*
X1633874Y98661D01*
G01X1632215Y103316D02*
Y100320D01*
G01X1629400Y106131D02*
X1632215Y103316D01*
G01X1630000Y95851D02*
X1632020Y97871D01*
G01X1596865Y150303D02*
X1595390Y151778D01*
G01X1596865Y149371D02*
Y150303D01*
G01X1609579Y121790D02*
X1610591D01*
G01X1608067Y123302D02*
X1609579Y121790D01*
G01X1606815Y123302D02*
X1608067D01*
G01X1605913Y122400D02*
X1606815Y123302D01*
G01X1597600Y122400D02*
X1605913D01*
G01X1596700Y121500D02*
X1597600Y122400D01*
G01X1595300Y121500D02*
X1596700D01*
G01X1649950Y161171D02*
X1651536Y159585D01*
G01X1649950Y163350D02*
Y161171D01*
G01X1650900Y164300D02*
X1649950Y163350D01*
G01X1625000Y175645D02*
Y177808D01*
G01X1624064Y174709D02*
X1625000Y175645D01*
G01X1638938Y167580D02*
Y165884D01*
G01X1641375Y170017D02*
X1638938Y167580D01*
G01X1641375Y174514D02*
Y170017D01*
G01X1642649Y175788D02*
X1641375Y174514D01*
G01X1615553Y182117D02*
Y184908D01*
G01X1612000Y178564D02*
X1615553Y182117D01*
G01X1612000Y177200D02*
Y178564D01*
G01X1613250Y175950D02*
X1612000Y177200D01*
G01X1613925Y175950D02*
X1613250D01*
G01X1615562Y174313D02*
X1613925Y175950D01*
G01X1616527Y174313D02*
X1615562D01*
G01X1617679Y173161D02*
X1616527Y174313D01*
G01X1617679Y171979D02*
Y173161D01*
G01X1616700Y171000D02*
X1617679Y171979D01*
G01X1615734Y171000D02*
X1616700D01*
G01X1614406Y169672D02*
X1615734Y171000D01*
G01X1613002Y169672D02*
X1614406D01*
G01X1613002Y167186D02*
Y169672D01*
G01X1613741Y166447D02*
X1613002Y167186D01*
G01X1613741Y165885D02*
Y166447D01*
G01X1616500Y185855D02*
Y188500D01*
G01X1615553Y184908D02*
X1616500Y185855D01*
G01X1627684Y167689D02*
X1629489Y165884D01*
G01X1625561Y167689D02*
X1627684D01*
G01X1623750Y169500D02*
X1625561Y167689D01*
G01X1610500Y184931D02*
X1610554Y184877D01*
G01X1610500Y188500D02*
Y184931D01*
G01X1595800Y189960D02*
X1596730Y189030D01*
G01X1595800Y193191D02*
Y189960D01*
G01X1597809Y195200D02*
X1595800Y193191D01*
G01X1601400Y195200D02*
X1597809D01*
G01X1608100Y188500D02*
X1601400Y195200D01*
G01X1610500Y188500D02*
X1608100D01*
G01X1610591Y163173D02*
Y162735D01*
G01X1603493Y170271D02*
X1610591Y163173D01*
G01X1603493Y178385D02*
Y170271D01*
G01X1604031Y178923D02*
X1603493Y178385D01*
G01X1604031Y181729D02*
Y178923D01*
G01X1596730Y189030D02*
X1604031Y181729D01*
G01X1620040Y160532D02*
Y159585D01*
G01X1621649Y162141D02*
X1620040Y160532D01*
G01X1621649Y163378D02*
Y162141D01*
G01X1620689Y164338D02*
X1621649Y163378D01*
G01X1619382Y164338D02*
X1620689D01*
G01X1618428Y165292D02*
X1619382Y164338D01*
G01X1618428Y166631D02*
Y165292D01*
G01X1617078Y167981D02*
X1618428Y166631D01*
G01X1617078Y169100D02*
Y167981D01*
G01Y169264D02*
Y169100D01*
G01X1619724Y171910D02*
X1617078Y169264D01*
G01X1619724Y173623D02*
Y171910D01*
G01X1620663Y174562D02*
X1619724Y173623D01*
G01X1620663Y182314D02*
Y174562D01*
G01X1619672Y183305D02*
X1620663Y182314D01*
G01X1618275Y183305D02*
X1619672D01*
G01X1617600Y183980D02*
X1618275Y183305D01*
G01X1617600Y186030D02*
Y183980D01*
G01X1619846Y188276D02*
X1617600Y186030D01*
G01X1604275Y168159D02*
Y164859D01*
G01X1602977Y169457D02*
X1604275Y168159D01*
G01X1602977Y169486D02*
Y169457D01*
G01X1602668Y169795D02*
X1602977Y169486D01*
G01X1602668Y173391D02*
Y169795D01*
G01X1600563Y175496D02*
X1602668Y173391D01*
G01X1600563Y181417D02*
Y175496D01*
G01X1595181Y186799D02*
X1600563Y181417D01*
G01X1592267Y186799D02*
X1595181D01*
G01X1590058Y189008D02*
X1592267Y186799D01*
G01X1590058Y192538D02*
Y189008D01*
G01X1595700Y198180D02*
X1590058Y192538D01*
G01X1602080Y198180D02*
X1595700D01*
G01X1610098Y206198D02*
X1602080Y198180D01*
G01X1610098Y215332D02*
Y206198D01*
G01X1611016Y216250D02*
X1610098Y215332D01*
G01X1611761Y216250D02*
X1611016D01*
G01X1616134Y162735D02*
X1616890D01*
G01X1614499Y161100D02*
X1616134Y162735D01*
G01X1609800Y161100D02*
X1614499D01*
G01X1609000Y161900D02*
X1609800Y161100D01*
G01X1609000Y163500D02*
Y161900D01*
G01X1607925Y164575D02*
X1609000Y163500D01*
G01X1604559Y164575D02*
X1607925D01*
G01X1604275Y164859D02*
X1604559Y164575D01*
G01X1630836Y201621D02*
Y197560D01*
G01X1632123Y202908D02*
X1630836Y201621D01*
G01X1657033Y202908D02*
X1632123D01*
G01X1626451Y182759D02*
X1625000Y181308D01*
G01X1627326Y182759D02*
X1626451D01*
G01X1590525Y220121D02*
Y217033D01*
G01X1599669Y192421D02*
X1598006D01*
G01X1605219Y186871D02*
X1599669Y192421D01*
G01X1605219Y178532D02*
Y186871D01*
G01X1604625Y177938D02*
X1605219Y178532D01*
G01X1604625Y170352D02*
Y177938D01*
G01X1607877Y167100D02*
X1604625Y170352D01*
G01X1609670Y167100D02*
X1607877D01*
G01X1609967Y167397D02*
X1609670Y167100D01*
G01X1611303Y167397D02*
X1609967D01*
G01X1612200Y166500D02*
X1611303Y167397D01*
G01X1612200Y164798D02*
Y166500D01*
G01X1612625Y164373D02*
X1612200Y164798D01*
G01X1613113Y164373D02*
X1612625D01*
G01X1613114Y164372D02*
X1613113Y164373D01*
G01X1614368Y164372D02*
X1613114D01*
G01X1614369Y164373D02*
X1614368Y164372D01*
G01X1616263Y164373D02*
X1614369D01*
G01X1616264Y164372D02*
X1616263Y164373D01*
G01X1617499Y164372D02*
X1616264D01*
G01X1618492Y163379D02*
X1617499Y164372D01*
G01X1618492Y162197D02*
Y163379D01*
G01X1617517Y161222D02*
X1618492Y162197D01*
G01X1617515Y161222D02*
X1617517D01*
G01X1617493Y161200D02*
X1617515Y161222D01*
G01X1616000Y161200D02*
X1617493D01*
G01X1614385Y159585D02*
X1616000Y161200D01*
G01X1613741Y159585D02*
X1614385D01*
G01X1615480Y179280D02*
X1614000Y177800D01*
G01X1618940Y179280D02*
X1615480D01*
G01X1644438Y223101D02*
X1655615Y211924D01*
G01X1635800Y198448D02*
X1633994Y200254D01*
G01X1637870Y195077D02*
X1635800Y197147D01*
G01D02*
Y198448D01*
G01X1603222Y159585D02*
X1607442D01*
G01X1599438Y163369D02*
X1603222Y159585D01*
G01X1599438Y164962D02*
Y163369D01*
G01X1595400Y169000D02*
X1599438Y164962D01*
G01X1589700Y169000D02*
X1595400D01*
G01X1613500Y185396D02*
X1613053Y184949D01*
G01X1613500Y188500D02*
Y185396D01*
G01X1611000Y173400D02*
X1611500Y172900D01*
G01X1611000Y182896D02*
Y173400D01*
G01X1613053Y184949D02*
X1611000Y182896D01*
G01X1625149Y201452D02*
X1619958Y206643D01*
G01X1625149Y186853D02*
Y201452D01*
G01X1623872Y185576D02*
X1625149Y186853D01*
G01X1623872Y184048D02*
Y185576D01*
G01X1622217Y182393D02*
X1623872Y184048D01*
G01X1622217Y177809D02*
Y182393D01*
G01X1615362Y211239D02*
Y213507D01*
G01X1619958Y206643D02*
X1615362Y211239D01*
G01X1604568Y158298D02*
X1605804Y157062D01*
G01X1602902Y158298D02*
X1604568D01*
G01X1601100Y160100D02*
X1602902Y158298D01*
G01X1599334Y160100D02*
X1601100D01*
G01X1597302Y162132D02*
X1599334Y160100D01*
G01X1595194Y164240D02*
X1597302Y162132D01*
G01X1594830Y164240D02*
X1595194D01*
G01X1592448Y166622D02*
X1594830Y164240D01*
G01X1590637Y175137D02*
X1595800Y180300D01*
G01X1588847Y175137D02*
X1590637D01*
G01X1593218Y192950D02*
Y191776D01*
G01X1596943Y196675D02*
X1593218Y192950D01*
G01X1602346Y196675D02*
X1596943D01*
G01X1603337Y197666D02*
X1602346Y196675D01*
G01X1603337Y197689D02*
Y197666D01*
G01X1605648Y200000D02*
X1603337Y197689D01*
G01X1617166Y200000D02*
X1605648D01*
G01X1618373Y198793D02*
X1617166Y200000D01*
G01X1618373Y195187D02*
Y198793D01*
G01X1619781Y193779D02*
X1618373Y195187D01*
G01X1619781Y191683D02*
Y193779D01*
G01X1634170Y171535D02*
Y168900D01*
G01X1636649Y174014D02*
X1634170Y171535D01*
G01X1636649Y175788D02*
Y174014D01*
G01X1638309Y159585D02*
X1638938D01*
G01X1636700Y161194D02*
X1638309Y159585D01*
G01X1634993Y161194D02*
X1636700D01*
G01X1634170Y162017D02*
X1634993Y161194D01*
G01X1634170Y168900D02*
Y162017D01*
G01X1624702Y161098D02*
X1626339Y162735D01*
G01X1622564Y161098D02*
X1624702D01*
G01X1621637Y160171D02*
X1622564Y161098D01*
G01X1621637Y159044D02*
Y160171D01*
G01X1620666Y158073D02*
X1621637Y159044D01*
G01X1609965Y158073D02*
X1620666D01*
G01X1609012Y159026D02*
X1609965Y158073D01*
G01X1609012Y160153D02*
Y159026D01*
G01X1607974Y161191D02*
X1609012Y160153D01*
G01X1605238Y161191D02*
X1607974D01*
G01X1602146Y164283D02*
X1605238Y161191D01*
G01X1602146Y168044D02*
Y164283D01*
G01X1600223Y169967D02*
X1602146Y168044D01*
G01X1593373Y169967D02*
X1600223D01*
G01X1591551Y171789D02*
X1593373Y169967D01*
G01X1629419Y217725D02*
X1629595D01*
G01X1626074Y214380D02*
X1629419Y217725D01*
G01X1626074Y186925D02*
Y214380D01*
G01X1629003Y183996D02*
X1626074Y186925D01*
G01X1629003Y181996D02*
Y183996D01*
G01X1626910Y179903D02*
X1629003Y181996D01*
G01X1626910Y176465D02*
Y179903D01*
G01X1626479Y176034D02*
X1626910Y176465D01*
G01X1626479Y172309D02*
Y176034D01*
G01X1625593Y171423D02*
X1626479Y172309D01*
G01X1622523Y171423D02*
X1625593D01*
G01X1622037Y170937D02*
X1622523Y171423D01*
G01X1622037Y168360D02*
Y170937D01*
G01X1622897Y167500D02*
X1622037Y168360D01*
G01X1623714Y167500D02*
X1622897D01*
G01X1624789Y166425D02*
X1623714Y167500D01*
G01X1624789Y166423D02*
Y166425D01*
G01X1624826Y166386D02*
X1624789Y166423D01*
G01X1624826Y165257D02*
Y166386D01*
G01X1624830Y165253D02*
X1624826Y165257D01*
G01X1624830Y164244D02*
Y165253D01*
G01X1626339Y162735D02*
X1624830Y164244D01*
G01X1593500Y159105D02*
X1592767Y159838D01*
G01X1593500Y157052D02*
Y159105D01*
G01X1591770Y162838D02*
X1588799D01*
G01X1594800Y159808D02*
X1591770Y162838D01*
G01X1594800Y157264D02*
Y159808D01*
G01X1650076Y192600D02*
X1652120Y194644D01*
G01X1648450Y192600D02*
X1650076D01*
G01X1594225Y212000D02*
X1596082D01*
G01X1593020Y213205D02*
X1594225Y212000D01*
G01X1593020Y215129D02*
Y213205D01*
G01X1617021Y175780D02*
X1618940D01*
G01X1616286Y176515D02*
X1617021Y175780D01*
G01X1644055Y222175D02*
X1655231Y210999D01*
G01X1606538Y178626D02*
Y173091D01*
G01X1608731Y180819D02*
X1606538Y178626D01*
G01X1593837Y200550D02*
X1591606Y198319D01*
G01X1596240Y200550D02*
X1593837D01*
G01X1591606Y198319D02*
Y196057D01*
G01X1644433Y184733D02*
Y185415D01*
G01X1639649Y179949D02*
X1644433Y184733D01*
G01X1639649Y179288D02*
Y179949D01*
G01X1654778Y210074D02*
X1643602Y221250D01*
G01X1605358Y204358D02*
X1604326Y203326D01*
G01X1606388Y204358D02*
X1605358D01*
G01X1609130Y207100D02*
X1606388Y204358D01*
G01X1609130Y216740D02*
Y207100D01*
G01X1610993Y218603D02*
X1609130Y216740D01*
G01X1616987Y215003D02*
X1613387Y218603D01*
G01X1624163Y215003D02*
X1616987D01*
G01X1626935Y217775D02*
X1624163Y215003D01*
G01X1601550Y200550D02*
X1599740D01*
G01X1604326Y203326D02*
X1601550Y200550D01*
G01X1644950Y187850D02*
Y189600D01*
G01X1646100Y186700D02*
X1644950Y187850D01*
G01X1646100Y184099D02*
Y186700D01*
G01X1645606Y183605D02*
X1646100Y184099D01*
G01X1645606Y172407D02*
Y183605D01*
G01X1643288Y170089D02*
X1645606Y172407D01*
G01X1643288Y169225D02*
Y170089D01*
G01X1642439Y168376D02*
X1643288Y169225D01*
G01X1642439Y168374D02*
Y168376D01*
G01X1641731Y167666D02*
X1642439Y168374D01*
G01X1641114Y167666D02*
X1641731D01*
G01X1640500Y167052D02*
X1641114Y167666D01*
G01X1640500Y161967D02*
Y167052D01*
G01X1639715Y161182D02*
X1640500Y161967D01*
G01X1638118Y161182D02*
X1639715D01*
G01X1637421Y161879D02*
X1638118Y161182D01*
G01X1637421Y163428D02*
Y161879D01*
G01X1635788Y165061D02*
X1637421Y163428D01*
G01X1635788Y165885D02*
Y165061D01*
G01X1640910Y192600D02*
X1644950D01*
G01D02*
Y189600D01*
G01X1646600Y170397D02*
X1645395Y169192D01*
G01X1646600Y183149D02*
Y170397D01*
G01X1647624Y184173D02*
X1646600Y183149D01*
G01X1651619Y184173D02*
X1647624D01*
G01X1645395Y169192D02*
X1642088Y165885D01*
G01X1648326Y163126D02*
Y162674D01*
G01X1649898Y164698D02*
X1648326Y163126D01*
G01X1649898Y168121D02*
Y164698D01*
G01X1651064Y169287D02*
X1649898Y168121D01*
G01X1648349Y175788D02*
X1651064Y173073D01*
G01X1637396Y171243D02*
X1637825Y171672D01*
G01X1637396Y164804D02*
Y171243D01*
G01X1638938Y163262D02*
X1637396Y164804D01*
G01X1638938Y162735D02*
Y163262D01*
G01X1639649Y173496D02*
Y175788D01*
G01X1637825Y171672D02*
X1639649Y173496D01*
G01X1623281Y189871D02*
Y191683D01*
G01X1623346Y189806D02*
X1623281Y189871D01*
G01X1623346Y188276D02*
Y189806D01*
G01X1611770Y213507D02*
X1611761D01*
G01X1611770Y211331D02*
Y213507D01*
G01X1623281Y199820D02*
X1611770Y211331D01*
G01X1623281Y191683D02*
Y199820D01*
G01X1649092Y204608D02*
X1657738D01*
G01X1634112Y219588D02*
X1649092Y204608D01*
G01X1623299Y216703D02*
X1626184Y219588D01*
G01X1617797Y216703D02*
X1623299D01*
G01X1614197Y220303D02*
X1617797Y216703D01*
G01X1607430Y217445D02*
X1610288Y220303D01*
G01X1607430Y210330D02*
Y217445D01*
G01X1602580Y205480D02*
X1607430Y210330D01*
G01X1599580Y205480D02*
X1602580D01*
G01X1598641Y206419D02*
X1599580Y205480D01*
G01X1598641Y212000D02*
Y206419D01*
G01X1636649Y181949D02*
Y179288D01*
G01X1637500Y182800D02*
X1636649Y181949D01*
G01X1640200Y182800D02*
X1637500D01*
G01X1641800Y184400D02*
X1640200Y182800D01*
G01X1643750Y279500D02*
Y283050D01*
G01Y267900D02*
Y279500D01*
G01X1632963Y274851D02*
Y281685D01*
G01X1636914Y270900D02*
X1632963Y274851D01*
G01X1635541Y274815D02*
X1636684D01*
G01X1634388Y275968D02*
X1635541Y274815D01*
G01X1634388Y282276D02*
Y275968D01*
G01X1644822Y224026D02*
X1655999Y212849D01*
G01X1642401Y224026D02*
X1644822D01*
G01X1635199Y231228D02*
X1642401Y224026D01*
G01X1624859Y231228D02*
X1635199D01*
G01X1619734Y236353D02*
X1624859Y231228D01*
G01X1605208Y236353D02*
X1619734D01*
G01X1600785Y240776D02*
X1605208Y236353D01*
G01X1595281Y240776D02*
X1600785D01*
G01X1595245Y240740D02*
X1595281Y240776D01*
G01X1616782Y277500D02*
X1594500D01*
G01X1621522Y272760D02*
X1616782Y277500D01*
G01X1621784Y272760D02*
X1621522D01*
G01X1621784Y272584D02*
Y272760D01*
G01X1622758Y271610D02*
X1621784Y272584D01*
G01X1623689Y271610D02*
X1622758D01*
G01X1623769Y271530D02*
X1623689Y271610D01*
G01X1631793Y271530D02*
X1623769D01*
G01X1635466Y267857D02*
X1631793Y271530D01*
G01X1637734Y267857D02*
X1635466D01*
G01X1637735Y267856D02*
X1637734Y267857D01*
G01X1638645Y267856D02*
X1637735D01*
G01X1640317Y269528D02*
X1638645Y267856D01*
G01X1640317Y283830D02*
Y269528D01*
G01X1597201Y237340D02*
Y238188D01*
G01X1594744Y234883D02*
X1597201Y237340D01*
G01X1589103Y234883D02*
X1594744D01*
G01X1594690Y242201D02*
X1594654Y242165D01*
G01X1601376Y242201D02*
X1594690D01*
G01X1605797Y237780D02*
X1601376Y242201D01*
G01X1620323Y237780D02*
X1605797D01*
G01X1625450Y232653D02*
X1620323Y237780D01*
G01X1635790Y232653D02*
X1625450D01*
G01X1642706Y225737D02*
X1635790Y232653D01*
G01X1654458Y225737D02*
X1642706D01*
G01X1637844Y239938D02*
X1651376D01*
G01X1629347Y248435D02*
X1637844Y239938D01*
G01X1619852Y248435D02*
X1629347D01*
G01X1610052Y258235D02*
X1619852Y248435D01*
G01X1597265Y258235D02*
X1610052D01*
G01X1638112Y243750D02*
X1656982D01*
G01X1630229Y251633D02*
X1638112Y243750D01*
G01X1626426Y251633D02*
X1630229D01*
G01X1624150Y253909D02*
X1626426Y251633D01*
G01X1624150Y257420D02*
Y253909D01*
G01X1617355Y264215D02*
X1624150Y257420D01*
G01X1611427Y264215D02*
X1617355D01*
G01X1610290Y265352D02*
X1611427Y264215D01*
G01X1608670Y221090D02*
X1605760D01*
G01X1610250Y222670D02*
X1608670Y221090D01*
G01X1610550Y222670D02*
X1610250D01*
G01X1605760Y219830D02*
Y221090D01*
G01X1604930Y219000D02*
X1605760Y219830D01*
G01X1601200Y219000D02*
X1604930D01*
G01X1601200Y221386D02*
Y219000D01*
G01X1600724Y221862D02*
X1601200Y221386D01*
G01X1599076Y221862D02*
X1600724D01*
G01X1598641Y221427D02*
X1599076Y221862D01*
G01X1598641Y219000D02*
Y221427D01*
G01X1592870Y219871D02*
Y217900D01*
G01X1596561Y223562D02*
X1592870Y219871D01*
G01X1601470Y223562D02*
X1596561D01*
G01X1603942Y221090D02*
X1601470Y223562D01*
G01X1605760Y221090D02*
X1603942D01*
G01X1598204Y227800D02*
X1590525Y220121D01*
G01X1613095Y227800D02*
X1598204D01*
G01X1619166Y221729D02*
X1613095Y227800D01*
G01X1622524Y221729D02*
X1619166D01*
G01X1626045Y225250D02*
X1622524Y221729D01*
G01X1626124Y225250D02*
X1626045D01*
G01X1623447Y273773D02*
Y273273D01*
G01X1625264Y275590D02*
X1623447Y273773D01*
G01X1629289Y275590D02*
X1625264D01*
G01X1635922Y268957D02*
X1629289Y275590D01*
G01X1638190Y268957D02*
X1635922D01*
G01X1639217Y269984D02*
X1638190Y268957D01*
G01X1639217Y284286D02*
Y269984D01*
G01X1644681Y229012D02*
X1672216D01*
G01X1637733Y235960D02*
X1644681Y229012D01*
G01X1628191Y235960D02*
X1637733D01*
G01X1625179Y238972D02*
X1628191Y235960D01*
G01X1625179Y241556D02*
Y238972D01*
G01X1624798Y241937D02*
X1625179Y241556D01*
G01X1642017Y223101D02*
X1644438D01*
G01X1635367Y229751D02*
X1642017Y223101D01*
G01X1624320Y229751D02*
X1635367D01*
G01X1619143Y234928D02*
X1624320Y229751D01*
G01X1605088Y234928D02*
X1619143D01*
G01X1600165Y239851D02*
X1605088Y234928D01*
G01X1595665Y239851D02*
X1600165D01*
G01X1595629Y239815D02*
X1595665Y239851D01*
G01X1594099Y243626D02*
X1594063Y243590D01*
G01X1601967Y243626D02*
X1594099D01*
G01X1603741Y245400D02*
X1601967Y243626D01*
G01X1614719Y245400D02*
X1603741D01*
G01X1626041Y234078D02*
X1614719Y245400D01*
G01X1633790Y234078D02*
X1626041D01*
G01X1633791Y234079D02*
X1633790Y234078D01*
G01X1636380Y234079D02*
X1633791D01*
G01X1643297Y227162D02*
X1636380Y234079D01*
G01X1664338Y227162D02*
X1643297D01*
G01X1590544Y251520D02*
X1589592Y252472D01*
G01X1592656Y251520D02*
X1590544D01*
G01X1595486Y254350D02*
X1592656Y251520D01*
G01X1603739Y254350D02*
X1595486D01*
G01X1605064Y255675D02*
X1603739Y254350D01*
G01X1605751Y255675D02*
X1605064D01*
G01X1605752Y255676D02*
X1605751Y255675D01*
G01X1607202Y255676D02*
X1605752D01*
G01X1607203Y255675D02*
X1607202Y255676D01*
G01X1609653Y255675D02*
X1607203D01*
G01X1609654Y255676D02*
X1609653Y255675D01*
G01X1611104Y255676D02*
X1609654D01*
G01X1611105Y255675D02*
X1611104Y255676D01*
G01X1611149Y255675D02*
X1611105D01*
G01X1619214Y247610D02*
X1611149Y255675D01*
G01X1629005Y247610D02*
X1619214D01*
G01X1637502Y239113D02*
X1629005Y247610D01*
G01X1646787Y239113D02*
X1637502D01*
G01X1649621Y236279D02*
X1646787Y239113D01*
G01X1649621Y236279D02*
X1651672Y234228D01*
G01X1615444Y269910D02*
X1612326Y273028D01*
G01X1620369Y269910D02*
X1615444D01*
G01X1621606Y268760D02*
X1620369Y269910D01*
G01X1622191Y268760D02*
X1621606D01*
G01X1622191Y268680D02*
Y268760D01*
G01X1630611Y268680D02*
X1622191D01*
G01X1632745Y266546D02*
X1630611Y268680D01*
G01X1632745Y261013D02*
Y266546D01*
G01X1635827Y257931D02*
X1632745Y261013D01*
G01X1639529Y257931D02*
X1635827D01*
G01X1643658Y253802D02*
X1639529Y257931D01*
G01X1659396Y253802D02*
X1643658D01*
G01X1627029Y226913D02*
X1628624Y225318D01*
G01X1622586Y226913D02*
X1627029D01*
G01X1620445Y229054D02*
X1622586Y226913D01*
G01X1589954Y229054D02*
X1620445D01*
G01X1596354Y263446D02*
X1589736Y270064D01*
G01X1602200Y263446D02*
X1596354D01*
G01X1602643Y263003D02*
X1602200Y263446D01*
G01X1602643Y261229D02*
Y263003D01*
G01X1602995Y260877D02*
X1602643Y261229D01*
G01X1605753Y260877D02*
X1602995D01*
G01X1607201Y262325D02*
X1605753Y260877D01*
G01X1607201Y266631D02*
Y262325D01*
G01X1609010Y268440D02*
X1607201Y266631D01*
G01X1612176Y268440D02*
X1609010D01*
G01X1613779Y266837D02*
X1612176Y268440D01*
G01X1626123Y266837D02*
X1613779D01*
G01X1626541Y267255D02*
X1626123Y266837D01*
G01X1630020Y267255D02*
X1626541D01*
G01X1631320Y265955D02*
X1630020Y267255D01*
G01X1631320Y260422D02*
Y265955D01*
G01X1635236Y256506D02*
X1631320Y260422D01*
G01X1638938Y256506D02*
X1635236D01*
G01X1643067Y252377D02*
X1638938Y256506D01*
G01X1659987Y252377D02*
X1643067D01*
G01X1643466Y237363D02*
X1650892Y229937D01*
G01X1636776Y237363D02*
X1643466D01*
G01X1628279Y245860D02*
X1636776Y237363D01*
G01X1618444Y245860D02*
X1628279D01*
G01X1610379Y253925D02*
X1618444Y245860D01*
G01X1606477Y253925D02*
X1610379D01*
G01X1605152Y252600D02*
X1606477Y253925D01*
G01X1596212Y252600D02*
X1605152D01*
G01X1592053Y248441D02*
X1596212Y252600D01*
G01X1616035Y271335D02*
X1612148Y275222D01*
G01X1620930Y271335D02*
X1616035D01*
G01X1620931Y271334D02*
X1620930Y271335D01*
G01X1622167Y270185D02*
X1620931Y271334D01*
G01X1623098Y270185D02*
X1622167D01*
G01X1623178Y270105D02*
X1623098Y270185D01*
G01X1631202Y270105D02*
X1623178D01*
G01X1634170Y267137D02*
X1631202Y270105D01*
G01X1634170Y264077D02*
Y267137D01*
G01X1635651Y262596D02*
X1634170Y264077D01*
G01X1639404Y262596D02*
X1635651D01*
G01X1646773Y255227D02*
X1639404Y262596D01*
G01X1658805Y255227D02*
X1646773D01*
G01X1647100Y263300D02*
Y282515D01*
G01X1644700Y260900D02*
X1647100Y263300D01*
G01X1641179Y264421D02*
X1644700Y260900D01*
G01X1637269Y264421D02*
X1641179D01*
G01X1595803Y245553D02*
X1596600Y246350D01*
G01X1593250Y245553D02*
X1595803D01*
G01X1638228Y240863D02*
X1657248D01*
G01X1629731Y249360D02*
X1638228Y240863D01*
G01X1620568Y249360D02*
X1629731D01*
G01X1618000Y251928D02*
X1620568Y249360D01*
G01X1618000Y254451D02*
Y251928D01*
G01X1618587Y255038D02*
X1618000Y254451D01*
G01X1618587Y255430D02*
Y255038D01*
G01X1620240Y257083D02*
X1618587Y255430D01*
G01X1620240Y257660D02*
Y257083D01*
G01X1641634Y222175D02*
X1644055D01*
G01X1634984Y228825D02*
X1641634Y222175D01*
G01X1623284Y228825D02*
X1634984D01*
G01X1619409Y232700D02*
X1623284Y228825D01*
G01X1595806Y232700D02*
X1619409D01*
G01X1595695Y232589D02*
X1595806Y232700D01*
G01X1604775Y266006D02*
X1600810D01*
G01X1605200Y265581D02*
X1604775Y266006D01*
G01X1605200Y263833D02*
Y265581D01*
G01X1596115Y231700D02*
X1596079Y231664D01*
G01X1619100Y231700D02*
X1596115D01*
G01X1622900Y227900D02*
X1619100Y231700D01*
G01X1634600Y227900D02*
X1622900D01*
G01X1641250Y221250D02*
X1634600Y227900D01*
G01X1643602Y221250D02*
X1641250D01*
G01X1613387Y218603D02*
X1610993D01*
G01X1620318Y254673D02*
X1620250Y254741D01*
G01X1620318Y251985D02*
Y254673D01*
G01X1621900Y250403D02*
X1620318Y251985D01*
G01X1630150Y250403D02*
X1621900D01*
G01X1637728Y242825D02*
X1630150Y250403D01*
G01X1656598Y242825D02*
X1637728D01*
G01X1629156Y255081D02*
X1638216Y246021D01*
G01X1626510Y255081D02*
X1629156D01*
G01X1625380Y256211D02*
X1626510Y255081D01*
G01X1625380Y257673D02*
Y256211D01*
G01X1617869Y265184D02*
X1625380Y257673D01*
G01X1613206Y265184D02*
X1617869D01*
G01X1611375Y267015D02*
X1613206Y265184D01*
G01X1609601Y267015D02*
X1611375D01*
G01X1608627Y266041D02*
X1609601Y267015D01*
G01X1608627Y261735D02*
Y266041D01*
G01X1606202Y259310D02*
X1608627Y261735D01*
G01X1598091Y259310D02*
X1606202D01*
G01X1591610Y271290D02*
X1597000Y265900D01*
G01X1598214D02*
X1597000D01*
G01X1600421Y268107D02*
X1598214Y265900D01*
G01X1604222Y268107D02*
X1600421D01*
G01X1644297Y228087D02*
X1672600D01*
G01X1637349Y235035D02*
X1644297Y228087D01*
G01X1627100Y235035D02*
X1637349D01*
G01X1614919Y247216D02*
X1627100Y235035D01*
G01X1606755Y247216D02*
X1614919D01*
G01X1605431Y248540D02*
X1606755Y247216D01*
G01X1593680Y248540D02*
X1605431D01*
G01X1592656Y247516D02*
X1593680Y248540D01*
G01X1615555Y279463D02*
X1630855Y294763D01*
G01X1591669Y249366D02*
X1588851D01*
G01X1595828Y253525D02*
X1591669Y249366D01*
G01X1604768Y253525D02*
X1595828D01*
G01X1606094Y254851D02*
X1604768Y253525D01*
G01X1606860Y254851D02*
X1606094D01*
G01X1606861Y254850D02*
X1606860Y254851D01*
G01X1609995Y254850D02*
X1606861D01*
G01X1609996Y254851D02*
X1609995Y254850D01*
G01X1610762Y254851D02*
X1609996D01*
G01X1618828Y246785D02*
X1610762Y254851D01*
G01X1628663Y246785D02*
X1618828D01*
G01X1637160Y238288D02*
X1628663Y246785D01*
G01X1644664Y238288D02*
X1637160D01*
G01X1651052Y231900D02*
X1644664Y238288D01*
G01X1626184Y219588D02*
X1634112D01*
G01X1610288Y220303D02*
X1614197D01*
G01X1592675Y305680D02*
X1589000D01*
G01X1593100Y306105D02*
X1592675Y305680D01*
G01X1593100Y307601D02*
Y306105D01*
G01X1591471Y309230D02*
X1593100Y307601D01*
G01X1591471Y311952D02*
Y309230D01*
G01X1644300Y283600D02*
Y288050D01*
G01X1643750Y283050D02*
X1644300Y283600D01*
G01X1641296Y289204D02*
Y296441D01*
G01X1642450Y288050D02*
X1641296Y289204D01*
G01X1644300Y288050D02*
X1642450D01*
G01X1600573Y333507D02*
X1602776Y331304D01*
G01X1641791Y328827D02*
X1658241Y345277D01*
G01X1641791Y324912D02*
Y328827D01*
G01X1641055Y324176D02*
X1641791Y324912D01*
G01X1639847Y322968D02*
X1641055Y324176D01*
G01X1638990Y322968D02*
X1639847D01*
G01X1634808Y318786D02*
X1638990Y322968D01*
G01X1634808Y317302D02*
Y318786D01*
G01X1632287Y314781D02*
X1634808Y317302D01*
G01X1632287Y282361D02*
Y314781D01*
G01X1632963Y281685D02*
X1632287Y282361D01*
G01X1633712Y282952D02*
X1634388Y282276D01*
G01X1633712Y314177D02*
Y282952D01*
G01X1637536Y318001D02*
X1633712Y314177D01*
G01X1638775Y318001D02*
X1637536D01*
G01X1639749Y318975D02*
X1638775Y318001D01*
G01X1639749Y319949D02*
Y318975D01*
G01X1643216Y323416D02*
X1639749Y319949D01*
G01X1643216Y328236D02*
Y323416D01*
G01X1652542Y337562D02*
X1643216Y328236D01*
G01X1651259Y329059D02*
X1648911Y326711D01*
G01X1649575Y311000D02*
X1650473Y311898D01*
G01X1646250Y311000D02*
X1649575D01*
G01X1648842Y319500D02*
X1650473D01*
G01X1647942Y320400D02*
X1648842Y319500D01*
G01X1647942Y325742D02*
Y320400D01*
G01X1648911Y326711D02*
X1647942Y325742D01*
G01X1640318Y283831D02*
X1640317Y283830D01*
G01X1640318Y290683D02*
Y283831D01*
G01X1638633Y292368D02*
X1640318Y290683D01*
G01X1638633Y298575D02*
Y292368D01*
G01X1639058Y299000D02*
X1638633Y298575D01*
G01X1641296Y299000D02*
X1639058D01*
G01X1643235Y308913D02*
X1639413Y312735D01*
G01X1650634Y308913D02*
X1643235D01*
G01X1618007Y336136D02*
X1619897D01*
G01X1614149Y332278D02*
X1618007Y336136D01*
G01X1604660Y332278D02*
X1614149D01*
G01X1602588Y334350D02*
X1604660Y332278D01*
G01X1604466Y329051D02*
X1603931Y328516D01*
G01X1620316Y329051D02*
X1604466D01*
G01X1629030Y337765D02*
X1620316Y329051D01*
G01X1630770Y337765D02*
X1629030D01*
G01X1634429Y341424D02*
X1630770Y337765D01*
G01X1593927Y320258D02*
X1589646D01*
G01X1599499Y325830D02*
X1593927Y320258D01*
G01X1603754Y325830D02*
X1599499D01*
G01X1605850Y327926D02*
X1603754Y325830D01*
G01X1620782Y327926D02*
X1605850D01*
G01X1627212Y334356D02*
X1620782Y327926D01*
G01X1633328Y334356D02*
X1627212D01*
G01X1637328Y338356D02*
X1633328Y334356D01*
G01X1637328Y352837D02*
Y338356D01*
G01X1638655Y284848D02*
X1639217Y284286D01*
G01X1636059Y284848D02*
X1638655D01*
G01X1635137Y285770D02*
X1636059Y284848D01*
G01X1635137Y312836D02*
Y285770D01*
G01X1636700Y314399D02*
X1635137Y312836D01*
G01X1642598Y314399D02*
X1636700D01*
G01X1645741Y317542D02*
X1642598Y314399D01*
G01X1645741Y327189D02*
Y317542D01*
G01X1653427Y334875D02*
X1645741Y327189D01*
G01X1650441Y301559D02*
X1651100Y300900D01*
G01X1648296Y301559D02*
X1650441D01*
G01X1613000Y337900D02*
X1618023Y342923D01*
G01X1591269Y313762D02*
X1589523D01*
G01X1594290Y316783D02*
X1591269Y313762D01*
G01X1595368Y316783D02*
X1594290D01*
G01X1600361Y321776D02*
X1595368Y316783D01*
G01X1605465Y321776D02*
X1600361D01*
G01X1607992Y324303D02*
X1605465Y321776D01*
G01X1628414Y324303D02*
X1607992D01*
G01X1631015Y326904D02*
X1628414Y324303D01*
G01X1631015Y328350D02*
Y326904D01*
G01X1635355Y323249D02*
Y324228D01*
G01X1631419Y319313D02*
X1635355Y323249D01*
G01X1629930Y317824D02*
X1631419Y319313D01*
G01X1629930Y295147D02*
Y317824D01*
G01X1620519Y285736D02*
X1629930Y295147D01*
G01X1590176Y331844D02*
X1588854D01*
G01X1604894Y336200D02*
X1605090Y336004D01*
G01X1619312Y341136D02*
X1619897D01*
G01X1612974Y334798D02*
X1619312Y341136D01*
G01X1606296Y334798D02*
X1612974D01*
G01X1605090Y336004D02*
X1606296Y334798D01*
G01X1620436Y340597D02*
X1619897Y341136D01*
G01X1623498Y340597D02*
X1620436D01*
G01X1626675Y343774D02*
X1623498Y340597D01*
G01X1594393Y319133D02*
X1589180D01*
G01X1599597Y324337D02*
X1594393Y319133D01*
G01X1604684Y324337D02*
X1599597D01*
G01X1607000Y326653D02*
X1604684Y324337D01*
G01X1621751Y326653D02*
X1607000D01*
G01X1627598Y332500D02*
X1621751Y326653D01*
G01X1635650Y332500D02*
X1627598D01*
G01X1649075Y345925D02*
X1635650Y332500D01*
G01X1646300Y287050D02*
X1647300Y288050D01*
G01X1646300Y283315D02*
Y287050D01*
G01X1647100Y282515D02*
X1646300Y283315D01*
G01X1647950Y288050D02*
X1652250Y283750D01*
G01X1647300Y288050D02*
X1647950D01*
G01X1600188Y322912D02*
X1594984Y317708D01*
G01X1605275Y322912D02*
X1600188D01*
G01X1607591Y325228D02*
X1605275Y322912D01*
G01X1627752Y325228D02*
X1607591D01*
G01X1629075Y326551D02*
X1627752Y325228D01*
G01X1629075Y328762D02*
Y326551D01*
G01X1631313Y331000D02*
X1629075Y328762D01*
G01X1636166Y331000D02*
X1631313D01*
G01X1650500Y345334D02*
X1636166Y331000D01*
G01X1593188Y303120D02*
X1589000D01*
G01X1594878Y304810D02*
X1593188Y303120D01*
G01X1594878Y314187D02*
Y304810D01*
G01X1600552Y319861D02*
X1594878Y314187D01*
G01X1625281Y319861D02*
X1600552D01*
G01X1635495Y330075D02*
X1625281Y319861D01*
G01X1636584Y330075D02*
X1635495D01*
G01X1654065Y347556D02*
X1636584Y330075D01*
G01X1636968Y329150D02*
X1654990Y347172D01*
G01X1635879Y329150D02*
X1636968D01*
G01X1625565Y318836D02*
X1635879Y329150D01*
G01X1600977Y318836D02*
X1625565D01*
G01X1595903Y313762D02*
X1600977Y318836D01*
G01X1595903Y303373D02*
Y313762D01*
G01X1593090Y300560D02*
X1595903Y303373D01*
G01X1589000Y300560D02*
X1593090D01*
G01X1639739Y328791D02*
X1656816Y345868D01*
G01X1639739Y325733D02*
Y328791D01*
G01X1633382Y319376D02*
X1639739Y325733D01*
G01X1633382Y317892D02*
Y319376D01*
G01X1630855Y315365D02*
X1633382Y317892D01*
G01X1630855Y294763D02*
Y315365D01*
G01X1644641Y321142D02*
X1642022Y318523D01*
G01X1644641Y327645D02*
Y321142D01*
G01X1653132Y336136D02*
X1644641Y327645D01*
G01X1639842Y316343D02*
X1639040D01*
G01X1642022Y318523D02*
X1639842Y316343D01*
G01X1604977Y331153D02*
X1603465Y329641D01*
G01X1616304Y331153D02*
X1604977D01*
G01X1619327Y334176D02*
X1616304Y331153D01*
G01X1622849Y334176D02*
X1619327D01*
G01X1626903Y338230D02*
X1622849Y334176D01*
G01X1626903Y339904D02*
Y338230D01*
G01X1632714Y345715D02*
X1626903Y339904D01*
G01X1619870Y338609D02*
X1619897Y338636D01*
G01X1618235Y338609D02*
X1619870D01*
G01X1613217Y333591D02*
X1618235Y338609D01*
G01X1604656Y333591D02*
X1613217D01*
G01X1602972Y335275D02*
X1604656Y333591D01*
G01X1620536Y337997D02*
X1619897Y338636D01*
G01X1622348Y337997D02*
X1620536D01*
G01X1627700Y343349D02*
X1622348Y337997D01*
G01X1626100Y375100D02*
Y373700D01*
G01X1624900Y376300D02*
X1626100Y375100D01*
G01X1624900Y377400D02*
Y376300D01*
G01X1618248Y368151D02*
X1620717D01*
G01X1617989Y367892D02*
X1618248Y368151D01*
G01X1617989Y365895D02*
Y367892D01*
G01X1618293Y365591D02*
X1617989Y365895D01*
G01X1620717Y365591D02*
X1618293D01*
G01X1623251Y368151D02*
X1620717D01*
G01X1623900Y368800D02*
X1623251Y368151D01*
G01X1623900Y372900D02*
Y368800D01*
G01X1624700Y373700D02*
X1623900Y372900D01*
G01X1626100Y373700D02*
X1624700D01*
G01X1626600Y355800D02*
Y356893D01*
G01X1625891Y355091D02*
X1626600Y355800D01*
G01X1620717Y355091D02*
X1625891D01*
G01X1618259D02*
X1620717D01*
G01X1617994Y355356D02*
X1618259Y355091D01*
G01X1617994Y357339D02*
Y355356D01*
G01X1618306Y357651D02*
X1617994Y357339D01*
G01X1620717Y357651D02*
X1618306D01*
G01X1626217Y359083D02*
Y360391D01*
G01X1626600Y358700D02*
X1626217Y359083D01*
G01X1626600Y356893D02*
Y358700D01*
G01X1632413Y402387D02*
X1631700Y403100D01*
G01X1632413Y388513D02*
Y402387D01*
G01X1629300Y385400D02*
X1632413Y388513D01*
G01X1594451Y378186D02*
X1594026Y377761D01*
G01X1594451Y382562D02*
Y378186D01*
G01X1595116Y383227D02*
X1594451Y382562D01*
G01X1615527Y383227D02*
X1595116D01*
G01X1624626Y392326D02*
X1615527Y383227D01*
G01X1624626Y410607D02*
Y392326D01*
G01X1639889Y370902D02*
X1640001Y370790D01*
G01X1639889Y400515D02*
Y370902D01*
G01X1647139Y407765D02*
X1639889Y400515D01*
G01X1610898Y349711D02*
X1613717D01*
G01X1610434Y350175D02*
X1610898Y349711D01*
G01X1607788Y350175D02*
X1610434D01*
G01X1607363Y349750D02*
X1607788Y350175D01*
G01X1607363Y345322D02*
Y349750D01*
G01X1608850Y343835D02*
X1607363Y345322D01*
G01X1630550Y401300D02*
X1628026Y403824D01*
G01X1634429Y344768D02*
Y341424D01*
G01X1633840Y345357D02*
X1634429Y344768D01*
G01X1633840Y346735D02*
Y345357D01*
G01X1636203Y349098D02*
X1633840Y346735D01*
G01X1636203Y353303D02*
Y349098D01*
G01X1639131Y356231D02*
X1636203Y353303D01*
G01X1642815Y356231D02*
X1639131D01*
G01X1643789Y357205D02*
X1642815Y356231D01*
G01X1643789Y368819D02*
Y357205D01*
G01X1641814Y370794D02*
X1643789Y368819D01*
G01X1641814Y399988D02*
Y370794D01*
G01X1648863Y407037D02*
X1641814Y399988D01*
G01X1639597Y355106D02*
X1637328Y352837D01*
G01X1643281Y355106D02*
X1639597D01*
G01X1644914Y356739D02*
X1643281Y355106D01*
G01X1644914Y369285D02*
Y356739D01*
G01X1642939Y371260D02*
X1644914Y369285D01*
G01X1642939Y399262D02*
Y371260D01*
G01X1649988Y406311D02*
X1642939Y399262D01*
G01X1597900Y348800D02*
X1599300Y350200D01*
G01X1610286Y347151D02*
X1613717D01*
G01X1609271Y348166D02*
X1610286Y347151D01*
G01X1614844D02*
X1613717D01*
G01X1616380Y348687D02*
X1614844Y347151D01*
G01X1616380Y350735D02*
Y348687D01*
G01X1615515Y351600D02*
X1616380Y350735D01*
G01X1600700Y351600D02*
X1615515D01*
G01X1599300Y350200D02*
X1600700Y351600D01*
G01X1588852Y369117D02*
X1591852D01*
G01X1588852D02*
Y370780D01*
G01X1626326Y400174D02*
Y407177D01*
G01X1630300Y396200D02*
X1626326Y400174D01*
G01X1630300Y395300D02*
Y396200D01*
G01X1624487Y352050D02*
X1626200D01*
G01X1623950Y351513D02*
X1624487Y352050D01*
G01X1623950Y347650D02*
Y351513D01*
G01X1623451Y347151D02*
X1623950Y347650D01*
G01X1620717Y347151D02*
X1623451D01*
G01X1618474D02*
X1620717D01*
G01X1618085Y346762D02*
X1618474Y347151D01*
G01X1618085Y344762D02*
Y346762D01*
G01X1618256Y344591D02*
X1618085Y344762D01*
G01X1620717Y344591D02*
X1618256D01*
G01X1620717Y343348D02*
Y344591D01*
G01X1620292Y342923D02*
X1620717Y343348D01*
G01X1618023Y342923D02*
X1620292D01*
G01X1597119Y360100D02*
X1593708Y356689D01*
G01X1603984Y360100D02*
X1597119D01*
G01X1606442Y362558D02*
X1603984Y360100D01*
G01X1609702Y362558D02*
X1606442D01*
G01X1610370Y361890D02*
X1609702Y362558D01*
G01X1611028Y362548D02*
X1610370Y361890D01*
G01X1611028Y367726D02*
Y362548D01*
G01X1611453Y368151D02*
X1611028Y367726D01*
G01X1613717Y368151D02*
X1611453D01*
G01X1588852Y366117D02*
X1591852D01*
G01X1626675Y347120D02*
Y343774D01*
G01X1628455Y348900D02*
X1626675Y347120D01*
G01X1630718Y348900D02*
X1628455D01*
G01X1632728Y350910D02*
X1630718Y348900D01*
G01X1632728Y354744D02*
Y350910D01*
G01X1634502Y356518D02*
X1632728Y354744D01*
G01X1634502Y373368D02*
Y356518D01*
G01X1635839Y374705D02*
X1634502Y373368D01*
G01X1635839Y402949D02*
Y374705D01*
G01X1643089Y410199D02*
X1635839Y402949D01*
G01X1594000Y353237D02*
X1595076D01*
G01X1593639Y352876D02*
X1594000Y353237D01*
G01X1615839Y357651D02*
X1613717D01*
G01X1616550Y356940D02*
X1615839Y357651D01*
G01X1616550Y353663D02*
Y356940D01*
G01X1616124Y353237D02*
X1616550Y353663D01*
G01X1595076Y353237D02*
X1616124D01*
G01X1610565Y357651D02*
X1613717D01*
G01X1610140Y358076D02*
X1610565Y357651D01*
G01X1610140Y358350D02*
Y358076D01*
G01X1649075Y353909D02*
Y345925D01*
G01X1647392Y355592D02*
X1649075Y353909D01*
G01X1647392Y370607D02*
Y355592D01*
G01X1645375Y372624D02*
X1647392Y370607D01*
G01X1645375Y399875D02*
Y372624D01*
G01X1651113Y405613D02*
X1645375Y399875D01*
G01X1608096Y360211D02*
X1607412Y360895D01*
G01X1613717Y360211D02*
X1608096D01*
G01X1648817Y356183D02*
X1650500Y354500D01*
G01X1648817Y371198D02*
Y356183D01*
G01X1646800Y373215D02*
X1648817Y371198D01*
G01X1646800Y398764D02*
Y373215D01*
G01X1647500Y399464D02*
X1646800Y398764D01*
G01X1647500Y399500D02*
Y399464D01*
G01X1652538Y404538D02*
X1647500Y399500D01*
G01X1648600Y376100D02*
X1649530Y375170D01*
G01X1648600Y399255D02*
Y376100D01*
G01X1653748Y404403D02*
X1648600Y399255D01*
G01X1649530Y371988D02*
X1654065Y367453D01*
G01X1649530Y375170D02*
Y371988D01*
G01X1594196Y361697D02*
X1592746Y360247D01*
G01X1603565Y361697D02*
X1594196D01*
G01X1605851Y363983D02*
X1603565Y361697D01*
G01X1607909Y363983D02*
X1605851D01*
G01X1609603Y365677D02*
X1607909Y363983D01*
G01X1609603Y368497D02*
Y365677D01*
G01X1611817Y370711D02*
X1609603Y368497D01*
G01X1613717Y370711D02*
X1611817D01*
G01X1632714Y347571D02*
Y345715D01*
G01X1635078Y349935D02*
X1632714Y347571D01*
G01X1635078Y353769D02*
Y349935D01*
G01X1636940Y355631D02*
X1635078Y353769D01*
G01X1636940Y372250D02*
Y355631D01*
G01X1638189Y373499D02*
X1636940Y372250D01*
G01X1638189Y401628D02*
Y373499D01*
G01X1645439Y408878D02*
X1638189Y401628D01*
G01X1627700Y346695D02*
Y343349D01*
G01X1628814Y347809D02*
X1627700Y346695D01*
G01X1630936Y347809D02*
X1628814D01*
G01X1633653Y350526D02*
X1630936Y347809D01*
G01X1633653Y354360D02*
Y350526D01*
G01X1635427Y356134D02*
X1633653Y354360D01*
G01X1635427Y372843D02*
Y356134D01*
G01X1636764Y374180D02*
X1635427Y372843D01*
G01X1636764Y402565D02*
Y374180D01*
G01X1644014Y409815D02*
X1636764Y402565D01*
G01X1642887Y348800D02*
X1640000D01*
G01X1642995Y348692D02*
X1642887Y348800D01*
G01X1643150Y348692D02*
X1642995D01*
G01X1591852Y372117D02*
X1590193Y373776D01*
G01X1628843Y412399D02*
X1630386Y413942D01*
G01X1628843Y411524D02*
Y412399D01*
G01X1632638Y427138D02*
Y466828D01*
G01X1638838Y420938D02*
X1632638Y427138D01*
G01X1638838Y413410D02*
Y420938D01*
G01X1632314Y406886D02*
X1638838Y413410D01*
G01X1630059Y406886D02*
X1632314D01*
G01X1629000Y405827D02*
X1630059Y406886D01*
G01X1629000Y404100D02*
Y405827D01*
G01X1630000Y403100D02*
X1629000Y404100D01*
G01X1631700Y403100D02*
X1630000D01*
G01X1632352Y418333D02*
X1624626Y410607D01*
G01X1632352Y420402D02*
Y418333D01*
G01X1624626Y428128D02*
X1632352Y420402D01*
G01X1624626Y451330D02*
Y428128D01*
G01X1626100Y452804D02*
X1624626Y451330D01*
G01X1626100Y468164D02*
Y452804D01*
G01X1647139Y426616D02*
Y407765D01*
G01X1644636Y429119D02*
X1647139Y426616D01*
G01X1644636Y462885D02*
Y429119D01*
G01X1648278Y466527D02*
X1644636Y462885D01*
G01X1602500Y430000D02*
X1605250D01*
G01X1602000Y430500D02*
X1602500Y430000D01*
G01X1596800Y430500D02*
X1602000D01*
G01X1589317D02*
X1596800D01*
G01X1615061Y463157D02*
Y466433D01*
G01X1622700Y459510D02*
X1623300Y458910D01*
G01X1622700Y461900D02*
Y459510D01*
G01X1628439Y431726D02*
Y439800D01*
G01X1631813Y428352D02*
X1628439Y431726D01*
G01X1631813Y426796D02*
Y428352D01*
G01X1638013Y420596D02*
X1631813Y426796D01*
G01X1638013Y414132D02*
Y420596D01*
G01X1631592Y407711D02*
X1638013Y414132D01*
G01X1629265Y407711D02*
X1631592D01*
G01X1628026Y406472D02*
X1629265Y407711D01*
G01X1628026Y403824D02*
Y406472D01*
G01X1628439Y450239D02*
X1630300Y452100D01*
G01X1628439Y439800D02*
Y450239D01*
G01X1630200Y462713D02*
Y457175D01*
G01X1629913Y463000D02*
X1630200Y462713D01*
G01X1648863Y464707D02*
Y407037D01*
G01X1663462Y479306D02*
X1648863Y464707D01*
G01X1649988Y464241D02*
Y406311D01*
G01X1664587Y478840D02*
X1649988Y464241D01*
G01X1629459Y419548D02*
X1630120Y418887D01*
G01X1626283Y419548D02*
X1629459D01*
G01X1627800Y452099D02*
Y464899D01*
G01X1626326Y450625D02*
X1627800Y452099D01*
G01X1626326Y428833D02*
Y450625D01*
G01X1631959Y423200D02*
X1626326Y428833D01*
G01X1633004Y423200D02*
X1631959D01*
G01X1636313Y419891D02*
X1633004Y423200D01*
G01X1636313Y417749D02*
Y419891D01*
G01X1632587Y414023D02*
X1636313Y417749D01*
G01X1632587Y411674D02*
Y414023D01*
G01X1632590Y411671D02*
X1632587Y411674D01*
G01X1630330Y409411D02*
X1632590Y411671D01*
G01X1628560Y409411D02*
X1630330D01*
G01X1626326Y407177D02*
X1628560Y409411D01*
G01X1633463Y462288D02*
X1640802Y469627D01*
G01X1633463Y427878D02*
Y462288D01*
G01X1633486Y427855D02*
X1633463Y427878D01*
G01X1633486Y427821D02*
Y427855D01*
G01X1639663Y421644D02*
X1633486Y427821D01*
G01X1639663Y412390D02*
Y421644D01*
G01X1632073Y404800D02*
X1639663Y412390D01*
G01X1630750Y404800D02*
X1632073D01*
G01X1612500Y411800D02*
Y414700D01*
G01X1643089Y423066D02*
Y410199D01*
G01X1636912Y429243D02*
X1643089Y423066D01*
G01X1636912Y459405D02*
Y429243D01*
G01X1636911Y459406D02*
X1636912Y459405D01*
G01X1636911Y460172D02*
Y459406D01*
G01X1636912Y460173D02*
X1636911Y460172D01*
G01X1636912Y460891D02*
Y460173D01*
G01X1644228Y468207D02*
X1636912Y460891D01*
G01X1621612Y452000D02*
X1623527Y453915D01*
G01X1621000Y452000D02*
X1621612D01*
G01X1645439Y425911D02*
Y408878D01*
G01X1642936Y428414D02*
X1645439Y425911D01*
G01X1642936Y463590D02*
Y428414D01*
G01X1646578Y467232D02*
X1642936Y463590D01*
G01X1644014Y423450D02*
Y409815D01*
G01X1637837Y429627D02*
X1644014Y423450D01*
G01X1637837Y460507D02*
Y429627D01*
G01X1645153Y467823D02*
X1637837Y460507D01*
G01X1641465Y495964D02*
X1641963D01*
G01X1635568Y490067D02*
X1641465Y495964D01*
G01X1635568Y469758D02*
Y490067D01*
G01X1632638Y466828D02*
X1635568Y469758D01*
G01X1634643Y476707D02*
X1626100Y468164D01*
G01X1634643Y490451D02*
Y476707D01*
G01X1639113Y494921D02*
X1634643Y490451D01*
G01X1639113Y496734D02*
Y494921D01*
G01X1648278Y470802D02*
Y466527D01*
G01X1648281Y470805D02*
X1648278Y470802D01*
G01X1648281Y471819D02*
Y470805D01*
G01X1655318Y478856D02*
X1648281Y471819D01*
G01X1650093Y500217D02*
X1651486D01*
G01X1646517Y503793D02*
X1650093Y500217D01*
G01X1646517Y505295D02*
Y503793D01*
G01X1647624Y506402D02*
X1646517Y505295D01*
G01X1649708Y506402D02*
X1647624D01*
G01X1650944Y505166D02*
X1649708Y506402D01*
G01X1615061Y466433D02*
X1615307Y466679D01*
G01X1648330Y504544D02*
X1650544Y502330D01*
G01X1643169Y508102D02*
X1641470Y506403D01*
G01X1651647Y508102D02*
X1643169D01*
G01X1627800Y464899D02*
X1633075Y470174D01*
G01X1649998Y514762D02*
X1654944D01*
G01X1649545Y515215D02*
X1649998Y514762D01*
G01X1639900Y518000D02*
X1719500D01*
G01X1637100Y515200D02*
X1639900Y518000D01*
G01X1637100Y504200D02*
Y515200D01*
G01X1644543Y496757D02*
X1637100Y504200D01*
G01X1644543Y487943D02*
Y496757D01*
G01X1640250Y483650D02*
X1644543Y487943D01*
G01X1640250Y477452D02*
Y483650D01*
G01X1640802Y476900D02*
X1640250Y477452D01*
G01X1640802Y469627D02*
Y476900D01*
G01X1644228Y475480D02*
Y468207D01*
G01X1644229Y475481D02*
X1644228Y475480D01*
G01X1644229Y478319D02*
Y475481D01*
G01X1644228Y478320D02*
X1644229Y478319D01*
G01X1644228Y478321D02*
Y478320D01*
G01X1643676Y478873D02*
X1644228Y478321D01*
G01X1643676Y482230D02*
Y478873D01*
G01X1645346Y483900D02*
X1643676Y482230D01*
G01X1651026Y483900D02*
X1645346D01*
G01X1649455Y511622D02*
X1651168Y513335D01*
G01X1649455Y511502D02*
Y511622D01*
G01X1649336Y511502D02*
X1649455D01*
G01X1646578Y471507D02*
Y467232D01*
G01X1646580Y471509D02*
X1646578Y471507D01*
G01X1646580Y472523D02*
Y471509D01*
G01X1653617Y479560D02*
X1646580Y472523D01*
G01X1644651Y503198D02*
X1653617Y494232D01*
G01X1644651Y505500D02*
Y503198D01*
G01X1645153Y472098D02*
Y467823D01*
G01X1645154Y472099D02*
X1645153Y472098D01*
G01X1645154Y472865D02*
Y472099D01*
G01X1645153Y472866D02*
X1645154Y472865D01*
G01X1645153Y475096D02*
Y472866D01*
G01X1645154Y475097D02*
X1645153Y475096D01*
G01X1645154Y478703D02*
Y475097D01*
G01X1645153Y478704D02*
X1645154Y478703D01*
G01X1645153Y478705D02*
Y478704D01*
G01X1644601Y479257D02*
X1645153Y478705D01*
G01X1644601Y481846D02*
Y479257D01*
G01X1645630Y482875D02*
X1644601Y481846D01*
G01X1651248Y482875D02*
X1645630D01*
G01X1643803Y563647D02*
Y570630D01*
G01X1641756Y561600D02*
X1643803Y563647D01*
G01X1641756Y558000D02*
Y561600D01*
G01X1645256Y563618D02*
X1646756Y565118D01*
G01X1645256Y558000D02*
Y563618D01*
G01X1594530Y611090D02*
X1594110Y611510D01*
G01X1594530Y596610D02*
Y611090D01*
G01X1590968Y593048D02*
X1594530Y596610D01*
G01X1606064Y621952D02*
X1707280D01*
G01X1603550Y619438D02*
X1606064Y621952D01*
G01X1603550Y618250D02*
Y619438D01*
G01X1605677Y622977D02*
X1707705D01*
G01X1600950Y618250D02*
X1605677Y622977D01*
G01X1691050Y3000D02*
X1691000D01*
G01X1695163Y7113D02*
X1691050Y3000D01*
G01X1730186Y7113D02*
X1695163D01*
G01X1682993Y5822D02*
X1680034Y2863D01*
G01X1691523Y5822D02*
X1682993D01*
G01X1694439Y8738D02*
X1691523Y5822D01*
G01X1729512Y8738D02*
X1694439D01*
G01X1654500Y32038D02*
X1657462Y35000D01*
G01X1654500Y26500D02*
Y32038D01*
G01X1653941Y25941D02*
X1654500Y26500D01*
G01X1651250Y25941D02*
X1653941D01*
G01X1650717Y15879D02*
Y13141D01*
G01X1661250Y16500D02*
X1656500D01*
G01X1656425Y31059D02*
X1658750D01*
G01X1656000Y30634D02*
X1656425Y31059D01*
G01X1656000Y19000D02*
Y30634D01*
G01X1656500Y18500D02*
X1656000Y19000D01*
G01X1656500Y16500D02*
Y18500D01*
G01X1652300Y12300D02*
X1653100Y11500D01*
G01X1652300Y15444D02*
Y12300D01*
G01X1653356Y16500D02*
X1652300Y15444D01*
G01X1656500Y16500D02*
X1653356D01*
G01X1679720Y-10630D02*
X1683210D01*
G01X1673500Y-16850D02*
X1679720Y-10630D01*
G01X1699788Y-20088D02*
X1758762D01*
G01X1690330Y-10630D02*
X1699788Y-20088D01*
G01X1683210Y-10630D02*
X1690330D01*
G01X1684236Y44014D02*
X1684250Y44000D01*
G01X1684236Y47039D02*
Y44014D01*
G01X1684350Y43900D02*
X1688060D01*
G01X1684250Y44000D02*
X1684350Y43900D01*
G01X1689300Y48050D02*
X1690250Y49000D01*
G01X1689300Y44700D02*
Y48050D01*
G01X1688500Y43900D02*
X1689300Y44700D01*
G01X1688060Y43900D02*
X1688500D01*
G01X1697800Y92200D02*
X1700800D01*
G01X1697800Y94612D02*
Y92200D01*
G01X1694630Y49880D02*
X1693750Y49000D01*
G01X1703250Y49880D02*
X1694630D01*
G01X1693650Y45050D02*
X1694200Y44500D01*
G01X1693650Y48900D02*
Y45050D01*
G01X1693750Y49000D02*
X1693650Y48900D01*
G01X1704824Y83744D02*
X1712420Y76148D01*
G01X1704824Y90049D02*
Y83744D01*
G01X1659183Y35000D02*
X1660944Y36761D01*
G01X1657462Y35000D02*
X1659183D01*
G01X1669172Y59300D02*
X1671700D01*
G01X1665876Y62596D02*
X1669172Y59300D01*
G01X1659196Y69276D02*
X1665876Y62596D01*
G01X1659196Y70291D02*
Y69276D01*
G01X1678400Y69500D02*
X1680958Y66942D01*
G01X1676400Y69500D02*
X1678400D01*
G01X1682200Y65700D02*
X1680958Y66942D01*
G01X1689129Y65700D02*
X1682200D01*
G01X1690500Y67071D02*
X1689129Y65700D01*
G01X1690500Y73950D02*
Y67071D01*
G01X1711250Y68500D02*
Y72000D01*
G01D02*
X1713600D01*
G01X1665699Y49000D02*
X1667497Y47202D01*
G01X1662600Y49000D02*
X1665699D01*
G01X1657400Y55100D02*
X1652279Y60221D01*
G01X1657400Y49371D02*
Y55100D01*
G01X1660348Y49371D02*
X1657400D01*
G01X1660719Y49000D02*
X1660348Y49371D01*
G01X1662600Y49000D02*
X1660719D01*
G01X1679377Y51223D02*
X1682625D01*
G01X1678974Y51626D02*
X1679377Y51223D01*
G01X1678627Y51973D02*
X1678974Y51626D01*
G01X1678627Y54616D02*
Y51973D01*
G01X1673024Y98726D02*
X1682750Y89000D01*
G01X1708610Y81691D02*
X1718400Y71901D01*
G01X1708610Y85121D02*
Y81691D01*
G01X1675200Y55800D02*
Y59300D01*
G01Y60075D02*
Y59300D01*
G01X1670775Y64500D02*
X1675200Y60075D01*
G01X1670500Y64500D02*
X1670775D01*
G01X1676800Y55800D02*
X1675200D01*
G01X1677346Y56346D02*
X1676800Y55800D01*
G01X1680603Y56346D02*
X1677346D01*
G01X1682638Y54311D02*
X1680603Y56346D01*
G01X1687750Y81500D02*
X1686250Y80000D01*
G01X1688700Y81500D02*
X1687750D01*
G01X1691655Y78545D02*
X1688700Y81500D01*
G01X1691655Y77991D02*
Y78545D01*
G01X1686138Y51236D02*
X1686125Y51223D01*
G01X1686138Y54311D02*
Y51236D01*
G01X1687694Y54000D02*
X1689750D01*
G01X1687383Y54311D02*
X1687694Y54000D01*
G01X1686138Y54311D02*
X1687383D01*
G01X1671700Y54650D02*
Y55800D01*
G01X1673663Y52687D02*
X1671700Y54650D01*
G01X1673663Y49264D02*
Y52687D01*
G01X1669399Y45000D02*
X1673663Y49264D01*
G01X1662708Y45000D02*
X1669399D01*
G01X1660000Y47708D02*
X1662708Y45000D01*
G01X1654328Y47708D02*
X1660000D01*
G01X1651425Y50611D02*
X1654328Y47708D01*
G01X1650659Y50611D02*
X1651425D01*
G01X1650658Y50610D02*
X1650659Y50611D01*
G01X1669500Y53500D02*
Y51500D01*
G01X1667000Y56000D02*
X1669500Y53500D01*
G01X1665677Y57323D02*
X1667000Y56000D01*
G01X1665677Y59323D02*
Y57323D01*
G01X1663000Y62000D02*
X1665677Y59323D01*
G01X1663000Y63456D02*
Y62000D01*
G01X1656600Y69856D02*
X1663000Y63456D01*
G01X1656600Y73614D02*
Y69856D01*
G01X1681939Y59736D02*
X1682158Y59955D01*
G01X1681939Y57671D02*
Y59736D01*
G01X1682864Y56746D02*
X1681939Y57671D01*
G01X1684248Y56746D02*
X1682864D01*
G01X1682364Y60161D02*
X1685661D01*
G01X1682158Y59955D02*
X1682364Y60161D01*
G01X1674250Y66000D02*
X1676400D01*
G01X1673500Y66750D02*
X1674250Y66000D01*
G01X1665127Y66750D02*
X1673500D01*
G01X1661658Y70219D02*
X1665127Y66750D01*
G01X1661658Y72028D02*
Y70219D01*
G01X1661563Y72028D02*
X1661658D01*
G01X1681040Y63161D02*
X1685661D01*
G01X1678201Y66000D02*
X1681040Y63161D01*
G01X1676400Y66000D02*
X1678201D01*
G01X1689700Y83000D02*
X1686250D01*
G01X1694155Y78545D02*
X1689700Y83000D01*
G01X1694155Y77991D02*
Y78545D01*
G01X1679312Y89438D02*
X1682750Y86000D01*
G01X1679312Y91042D02*
Y89438D01*
G01X1675557Y94797D02*
X1679312Y91042D01*
G01X1695940Y54000D02*
X1693250D01*
G01X1697500Y52440D02*
X1695940Y54000D01*
G01X1703250Y52440D02*
X1697500D01*
G01X1652500Y88000D02*
X1652000Y87500D01*
G01X1656000Y88000D02*
X1652500D01*
G01X1659000D02*
X1656000D01*
G01X1697100Y42500D02*
X1743001D01*
G01X1696150Y41550D02*
X1697100Y42500D01*
G01X1681850Y41550D02*
X1696150D01*
G01X1680750Y42650D02*
X1681850Y41550D01*
G01X1680750Y44000D02*
Y42650D01*
G01X1678289Y47039D02*
X1677250Y46000D01*
G01X1680736Y47039D02*
X1678289D01*
G01X1677250Y45150D02*
Y46000D01*
G01X1675100Y43000D02*
X1677250Y45150D01*
G01X1663670Y93080D02*
Y96064D01*
G01X1667087Y89663D02*
X1663670Y93080D01*
G01X1671645Y89663D02*
X1667087D01*
G01X1672113Y89195D02*
X1671645Y89663D01*
G01X1672113Y85249D02*
Y89195D01*
G01X1673799Y83563D02*
X1672113Y85249D01*
G01X1678405Y83563D02*
X1673799D01*
G01X1681968Y80000D02*
X1678405Y83563D01*
G01X1682750Y80000D02*
X1681968D01*
G01X1688350Y71000D02*
Y68000D01*
G01X1678000Y79232D02*
X1679147Y78085D01*
G01X1678000Y81600D02*
Y79232D01*
G01X1688350Y74129D02*
Y71000D01*
G01X1685929Y76550D02*
X1688350Y74129D01*
G01X1680682Y76550D02*
X1685929D01*
G01X1679147Y78085D02*
X1680682Y76550D01*
G01X1657000Y91000D02*
X1656000D01*
G01X1657900Y91900D02*
X1657000Y91000D01*
G01X1661400Y91900D02*
X1657900D01*
G01X1661900Y92400D02*
X1661400Y91900D01*
G01X1655699Y91000D02*
X1656000D01*
G01X1654199Y92500D02*
X1655699Y91000D01*
G01X1652000Y92500D02*
X1654199D01*
G01X1681246Y83000D02*
X1682750D01*
G01X1679758Y84488D02*
X1681246Y83000D01*
G01X1674183Y84488D02*
X1679758D01*
G01X1673078Y85593D02*
X1674183Y84488D01*
G01X1673078Y90772D02*
Y85593D01*
G01X1668550Y95300D02*
X1673078Y90772D01*
G01X1698373Y57560D02*
X1695772Y60161D01*
G01X1703250Y57560D02*
X1698373D01*
G01X1695772Y61778D02*
Y60161D01*
G01X1694070Y63480D02*
X1695772Y61778D01*
G01X1694070Y64800D02*
Y63480D01*
G01X1704639Y94061D02*
X1697896Y100804D01*
G01X1707186Y93006D02*
G02X1704639Y94061I0J3602D01*
G01X1720287Y93006D02*
X1707186D01*
G01X1665300Y76400D02*
X1670500Y81600D01*
G01X1663000Y76400D02*
X1665300D01*
G01X1662500Y60484D02*
Y58800D01*
G01X1661575Y61409D02*
X1662500Y60484D01*
G01X1661575Y62865D02*
Y61409D01*
G01X1660469Y63971D02*
X1661575Y62865D01*
G01X1656900Y63971D02*
X1660469D01*
G01X1656616Y76400D02*
X1663000D01*
G01X1654700Y74484D02*
X1656616Y76400D01*
G01X1654700Y68299D02*
Y74484D01*
G01X1656900Y66099D02*
X1654700Y68299D01*
G01X1656900Y63971D02*
Y66099D01*
G01X1689161Y64421D02*
Y63161D01*
G01X1692470Y67730D02*
X1689161Y64421D01*
G01X1692470Y69740D02*
Y67730D01*
G01X1689161Y60161D02*
Y63161D01*
G01X1692272Y60161D02*
X1689161D01*
G01X1653944Y46783D02*
X1651042Y49685D01*
G01X1659516Y46783D02*
X1653944D01*
G01X1662299Y44000D02*
X1659516Y46783D01*
G01X1671750Y44000D02*
X1662299D01*
G01X1673750Y46000D02*
X1671750Y44000D01*
G01X1691800Y94136D02*
Y92200D01*
G01X1692225Y94561D02*
X1691800Y94136D01*
G01Y92200D02*
X1694800D01*
G01X1698755Y60120D02*
X1703250D01*
G01X1697891Y60984D02*
X1698755Y60120D01*
G01X1697891Y65019D02*
Y60984D01*
G01X1695605Y67305D02*
X1697891Y65019D01*
G01X1695605Y73955D02*
Y67305D01*
G01X1696647Y74997D02*
X1695605Y73955D01*
G01X1702882Y74997D02*
X1696647D01*
G01X1703727Y74152D02*
X1702882Y74997D01*
G01X1705714Y68500D02*
X1707750D01*
G01X1704558Y69656D02*
X1705714Y68500D01*
G01X1704558Y73321D02*
Y69656D01*
G01X1703727Y74152D02*
X1704558Y73321D01*
G01X1707750Y74550D02*
Y72000D01*
G01X1704600Y77700D02*
X1707750Y74550D01*
G01X1700130Y77700D02*
X1704600D01*
G01X1693900Y73701D02*
Y73300D01*
G01X1696290Y76091D02*
X1693900Y73701D01*
G01X1698521Y76091D02*
X1696290D01*
G01X1700130Y77700D02*
X1698521Y76091D01*
G01X1665881Y103269D02*
X1662675Y106475D01*
G01X1666797Y103269D02*
X1665881D01*
G01X1668618Y101448D02*
X1666797Y103269D01*
G01X1674992Y101448D02*
X1668618D01*
G01X1678845Y97595D02*
X1674992Y101448D01*
G01X1679345Y97096D02*
X1678846Y97595D01*
G01X1681969Y97096D02*
X1679345D01*
G01X1682750Y96315D02*
X1681969Y97096D01*
G01X1682750Y95000D02*
Y96315D01*
G01X1661727Y107423D02*
X1662675Y106475D01*
G01X1659603Y107423D02*
X1661727D01*
G01X1657835Y109191D02*
X1659603Y107423D01*
G01X1658736Y122688D02*
G02X1657835Y121790I-269701J269701D01*
G01X1658788Y122740D02*
X1658736Y122688D01*
G01X1660232Y123338D02*
G03X1658788Y122740I0J-2042D01*
G01X1667024Y123338D02*
X1660232D01*
G01X1672751Y121116D02*
G03X1667024Y123338I-5727J-6269D01*
G01X1673613Y119035D02*
G03X1672751Y121116I-2943J0D01*
G01X1673613Y118893D02*
Y119035D01*
G01X1674085Y118011D02*
G02X1673613Y118893I1222J1221D01*
G01X1676113Y115983D02*
X1674085Y118011D01*
G01X1677510Y112611D02*
G03X1676113Y115983I-4768J0D01*
G01X1677510Y112607D02*
Y112611D01*
G01X1679246Y108416D02*
G02X1677510Y112607I4191J4191D01*
G01X1679250Y108412D02*
X1679246Y108416D01*
G01X1683182Y104478D02*
X1679250Y108412D01*
G01X1686507Y103101D02*
G02X1683182Y104478I-1J4701D01*
G01X1690970Y103101D02*
X1686507D01*
G01X1707635Y95051D02*
X1719811D01*
G01X1705561Y95910D02*
G03X1707635Y95051I2074J2074D01*
G01X1699222Y102249D02*
X1705561Y95910D01*
G01X1697166Y103101D02*
G02X1699222Y102249I0J-2908D01*
G01X1690970Y103101D02*
X1697166D01*
G01X1707519Y116423D02*
X1697872D01*
G01X1710520Y115180D02*
G03X1707519Y116423I-3001J-3002D01*
G01X1715253Y110447D02*
X1710520Y115180D01*
G01X1695531Y116423D02*
X1697872D01*
G01X1694841Y116709D02*
G03X1695531Y116423I690J689D01*
G01X1693565Y117985D02*
X1694841Y116709D01*
G01X1692355Y117985D02*
G02X1693565I605J-606D01*
G01X1692354Y117984D02*
X1692355Y117985D01*
G01X1691144Y117984D02*
G03X1692354I605J606D01*
G01X1690992Y118136D02*
X1691144Y117984D01*
G01X1690992Y119346D02*
G03Y118136I606J-605D01*
G01X1690993Y119347D02*
X1690992Y119346D01*
G01X1690993Y120557D02*
G02Y119347I-606J-605D01*
G01X1685674Y125876D02*
X1690993Y120557D01*
G01X1683161Y126917D02*
G02X1685674Y125876I0J-3554D01*
G01X1679570Y126917D02*
X1683161D01*
G01X1679250Y126974D02*
G03X1679570Y126917I320J871D01*
G01X1678914Y127189D02*
G03X1679250Y126974I657J656D01*
G01X1678755Y127347D02*
X1678914Y127189D01*
G01X1677617Y127819D02*
G02X1678755Y127347I-1J-1610D01*
G01X1670783Y127819D02*
X1677617D01*
G01X1670491Y127832D02*
G02X1670783Y127819I2J-3233D01*
G01X1668594Y127046D02*
G02X1670491Y127832I1897J-1897D01*
G01X1668386Y126838D02*
X1668594Y127046D01*
G01X1667420Y126438D02*
G03X1668386Y126838I0J1366D01*
G01X1661463Y126438D02*
X1667420D01*
G01X1660985Y126916D02*
G03X1661463Y126438I478J0D01*
G01X1660985Y128089D02*
Y126916D01*
G01X1665000Y154151D02*
X1664135Y153286D01*
G01X1666859Y154921D02*
G03X1665000Y154151I0J-2629D01*
G01X1668188Y154921D02*
X1666859D01*
G01X1669586Y155500D02*
G02X1668188Y154921I-1398J1398D01*
G01X1670010Y155923D02*
X1669586Y155500D01*
G01X1671160Y156400D02*
G03X1670010Y155923I1J-1627D01*
G01X1666456Y102444D02*
X1668247Y100653D01*
G01X1666142Y102444D02*
X1666456D01*
G01X1666141Y102445D02*
X1666142Y102444D01*
G01X1665459Y102445D02*
X1666141D01*
G01X1665458Y102444D02*
X1665459Y102445D01*
G01X1663765Y102444D02*
X1665458D01*
G01X1660000Y106209D02*
X1663765Y102444D01*
G01X1658679Y106209D02*
X1660000D01*
G01X1656237Y108651D02*
X1658679Y106209D01*
G01X1656237Y110789D02*
Y108651D01*
G01X1654685Y112341D02*
X1656237Y110789D01*
G01X1653752Y106975D02*
X1651536Y109191D01*
G01X1655269Y106975D02*
X1653752D01*
G01X1656859Y105385D02*
X1655269Y106975D01*
G01X1659658Y105385D02*
X1656859D01*
G01X1663423Y101620D02*
X1659658Y105385D01*
G01X1665800Y101620D02*
X1663423D01*
G01X1668694Y98726D02*
X1665800Y101620D01*
G01X1672222Y98726D02*
X1668694D01*
G01X1672222D02*
X1673024D01*
G01X1707042Y147311D02*
X1716094Y138259D01*
G01X1707042Y147319D02*
Y147311D01*
G01X1701580Y152782D02*
X1707042Y147319D01*
G01X1701455Y153083D02*
G03X1701580Y152782I426J1D01*
G01X1683749Y136233D02*
X1682141D01*
G01X1685517Y135501D02*
G03X1683749Y136233I-1768J-1768D01*
G01X1686225Y134793D02*
X1685517Y135501D01*
G01X1687585Y134793D02*
G02X1686225I-680J680D01*
G01X1688112Y135320D02*
X1687585Y134793D01*
G01X1689472Y135320D02*
G03X1688112I-680J-680D01*
G01X1689474Y135318D02*
X1689472Y135320D01*
G01X1689474Y133958D02*
G03Y135318I-680J680D01*
G01X1688947Y133431D02*
X1689474Y133958D01*
G01X1688947Y132071D02*
G02Y133431I680J680D01*
G01X1692875Y128143D02*
X1688947Y132071D01*
G01X1694235Y128143D02*
G02X1692875I-680J680D01*
G01X1695166Y129074D02*
X1694235Y128143D01*
G01X1696526Y129074D02*
G03X1695166I-680J-680D01*
G01X1696528Y129072D02*
X1696526Y129074D01*
G01X1696528Y127712D02*
G03Y129072I-680J680D01*
G01X1695597Y126781D02*
X1696528Y127712D01*
G01X1695597Y125421D02*
G02Y126781I680J680D01*
G01X1697064Y123954D02*
X1695597Y125421D01*
G01X1697061Y123947D02*
X1697064Y123954D01*
G01X1697058Y123948D02*
X1697061Y123947D01*
G01X1697577Y123429D02*
X1697058Y123948D01*
G01X1698091Y123216D02*
G02X1697577Y123429I0J727D01*
G01X1698597Y123216D02*
X1698091D01*
G01X1699461Y124080D02*
G02X1698597Y123216I-864J0D01*
G01X1700325Y124944D02*
G03X1699461Y124080I0J-864D01*
G01X1700522Y124944D02*
X1700325D01*
G01X1701386Y124080D02*
G03X1700522Y124944I-864J0D01*
G01X1702250Y123216D02*
G02X1701386Y124080I0J864D01*
G01X1702447Y123216D02*
X1702250D01*
G01X1703311Y124080D02*
G02X1702447Y123216I-864J0D01*
G01X1704175Y124944D02*
G03X1703311Y124080I0J-864D01*
G01X1704372Y124944D02*
X1704175D01*
G01X1705236Y124080D02*
G03X1704372Y124944I-864J0D01*
G01X1706100Y123216D02*
G02X1705236Y124080I0J864D01*
G01X1714041Y123216D02*
X1706100D01*
G01X1664135Y129072D02*
Y128089D01*
G01X1664701Y129638D02*
G03X1664135Y129072I0J-566D01*
G01X1668220Y129638D02*
X1664701D01*
G01X1669216Y130634D02*
G02X1668220Y129638I-996J0D01*
G01X1669216Y133622D02*
Y130634D01*
G01X1671142Y133622D02*
G03X1669216I-963J0D01*
G01X1671142Y131230D02*
Y133622D01*
G01X1673068Y131230D02*
G02X1671142I-963J0D01*
G01X1673068Y134665D02*
Y131230D01*
G01X1674636Y136233D02*
G03X1673068Y134665I0J-1568D01*
G01X1676633Y136233D02*
X1674636D01*
G01X1677497Y135369D02*
G03X1676633Y136233I-864J0D01*
G01X1678361Y134505D02*
G02X1677497Y135369I0J864D01*
G01X1678564Y134505D02*
X1678361D01*
G01X1679250Y134848D02*
G02X1678564Y134505I-686J515D01*
G01X1679422Y135363D02*
G02X1679250Y134848I-857J0D01*
G01X1679422Y135369D02*
Y135363D01*
G01X1680286Y136233D02*
G03X1679422Y135369I0J-864D01*
G01X1682141Y136233D02*
X1680286D01*
G01X1672511Y138275D02*
X1676372D01*
G01X1668755Y136719D02*
G02X1672511Y138275I3756J-3755D01*
G01X1667156Y135120D02*
X1668755Y136719D01*
G01X1666854Y134995D02*
G03X1667156Y135120I0J427D01*
G01X1660822Y134995D02*
X1666854D01*
G01X1660822Y133069D02*
G02Y134995I0J963D01*
G01X1666238Y133069D02*
X1660822D01*
G01X1667284Y132023D02*
G03X1666238Y133069I-1046J0D01*
G01X1667284Y131239D02*
Y132023D01*
G01X1688513Y138275D02*
X1676372D01*
G01X1690162Y137592D02*
G03X1688513Y138275I-1649J-1649D01*
G01X1690522Y137232D02*
X1690162Y137592D01*
G01X1691244Y137232D02*
G02X1690522I-361J360D01*
G01X1691444Y137432D02*
X1691244Y137232D01*
G01X1692562Y137432D02*
G03X1691444I-559J-560D01*
G01X1692806Y137188D02*
X1692562Y137432D01*
G01X1692806Y136199D02*
G03Y137188I-495J494D01*
G01X1692385Y135778D02*
X1692806Y136199D01*
G01X1691786Y134332D02*
G02X1692385Y135778I2045J0D01*
G01X1691786Y133364D02*
Y134332D01*
G01X1692353Y131995D02*
G02X1691786Y133364I1369J1369D01*
G01X1693869Y131367D02*
G02X1692353Y131995I0J2144D01*
G01X1700604Y131367D02*
X1693869D01*
G01X1701224Y131110D02*
G03X1700604Y131367I-620J-620D01*
G01X1701556Y130778D02*
X1701224Y131110D01*
G01X1701556Y129600D02*
G03Y130778I-589J589D01*
G01X1700511Y128555D02*
X1701556Y129600D01*
G01X1700511Y127195D02*
G02Y128555I680J680D01*
G01X1700513Y127193D02*
X1700511Y127195D01*
G01X1701873Y127193D02*
G02X1700513I-680J680D01*
G01X1702827Y128147D02*
X1701873Y127193D01*
G01X1704187Y128147D02*
G03X1702827I-680J-680D01*
G01X1705687Y126647D02*
X1704187Y128147D01*
G01X1708698Y125400D02*
G02X1705687Y126647I0J4259D01*
G01X1716777Y125400D02*
X1708698D01*
G01X1706280Y135570D02*
G03X1713322Y132653I7042J7042D01*
G01X1699561Y142291D02*
X1706280Y135570D01*
G01X1699206Y142438D02*
G02X1699561Y142291I0J-502D01*
G01X1693586Y142438D02*
X1699206D01*
G01X1680435Y152650D02*
X1677740D01*
G01X1681411Y153054D02*
G02X1680435Y152650I-976J977D01*
G01X1683289Y154932D02*
X1681411Y153054D01*
G01X1683823Y155153D02*
G03X1683289Y154932I0J-755D01*
G01X1692389Y155153D02*
X1683823D01*
G01X1693351Y154191D02*
G03X1692389Y155153I-962J0D01*
G01X1693351Y154180D02*
Y154191D01*
G01X1695276Y154180D02*
G02X1693351I-962J0D01*
G01X1695276Y154191D02*
Y154180D01*
G01X1696238Y155153D02*
G03X1695276Y154191I0J-962D01*
G01X1701289Y155153D02*
X1696238D01*
G01X1702960Y154461D02*
G03X1701289Y155153I-1671J-1672D01*
G01X1715893Y141528D02*
X1702960Y154461D01*
G01X1652312Y154064D02*
X1654686Y150138D01*
G01X1653800Y148588D02*
G02X1652829Y149137I0J1133D01*
G01X1661190Y148588D02*
X1653800D01*
G01X1662066Y148951D02*
G02X1661190Y148588I-876J876D01*
G01X1662151Y149036D02*
X1662066Y148951D01*
G01X1662386Y149238D02*
G02X1662151Y149036I-1449J1448D01*
G01X1663386Y150238D02*
X1662386Y149238D01*
G01X1664352Y150638D02*
G03X1663386Y150238I0J-1366D01*
G01X1665020Y150638D02*
X1664352D01*
G01X1665986Y151038D02*
G02X1665020Y150638I-966J966D01*
G01X1666675Y151730D02*
X1665986Y151038D01*
G01X1667251Y151969D02*
G03X1666675Y151730I0J-813D01*
G01X1669042Y151969D02*
X1667251D01*
G01X1669467Y151544D02*
G03X1669042Y151969I-425J0D01*
G01X1669467Y151346D02*
Y151544D01*
G01X1671392Y151346D02*
G02X1669467I-962J0D01*
G01X1671392Y151995D02*
Y151346D01*
G01X1673317Y151995D02*
G03X1671392I-962J0D01*
G01X1673317Y151560D02*
Y151995D01*
G01X1675242Y151560D02*
G02X1673317I-962J0D01*
G01X1675242Y152038D02*
Y151560D01*
G01X1675655Y152594D02*
G03X1675242Y152038I168J-556D01*
G01X1675960Y152650D02*
G03X1675655Y152594I0J-857D01*
G01X1677740Y152650D02*
X1675960D01*
G01X1663563Y146413D02*
X1664186Y147038D01*
G01X1663018Y145094D02*
G02X1663563Y146413I1868J0D01*
G01X1663018Y144362D02*
Y145094D01*
G01X1664747Y144362D02*
G02X1663018I-865J0D01*
G01X1665666Y146004D02*
G03X1664747Y144362I1007J-1642D01*
G01X1668491Y147174D02*
G03X1665666Y146004I0J-3995D01*
G01X1676880Y147174D02*
X1668491D01*
G01X1677710Y146830D02*
G03X1676880Y147174I-830J-830D01*
G01X1679019Y146288D02*
G02X1677710Y146830I0J1851D01*
G01X1683784Y146288D02*
X1679019D01*
G01X1684746Y147250D02*
G02X1683784Y146288I-962J0D01*
G01X1684746Y148404D02*
Y147250D01*
G01X1686671Y148404D02*
G03X1684746I-963J0D01*
G01X1686671Y147250D02*
Y148404D01*
G01X1688596Y147250D02*
G02X1686671I-962J0D01*
G01X1688596Y148404D02*
Y147250D01*
G01X1690521Y148404D02*
G03X1688596I-962J0D01*
G01X1690521Y147251D02*
Y148404D01*
G01X1692446Y147251D02*
G02X1690521I-962J0D01*
G01X1692446Y148404D02*
Y147251D01*
G01X1694371Y148404D02*
G03X1692446I-962J0D01*
G01X1694371Y147251D02*
Y148404D01*
G01X1696296Y147251D02*
G02X1694371I-962J0D01*
G01X1696296Y148358D02*
Y147251D01*
G01X1698221Y148358D02*
G03X1696296I-962J0D01*
G01X1698221Y147250D02*
Y148358D01*
G01X1699183Y146288D02*
G02X1698221Y147250I0J962D01*
G01X1699780Y146288D02*
X1699183D01*
G01X1702746Y145059D02*
G03X1699780Y146288I-2966J-2965D01*
G01X1706065Y141740D02*
X1702746Y145059D01*
G01X1711422Y137225D02*
G02X1712880Y136621I0J-2062D01*
G01X1709984Y137820D02*
G03X1711422Y137225I1437J1438D01*
G01X1708897Y138908D02*
X1709984Y137820D01*
G01X1706065Y141740D02*
X1708897Y138908D01*
G01X1653409Y106151D02*
X1652149D01*
G01X1653410Y106150D02*
X1653409Y106151D01*
G01X1654431Y106150D02*
X1653410D01*
G01X1656020Y104561D02*
X1654431Y106150D01*
G01X1659316Y104561D02*
X1656020D01*
G01X1663081Y100796D02*
X1659316Y104561D01*
G01X1665458Y100796D02*
X1663081D01*
G01X1666477Y99777D02*
X1665458Y100796D01*
G01X1666477Y98539D02*
Y99777D01*
G01X1667972Y97044D02*
X1666477Y98539D01*
G01X1668956Y97044D02*
X1667972D01*
G01X1671203Y94797D02*
X1668956Y97044D01*
G01X1673415Y94797D02*
X1671203D01*
G01X1673415D02*
X1675557D01*
G01X1678155Y154625D02*
X1673132D01*
G01X1679250Y154772D02*
G02X1678155Y154625I-1095J4007D01*
G01X1681092Y155842D02*
G02X1679250Y154772I-2938J2937D01*
G01X1682857Y157607D02*
X1681092Y155842D01*
G01X1704167Y155994D02*
G03X1701446Y157121I-2721J-2721D01*
G01X1705167Y154994D02*
X1704167Y155994D01*
G01X1706527Y154994D02*
G02X1705167I-680J680D01*
G01X1707757Y156224D02*
X1706527Y154994D01*
G01X1709119Y156222D02*
X1709117Y156224D01*
G01X1709119Y154862D02*
G03Y156222I-680J680D01*
G01X1707889Y153632D02*
X1709119Y154862D01*
G01X1707889Y152272D02*
G02Y153632I680J680D01*
G01X1707891Y152270D02*
X1707889Y152272D01*
G01X1709251Y152270D02*
G02X1707891I-680J680D01*
G01X1710481Y153500D02*
X1709251Y152270D01*
G01X1711841Y153500D02*
G03X1710481I-680J-680D01*
G01X1711843Y153498D02*
X1711841Y153500D01*
G01X1711843Y152138D02*
G03Y153498I-680J680D01*
G01X1710613Y150908D02*
X1711843Y152138D01*
G01X1710613Y149548D02*
G02Y150908I680J680D01*
G01X1716663Y143496D02*
X1710613Y149548D01*
G01X1671859Y154625D02*
X1673132D01*
G01X1670642Y154121D02*
G02X1671859Y154625I1217J-1217D01*
G01X1670639Y154118D02*
X1670642Y154121D01*
G01X1669128Y153492D02*
G03X1670639Y154118I0J2137D01*
G01X1668070Y153492D02*
X1669128D01*
G01X1665629Y152481D02*
G02X1668070Y153492I2441J-2441D01*
G01X1665386Y152238D02*
X1665629Y152481D01*
G01X1664179Y151738D02*
G03X1665386Y152238I0J1707D01*
G01X1662370Y151738D02*
X1664179D01*
G01X1660921Y153187D02*
G03X1662370Y151738I1449J0D01*
G01X1660921Y153869D02*
Y153187D01*
G01X1660614Y154610D02*
G02X1660921Y153869I-741J-741D01*
G01X1660131Y154810D02*
G02X1660614Y154610I0J-683D01*
G01X1655244Y154810D02*
X1660131D01*
G01X1654686Y154252D02*
G02X1655244Y154810I558J0D01*
G01X1654686Y153288D02*
Y154252D01*
G01X1653812Y104000D02*
X1651009D01*
G01X1655149Y102663D02*
X1653812Y104000D01*
G01X1658882Y102663D02*
X1655149D01*
G01X1662064Y99481D02*
X1658882Y102663D01*
G01X1662064Y98354D02*
Y99481D01*
G01X1662063Y98353D02*
X1662064Y98354D01*
G01X1662063Y97671D02*
Y98353D01*
G01X1663670Y96064D02*
X1662063Y97671D01*
G01X1665600Y95300D02*
X1666693D01*
G01X1662888Y98012D02*
X1665600Y95300D01*
G01X1662888Y99823D02*
Y98012D01*
G01X1659224Y103487D02*
X1662888Y99823D01*
G01X1655631Y103487D02*
X1659224D01*
G01X1654093Y105025D02*
X1655631Y103487D01*
G01X1651575Y105025D02*
X1654093D01*
G01X1666693Y95300D02*
X1668550D01*
G01X1691732Y151292D02*
X1697694D01*
G01X1690770Y152254D02*
G03X1691732Y151292I962J0D01*
G01X1690770Y152265D02*
Y152254D01*
G01X1688845Y152265D02*
G02X1690770I962J0D01*
G01X1688845Y152254D02*
Y152265D01*
G01X1686920Y152254D02*
G03X1688845I963J0D01*
G01X1686920Y152265D02*
Y152254D01*
G01X1684995Y152265D02*
G02X1686920I962J0D01*
G01X1684995Y152254D02*
Y152265D01*
G01X1684033Y151292D02*
G03X1684995Y152254I0J962D01*
G01X1682660Y151292D02*
X1684033D01*
G01X1681510Y150142D02*
G02X1682660Y151292I1150J0D01*
G01X1681510Y149183D02*
Y150142D01*
G01X1679585Y149183D02*
G03X1681510I962J0D01*
G01X1679585Y150143D02*
Y149183D01*
G01X1679028Y150700D02*
G02X1679585Y150143I0J-557D01*
G01X1678471Y150700D02*
X1679028D01*
G01X1676899Y150049D02*
G02X1678471Y150700I1572J-1572D01*
G01X1675746Y148896D02*
X1676899Y150049D01*
G01X1675002Y148588D02*
G03X1675746Y148896I0J1053D01*
G01X1663972Y148588D02*
X1675002D01*
G01X1662886Y148138D02*
G02X1663972Y148588I1086J-1086D01*
G01X1662586Y147414D02*
G02X1662886Y148138I1024J0D01*
G01X1662586Y147038D02*
Y147414D01*
G01X1662162Y146013D02*
G03X1662586Y147038I-1027J1025D01*
G01X1662086Y145938D02*
X1662162Y146013D01*
G01X1660879Y145438D02*
G03X1662086Y145938I0J1707D01*
G01X1652664Y145438D02*
X1660879D01*
G01X1651838Y145780D02*
G03X1652664Y145438I826J826D01*
G01X1651536Y146509D02*
G03X1651838Y145780I1031J0D01*
G01X1651536Y146988D02*
Y146509D01*
G01X1700400Y151168D02*
X1713324Y138242D01*
G01X1700098Y151292D02*
G02X1700400Y151168I1J-427D01*
G01X1697694Y151292D02*
X1700098D01*
G01X1674481Y114647D02*
X1673296Y115832D01*
G01X1675544Y112081D02*
G03X1674481Y114647I-3629J0D01*
G01X1675544Y111358D02*
Y112081D01*
G01X1677000Y107844D02*
G02X1675544Y111358I3514J3515D01*
G01X1682030Y102814D02*
X1677000Y107844D01*
G01X1685985Y101176D02*
G02X1682030Y102814I0J5593D01*
G01X1696998Y101176D02*
X1685985D01*
G01X1697896Y100804D02*
G03X1696998Y101176I-898J-898D01*
G01X1666526Y119399D02*
X1664135Y121790D01*
G01X1668105Y118745D02*
G02X1666526Y119399I0J2233D01*
G01X1668799Y118745D02*
X1668105D01*
G01X1671503Y117625D02*
G03X1668799Y118745I-2704J-2704D01*
G01X1673296Y115832D02*
X1671503Y117625D01*
G01X1678838Y140300D02*
X1670733D01*
G01X1679250Y140322D02*
G02X1678838Y140300I-413J3865D01*
G01X1681586Y141438D02*
G02X1679250Y140322I-2748J2750D01*
G01X1661167Y137720D02*
X1660986Y137538D01*
G01X1664500Y139100D02*
G03X1661167Y137720I-1J-4713D01*
G01X1666100Y139100D02*
X1664500D01*
G01X1667466Y139666D02*
G02X1666100Y139100I-1366J1365D01*
G01X1667468Y139668D02*
X1667466Y139666D01*
G01X1668993Y140300D02*
G03X1667468Y139668I0J-2156D01*
G01X1670733Y140300D02*
X1668993D01*
G01X1661770Y125264D02*
G03X1660985Y124939I0J-1110D01*
G01X1669157Y125264D02*
X1661770D01*
G01X1670550Y124687D02*
G03X1669157Y125264I-1393J-1393D01*
G01X1671931Y124687D02*
G02X1670550I-690J691D01*
G01X1672349Y125662D02*
G02X1671931Y124687I-1425J34D01*
G01X1672349Y125663D02*
Y125662D01*
G01X1672540Y126343D02*
G03X1672349Y125663I1117J-681D01*
G01X1673385Y126693D02*
G03X1672540Y126343I0J-1195D01*
G01X1675236Y126693D02*
X1673385D01*
G01X1677604Y125712D02*
G03X1675236Y126693I-2368J-2368D01*
G01X1677606Y125710D02*
X1677604Y125712D01*
G01X1679250Y124952D02*
G02X1677606Y125710I206J2609D01*
G01X1679352Y124948D02*
G02X1679250Y124952I0J1297D01*
G01X1682701Y124948D02*
X1679352D01*
G01X1683210Y124737D02*
G03X1682701Y124948I-509J-509D01*
G01X1684127Y122523D02*
G03X1683210Y124737I-3131J0D01*
G01X1684127Y118033D02*
Y122523D01*
G01X1685091Y115705D02*
G02X1684127Y118033I2328J2328D01*
G01X1686751Y114045D02*
X1685091Y115705D01*
G01X1688124Y115418D02*
G02X1686751Y114045I-687J-686D01*
G01X1686461Y117081D02*
X1688124Y115418D01*
G01X1686053Y118066D02*
G03X1686461Y117081I1393J0D01*
G01X1686053Y120422D02*
Y118066D01*
G01X1687979Y120422D02*
G03X1686053I-963J0D01*
G01X1687979Y118546D02*
Y120422D01*
G01X1688104Y118244D02*
G02X1687979Y118546I302J302D01*
G01X1691302Y115046D02*
X1688104Y118244D01*
G01X1692692Y114470D02*
G02X1691302Y115046I0J1966D01*
G01X1705138Y114470D02*
X1692692D01*
G01X1705139Y114471D02*
X1705138Y114470D01*
G01X1706986Y114471D02*
X1705139D01*
G01X1709192Y113557D02*
G03X1706986Y114471I-2206J-2205D01*
G01X1715951Y106798D02*
X1709192Y113557D01*
G01X1657835Y118238D02*
X1654875Y115278D01*
G01X1657835Y118640D02*
Y118238D01*
G01X1655500Y101000D02*
X1654800Y100300D01*
G01X1656000Y101000D02*
X1655500D01*
G01X1659379D02*
X1656000D01*
G01X1660400Y99979D02*
X1659379Y101000D01*
G01X1660400Y98500D02*
Y99979D01*
G01X1688126Y144363D02*
X1692944D01*
G01X1687089Y143326D02*
G02X1688126Y144363I1037J0D01*
G01X1687089Y141163D02*
Y143326D01*
G01X1685164Y141163D02*
G03X1687089I962J0D01*
G01X1685164Y142360D02*
Y141163D01*
G01X1683895Y143629D02*
G02X1685164Y142360I0J-1269D01*
G01X1680369Y143629D02*
X1683895D01*
G01X1679271Y143174D02*
G02X1680369Y143629I1098J-1098D01*
G01X1679250Y143153D02*
X1679271Y143174D01*
G01X1678805Y142756D02*
G02X1679250Y143153I3700J-3699D01*
G01X1678803Y142754D02*
X1678805Y142756D01*
G01X1676378Y141749D02*
G03X1678803Y142754I0J3429D01*
G01X1669027Y141749D02*
X1676378D01*
G01X1669027Y143674D02*
G03Y141749I0J-962D01*
G01X1675160Y143674D02*
X1669027D01*
G01X1675160Y145600D02*
G02Y143674I0J-963D01*
G01X1667982Y145600D02*
X1675160D01*
G01X1666452Y144070D02*
G02X1667982Y145600I1530J0D01*
G01X1666452Y143050D02*
Y144070D01*
G01X1665602Y142200D02*
G03X1666452Y143050I0J850D01*
G01X1658277Y142200D02*
X1665602D01*
G01X1657836Y141759D02*
G02X1658277Y142200I441J0D01*
G01X1657836Y140688D02*
Y141759D01*
G01X1699354Y144363D02*
X1692944D01*
G01X1700988Y143686D02*
G03X1699354Y144363I-1634J-1633D01*
G01X1707726Y136948D02*
X1700988Y143686D01*
G01X1713211Y134676D02*
G02X1707726Y136948I0J7757D01*
G01X1692243Y94561D02*
X1692225D01*
G01X1692285Y94603D02*
X1692243Y94561D01*
G01X1692285Y94612D02*
Y94603D01*
G01X1710089Y158080D02*
X1718501Y149668D01*
G01X1652200Y164300D02*
X1650900D01*
G01X1653496Y165596D02*
X1652200Y164300D01*
G01X1653496Y167799D02*
Y165596D01*
G01Y173772D02*
Y167799D01*
G01X1653849Y174125D02*
X1653496Y173772D01*
G01X1653849Y175788D02*
Y174125D01*
G01X1711610Y208600D02*
X1701500D01*
G01X1719297Y216287D02*
X1711610Y208600D01*
G01X1684143D02*
X1701500D01*
G01X1680452Y212291D02*
X1684143Y208600D01*
G01X1672311Y212291D02*
X1680452D01*
G01X1669103Y209083D02*
X1672311Y212291D01*
G01X1661430Y209083D02*
X1669103D01*
G01X1657664Y212849D02*
X1661430Y209083D01*
G01X1655999Y212849D02*
X1657664D01*
G01X1665579Y214616D02*
X1654458Y225737D01*
G01X1665579Y212521D02*
Y214616D01*
G01X1666667Y211433D02*
X1665579Y212521D01*
G01X1668045Y211433D02*
X1666667D01*
G01X1668236Y211624D02*
X1668045Y211433D01*
G01X1668319Y211624D02*
X1668236D01*
G01X1672109Y215414D02*
X1668319Y211624D01*
G01X1688239Y215414D02*
X1672109D01*
G01X1691227Y212426D02*
X1688239Y215414D01*
G01X1691869Y212426D02*
X1691227D01*
G01X1691870Y212425D02*
X1691869Y212426D01*
G01X1709624Y212425D02*
X1691870D01*
G01X1715837Y218638D02*
X1709624Y212425D01*
G01X1692945Y162922D02*
X1691596D01*
G01X1693235Y162862D02*
G03X1692945Y162922I-291J-676D01*
G01X1693699Y162670D02*
G02X1693235Y162862I0J656D01*
G01X1698255Y162670D02*
X1693699D01*
G01X1699292Y163707D02*
G02X1698255Y162670I-1037J0D01*
G01X1699292Y167424D02*
Y163707D01*
G01X1701217Y167424D02*
G03X1699292I-962J0D01*
G01X1701217Y164774D02*
Y167424D01*
G01X1703142Y164774D02*
G02X1701217I-962J0D01*
G01X1703142Y167572D02*
Y164774D01*
G01X1705067Y167572D02*
G03X1703142I-963J0D01*
G01X1705067Y163865D02*
Y167572D01*
G01X1706113Y162819D02*
G02X1705067Y163865I0J1046D01*
G01X1713748Y162819D02*
X1706113D01*
G01X1677550Y156400D02*
X1671160D01*
G01X1679598Y157249D02*
G02X1677550Y156400I-2049J2048D01*
G01X1679599Y157249D02*
X1679598D01*
G01X1679599Y157248D02*
Y157249D01*
G01X1680445Y158095D02*
X1679599Y157248D01*
G01X1680445Y159297D02*
G02Y158095I-601J-601D01*
G01X1679772Y159969D02*
X1680445Y159297D01*
G01X1681140Y161337D02*
G03X1679772Y159969I-684J-684D01*
G01X1681977Y160500D02*
X1681140Y161337D01*
G01X1682849Y160500D02*
G02X1681977I-436J436D01*
G01X1684256Y161907D02*
X1682849Y160500D01*
G01X1686813Y162966D02*
G03X1684256Y161907I0J-3616D01*
G01X1691552Y162966D02*
X1686813D01*
G01X1691596Y162922D02*
X1691552Y162966D01*
G01X1658777Y201164D02*
X1657033Y202908D01*
G01X1658777Y200100D02*
Y201164D01*
G01X1659751Y199126D02*
X1658777Y200100D01*
G01X1668600Y199126D02*
X1659751D01*
G01X1669091Y198635D02*
X1668600Y199126D01*
G01X1683847Y198635D02*
X1669091D01*
G01X1687846Y194636D02*
X1683847Y198635D01*
G01X1687846Y189992D02*
Y194636D01*
G01X1685921Y188067D02*
X1687846Y189992D01*
G01X1685921Y181870D02*
Y188067D01*
G01X1683562Y179511D02*
X1685921Y181870D01*
G01X1679250Y179511D02*
X1683562D01*
G01X1710620Y160354D02*
X1716202Y154772D01*
G01X1709317Y160894D02*
G02X1710620Y160354I0J-1842D01*
G01X1703930Y160894D02*
X1709317D01*
G01X1703610Y161214D02*
X1703930Y160894D01*
G01X1660679Y179278D02*
Y175778D01*
G01Y181779D02*
X1660800Y181900D01*
G01X1660679Y179278D02*
Y181779D01*
G01X1712811Y200675D02*
X1708922Y204564D01*
G01X1685700D02*
X1708922D01*
G01X1681521Y208743D02*
X1685700Y204564D01*
G01X1675372Y208743D02*
X1681521D01*
G01X1673345Y206716D02*
X1675372Y208743D01*
G01X1669963Y206716D02*
X1673345D01*
G01X1668521Y208158D02*
X1669963Y206716D01*
G01X1661045Y208158D02*
X1668521D01*
G01X1657279Y211924D02*
X1661045Y208158D01*
G01X1655615Y211924D02*
X1657279D01*
G01X1691362Y214786D02*
X1680148Y226000D01*
G01X1705162Y214786D02*
X1691362D01*
G01X1705163Y214785D02*
X1705162Y214786D01*
G01X1706667Y214785D02*
X1705163D01*
G01X1713882Y222000D02*
X1706667Y214785D01*
G01X1656700Y168761D02*
Y171014D01*
G01X1655374Y167435D02*
X1656700Y168761D01*
G01X1655374Y165601D02*
Y167435D01*
G01X1655373Y165600D02*
X1655374Y165601D01*
G01X1655373Y164821D02*
Y165600D01*
G01X1654799Y164247D02*
X1655373Y164821D01*
G01X1654059Y164247D02*
X1654799D01*
G01X1653173Y163361D02*
X1654059Y164247D01*
G01X1653173Y162621D02*
Y163361D01*
G01X1653126Y162574D02*
X1653173Y162621D01*
G01X1653126Y158025D02*
Y162574D01*
G01X1651536Y156435D02*
X1653126Y158025D01*
G01X1667356Y214113D02*
Y213096D01*
G01X1669579Y216336D02*
X1667356Y214113D01*
G01X1688484Y216336D02*
X1669579D01*
G01X1691320Y213500D02*
X1688484Y216336D01*
G01X1709532Y213500D02*
X1691320D01*
G01X1715495Y219463D02*
X1709532Y213500D01*
G01X1683805Y158000D02*
G03X1682857Y157607I0J-1340D01*
G01X1684589Y158000D02*
X1683805D01*
G01X1685422Y158833D02*
G02X1684589Y158000I-833J0D01*
G01X1685422Y159503D02*
Y158833D01*
G01X1687347Y159503D02*
G03X1685422I-962J0D01*
G01X1687347Y158933D02*
Y159503D01*
G01X1688002Y158278D02*
G02X1687347Y158933I0J655D01*
G01X1691814Y158278D02*
X1688002D01*
G01X1692243Y158707D02*
G02X1691814Y158278I-429J0D01*
G01X1692243Y159470D02*
Y158707D01*
G01X1694168Y159470D02*
G03X1692243I-962J0D01*
G01X1694168Y158467D02*
Y159470D01*
G01X1696094Y158467D02*
G02X1694168I-963J0D01*
G01X1696094Y159668D02*
Y158467D01*
G01X1698019Y159668D02*
G03X1696094I-962J0D01*
G01X1698019Y158425D02*
Y159668D01*
G01X1698449Y157495D02*
G02X1698019Y158425I791J930D01*
G01X1699466Y157121D02*
G02X1698449Y157495I0J1568D01*
G01X1701446Y157121D02*
X1699466D01*
G01X1709117Y156224D02*
G03X1707757I-680J-680D01*
G01X1660131Y217239D02*
X1654015D01*
G01X1661494Y215876D02*
X1660131Y217239D01*
G01X1661494Y214820D02*
Y215876D01*
G01X1661513Y214801D02*
X1661494Y214820D01*
G01X1661513Y212273D02*
Y214801D01*
G01X1661553Y212233D02*
X1661513Y212273D01*
G01X1661553Y212175D02*
Y212233D01*
G01X1663720Y210008D02*
X1661553Y212175D01*
G01X1668636Y210008D02*
X1663720D01*
G01X1668827Y210199D02*
X1668636Y210008D01*
G01X1668910Y210199D02*
X1668827D01*
G01X1672173Y213462D02*
X1668910Y210199D01*
G01X1685038Y213462D02*
X1672173D01*
G01X1687500Y211000D02*
X1685038Y213462D01*
G01X1710999Y211000D02*
X1687500D01*
G01X1713137Y213138D02*
X1710999Y211000D01*
G01X1705900Y216636D02*
X1716083Y226819D01*
G01X1692453Y216636D02*
X1705900D01*
G01X1681800Y227289D02*
X1692453Y216636D01*
G01X1709900Y184100D02*
Y187300D01*
G01X1708600Y182800D02*
X1709900Y184100D01*
G01X1654200Y199700D02*
X1656200D01*
G01X1652120Y197620D02*
X1654200Y199700D01*
G01X1652120Y194644D02*
Y197620D01*
G01X1683433Y194000D02*
X1686183Y191250D01*
G01X1673595Y194000D02*
X1683433D01*
G01X1669885Y197710D02*
X1673595Y194000D01*
G01X1669475Y197710D02*
X1669885D01*
G01X1669474Y197709D02*
X1669475Y197710D01*
G01X1668708Y197709D02*
X1669474D01*
G01X1668216Y198201D02*
X1668708Y197709D01*
G01X1659367Y198201D02*
X1668216D01*
G01X1658868Y198700D02*
X1659367Y198201D01*
G01X1657577Y198700D02*
X1658868D01*
G01X1656577Y199700D02*
X1657577Y198700D01*
G01X1656200Y199700D02*
X1656577D01*
G01X1653099Y196533D02*
Y192608D01*
G01X1654266Y197700D02*
X1653099Y196533D01*
G01X1658559Y197700D02*
X1654266D01*
G01X1658983Y197276D02*
X1658559Y197700D01*
G01X1667832Y197276D02*
X1658983D01*
G01X1668324Y196784D02*
X1667832Y197276D01*
G01X1669416Y196784D02*
X1668324D01*
G01X1676400Y189800D02*
X1669416Y196784D01*
G01X1677417Y189800D02*
X1676400D01*
G01X1677558Y189941D02*
X1677417Y189800D01*
G01X1678525Y190908D02*
X1677558Y189941D01*
G01X1683484Y190908D02*
X1678525D01*
G01X1710960Y199750D02*
X1713736D01*
G01X1707750Y202960D02*
X1710960Y199750D01*
G01X1685802Y202960D02*
X1707750D01*
G01X1685296Y203466D02*
X1685802Y202960D01*
G01X1685245Y203466D02*
X1685296D01*
G01X1680893Y207818D02*
X1685245Y203466D01*
G01X1675756Y207818D02*
X1680893D01*
G01X1673729Y205791D02*
X1675756Y207818D01*
G01X1669579Y205791D02*
X1673729D01*
G01X1668137Y207233D02*
X1669579Y205791D01*
G01X1660661Y207233D02*
X1668137D01*
G01X1656895Y210999D02*
X1660661Y207233D01*
G01X1655231Y210999D02*
X1656895D01*
G01X1705500Y217600D02*
X1715043Y227143D01*
G01X1692904Y217600D02*
X1705500D01*
G01X1684300Y226204D02*
X1692904Y217600D01*
G01X1656511Y210074D02*
X1654778D01*
G01X1658190Y208395D02*
X1656511Y210074D01*
G01X1658190Y208362D02*
Y208395D01*
G01X1660244Y206308D02*
X1658190Y208362D01*
G01X1667753Y206308D02*
X1660244D01*
G01X1669478Y204583D02*
X1667753Y206308D01*
G01X1673846Y204583D02*
X1669478D01*
G01X1673847Y204584D02*
X1673846Y204583D01*
G01X1675255Y204584D02*
X1673847D01*
G01X1677804Y202035D02*
X1675255Y204584D01*
G01X1681494Y202035D02*
X1677804D01*
G01X1682000Y202541D02*
X1681494Y202035D01*
G01X1684912Y202541D02*
X1682000D01*
G01X1685418Y202035D02*
X1684912Y202541D01*
G01X1698814Y202035D02*
X1685418D01*
G01X1710032Y190817D02*
X1698814Y202035D01*
G01X1711548Y190817D02*
X1710032D01*
G01X1713839Y188526D02*
X1711548Y190817D01*
G01X1691746Y215711D02*
X1678944Y228513D01*
G01X1705546Y215711D02*
X1691746D01*
G01X1705547Y215710D02*
X1705546Y215711D01*
G01X1706283Y215710D02*
X1705547D01*
G01X1719132Y228559D02*
X1706283Y215710D01*
G01X1656599Y192608D02*
Y189608D01*
G01X1653926Y186480D02*
X1651619Y184173D01*
G01X1655574Y186480D02*
X1653926D01*
G01X1656599Y187505D02*
X1655574Y186480D01*
G01X1656599Y189608D02*
Y187505D01*
G01X1651064Y171331D02*
Y169287D01*
G01Y173073D02*
Y171331D01*
G01X1710647Y189117D02*
X1712951Y186813D01*
G01X1709327Y189117D02*
X1710647D01*
G01X1698109Y200335D02*
X1709327Y189117D01*
G01X1684713Y200335D02*
X1698109D01*
G01X1684207Y200841D02*
X1684713Y200335D01*
G01X1682705Y200841D02*
X1684207D01*
G01X1682199Y200335D02*
X1682705Y200841D01*
G01X1677099Y200335D02*
X1682199D01*
G01X1674551Y202883D02*
X1677099Y200335D01*
G01X1667248Y202883D02*
X1674551D01*
G01X1666623Y203508D02*
X1667248Y202883D01*
G01X1658838Y203508D02*
X1666623D01*
G01X1657738Y204608D02*
X1658838Y203508D01*
G01X1704719Y158650D02*
X1706296D01*
G01X1704263Y158671D02*
G03X1704719Y158650I455J4915D01*
G01X1702692Y159322D02*
G03X1704263Y158671I1571J1570D01*
G01X1700836Y161178D02*
X1702692Y159322D01*
G01X1700836Y161268D02*
Y161178D01*
G01X1708713Y158650D02*
G02X1710089Y158080I0J-1946D01*
G01X1706296Y158650D02*
X1708713D01*
G01X1668223Y241987D02*
X1669348Y240862D01*
G01X1666345Y241987D02*
X1668223D01*
G01X1673813Y277231D02*
X1677300Y280718D01*
G01X1673813Y277180D02*
Y277231D01*
G01X1673014Y276381D02*
X1673813Y277180D01*
G01X1673014Y268012D02*
Y276381D01*
G01X1676219Y264807D02*
X1673014Y268012D01*
G01X1676219Y248654D02*
Y264807D01*
G01X1674354Y246789D02*
X1676219Y248654D01*
G01X1674354Y238432D02*
Y246789D01*
G01X1671216Y235294D02*
X1674354Y238432D01*
G01X1660206Y235294D02*
X1671216D01*
G01X1658946Y236554D02*
X1660206Y235294D01*
G01X1655821Y236554D02*
X1658946D01*
G01X1654760D02*
X1655821D01*
G01X1651376Y239938D02*
X1654760Y236554D01*
G01X1670239Y277685D02*
X1674475Y281921D01*
G01X1670239Y266860D02*
Y277685D01*
G01X1672485Y264614D02*
X1670239Y266860D01*
G01X1672485Y248911D02*
Y264614D01*
G01X1671579Y248005D02*
X1672485Y248911D01*
G01X1671579Y240317D02*
Y248005D01*
G01X1670161Y238899D02*
X1671579Y240317D01*
G01X1661833Y238899D02*
X1670161D01*
G01X1656982Y243750D02*
X1661833Y238899D01*
G01X1659038Y247500D02*
X1656500D01*
G01X1661186Y245352D02*
X1659038Y247500D01*
G01X1677437Y272237D02*
X1679100Y273900D01*
G01X1677437Y270611D02*
Y272237D01*
G01X1680117Y267931D02*
X1677437Y270611D01*
G01X1680117Y247600D02*
Y267931D01*
G01X1678378Y245861D02*
X1680117Y247600D01*
G01X1678378Y235662D02*
Y245861D01*
G01X1678300Y235584D02*
X1678378Y235662D01*
G01X1678300Y235089D02*
Y235584D01*
G01X1672649Y229438D02*
X1678300Y235089D01*
G01X1672642Y229438D02*
X1672649D01*
G01X1672216Y229012D02*
X1672642Y229438D01*
G01X1665500Y226000D02*
X1664338Y227162D01*
G01X1680148Y226000D02*
X1665500D01*
G01X1673839Y276039D02*
X1679100Y281300D01*
G01X1673839Y268354D02*
Y276039D01*
G01X1677373Y264820D02*
X1673839Y268354D01*
G01X1677373Y248641D02*
Y264820D01*
G01X1675179Y246447D02*
X1677373Y248641D01*
G01X1675179Y237024D02*
Y246447D01*
G01X1672383Y234228D02*
X1675179Y237024D01*
G01X1651672Y234228D02*
X1672383D01*
G01X1662157Y256563D02*
X1659396Y253802D01*
G01X1662157Y279377D02*
Y256563D01*
G01X1667675Y284895D02*
X1662157Y279377D01*
G01X1665000Y278648D02*
Y254000D01*
G01X1670200Y283848D02*
X1665000Y278648D01*
G01Y248678D02*
X1664324Y248002D01*
G01X1665000Y254000D02*
Y248678D01*
G01X1663582Y255972D02*
X1659987Y252377D01*
G01X1663582Y278786D02*
Y255972D01*
G01X1669100Y284304D02*
X1663582Y278786D01*
G01X1681800Y233066D02*
Y227289D01*
G01X1681632Y233234D02*
X1681800Y233066D01*
G01X1681632Y233665D02*
Y233234D01*
G01X1675989Y273289D02*
X1679100Y276400D01*
G01X1675989Y269655D02*
Y273289D01*
G01X1679123Y266521D02*
X1675989Y269655D01*
G01X1679123Y264285D02*
Y266521D01*
G01X1679124Y264284D02*
X1679123Y264285D01*
G01X1679124Y262834D02*
Y264284D01*
G01X1679123Y262833D02*
X1679124Y262834D01*
G01X1679123Y247915D02*
Y262833D01*
G01X1677453Y246245D02*
X1679123Y247915D01*
G01X1677453Y236046D02*
Y246245D01*
G01X1671344Y229937D02*
X1677453Y236046D01*
G01X1650892Y229937D02*
X1671344D01*
G01X1660732Y257154D02*
X1658805Y255227D01*
G01X1660732Y279968D02*
Y257154D01*
G01X1668648Y278264D02*
X1673050Y282666D01*
G01X1668648Y265000D02*
Y278264D01*
G01Y262553D02*
Y265000D01*
G01X1669300Y261901D02*
X1668648Y262553D01*
G01X1669300Y259857D02*
Y261901D01*
G01X1667800Y258357D02*
X1669300Y259857D01*
G01X1667800Y258053D02*
Y258357D01*
G01X1667667Y257920D02*
X1667800Y258053D01*
G01X1672887Y277614D02*
X1676375Y281102D01*
G01X1672887Y277563D02*
Y277614D01*
G01X1672089Y276765D02*
X1672887Y277563D01*
G01X1672089Y267628D02*
Y276765D01*
G01X1675294Y264423D02*
X1672089Y267628D01*
G01X1675294Y249038D02*
Y264423D01*
G01X1673429Y247173D02*
X1675294Y249038D01*
G01X1673429Y238816D02*
Y247173D01*
G01X1670832Y236219D02*
X1673429Y238816D01*
G01X1661892Y236219D02*
X1670832D01*
G01X1657248Y240863D02*
X1661892Y236219D01*
G01X1684300Y233579D02*
Y226204D01*
G01X1692469Y252956D02*
X1690565Y251052D01*
G01X1708561Y252956D02*
X1692469D01*
G01X1712941Y248576D02*
X1708561Y252956D01*
G01X1662046Y237377D02*
X1656598Y242825D01*
G01X1670681Y237377D02*
X1662046D01*
G01X1672504Y239200D02*
X1670681Y237377D01*
G01X1672504Y247557D02*
Y239200D01*
G01X1674369Y249422D02*
X1672504Y247557D01*
G01X1674369Y264039D02*
Y249422D01*
G01X1671164Y267244D02*
X1674369Y264039D01*
G01X1671164Y277200D02*
Y267244D01*
G01X1675450Y281486D02*
X1671164Y277200D01*
G01X1673026Y228513D02*
X1674500D01*
G01X1672600Y228087D02*
X1673026Y228513D01*
G01X1678944D02*
X1674500D01*
G01X1666609Y260970D02*
X1666968Y260611D01*
G01X1666609Y278241D02*
Y260970D01*
G01X1671625Y283257D02*
X1666609Y278241D01*
G01X1666500Y231900D02*
X1651052D01*
G01X1671222D02*
X1666500D01*
G01X1676104Y236782D02*
X1671222Y231900D01*
G01X1676104Y246205D02*
Y236782D01*
G01X1678198Y248299D02*
X1676104Y246205D01*
G01X1678198Y263217D02*
Y248299D01*
G01X1678199Y263218D02*
X1678198Y263217D01*
G01X1678199Y263900D02*
Y263218D01*
G01X1678198Y263901D02*
X1678199Y263900D01*
G01X1678198Y265162D02*
Y263901D01*
G01X1674664Y268696D02*
X1678198Y265162D01*
G01X1674664Y274488D02*
Y268696D01*
G01X1679100Y278924D02*
X1674664Y274488D01*
G01X1689019Y253510D02*
X1686113Y250604D01*
G01X1689480Y253971D02*
X1689019Y253510D01*
G01X1708986Y253971D02*
X1689480D01*
G01X1713866Y249091D02*
X1708986Y253971D01*
G01X1653927Y337562D02*
X1652542D01*
G01X1654937Y338572D02*
X1653927Y337562D01*
G01X1654937Y338572D02*
X1659666Y343301D01*
G01X1665388Y309492D02*
Y341500D01*
G01X1664453Y308557D02*
X1665388Y309492D01*
G01X1652991Y329059D02*
X1651259D01*
G01X1650473Y311898D02*
Y319500D01*
G01X1676512Y302088D02*
X1679100Y299500D01*
G01X1676512Y314055D02*
Y302088D01*
G01X1677415Y314958D02*
X1676512Y314055D01*
G01X1677415Y431588D02*
Y314958D01*
G01X1678393Y284093D02*
X1679100D01*
G01X1677300Y283000D02*
X1678393Y284093D01*
G01X1677300Y280718D02*
Y283000D01*
G01X1654750Y313029D02*
X1650634Y308913D01*
G01X1654750Y314750D02*
Y313029D01*
G01X1658250Y314750D02*
X1654750D01*
G01X1659500Y316000D02*
X1658250Y314750D01*
G01X1659500Y317250D02*
Y316000D01*
G01X1662300Y332400D02*
X1661600Y333100D01*
G01X1662300Y327300D02*
Y332400D01*
G01Y318800D02*
Y327300D01*
G01X1660750Y317250D02*
X1662300Y318800D01*
G01X1659500Y317250D02*
X1660750D01*
G01X1678891Y314991D02*
Y431755D01*
G01X1677437Y313537D02*
X1678891Y314991D01*
G01X1677437Y303763D02*
Y313537D01*
G01X1679100Y302100D02*
X1677437Y303763D01*
G01X1679100Y291852D02*
Y292000D01*
G01X1674475Y287227D02*
X1679100Y291852D01*
G01X1674475Y281921D02*
Y287227D01*
G01X1661872Y339602D02*
Y338515D01*
G01X1663291Y341021D02*
X1661872Y339602D01*
G01X1663291Y374906D02*
Y341021D01*
G01X1659407Y308711D02*
X1661248D01*
G01X1658207Y309911D02*
X1659407Y308711D01*
G01X1658207Y312925D02*
Y309911D01*
G01X1663963Y318681D02*
X1658207Y312925D01*
G01X1663963Y333708D02*
Y318681D01*
G01X1661872Y335799D02*
X1663963Y333708D01*
G01X1661872Y338515D02*
Y335799D01*
G01X1676490Y315342D02*
Y431972D01*
G01X1675587Y314439D02*
X1676490Y315342D01*
G01X1675587Y300513D02*
Y314439D01*
G01X1679100Y297000D02*
X1675587Y300513D01*
G01X1657750Y334875D02*
X1653427D01*
G01X1658758Y335883D02*
X1657750Y334875D01*
G01X1658758Y338177D02*
Y335883D01*
G01X1662191Y341610D02*
X1658758Y338177D01*
G01X1651100Y292050D02*
X1651500Y291650D01*
G01X1651100Y300900D02*
Y292050D01*
G01X1653584Y298027D02*
X1655526D01*
G01X1652700Y297143D02*
X1653584Y298027D01*
G01X1652700Y292300D02*
Y297143D01*
G01X1652050Y291650D02*
X1652700Y292300D01*
G01X1651500Y291650D02*
X1652050D01*
G01X1679100Y281300D02*
Y281593D01*
G01X1667675Y290047D02*
Y284895D01*
G01X1668735Y291107D02*
X1667675Y290047D01*
G01X1668735Y344282D02*
Y291107D01*
G01X1678490Y305310D02*
X1679100Y304700D01*
G01X1678490Y312691D02*
Y305310D01*
G01X1679916Y314117D02*
X1678490Y312691D01*
G01X1679916Y431471D02*
Y314117D01*
G01X1670200Y289000D02*
Y283848D01*
G01X1671312Y290112D02*
X1670200Y289000D01*
G01X1671312Y316212D02*
Y290112D01*
G01X1672215Y317115D02*
X1671312Y316212D01*
G01X1672215Y433745D02*
Y317115D01*
G01X1669100Y289456D02*
Y284304D01*
G01X1670212Y290568D02*
X1669100Y289456D01*
G01X1670212Y316668D02*
Y290568D01*
G01X1671115Y317571D02*
X1670212Y316668D01*
G01X1671115Y434201D02*
Y317571D01*
G01X1666250Y285486D02*
X1660732Y279968D01*
G01X1666250Y290638D02*
Y285486D01*
G01X1666900Y291288D02*
X1666250Y290638D01*
G01X1666900Y342004D02*
Y291288D01*
G01X1675065Y315933D02*
Y432563D01*
G01X1674162Y315030D02*
X1675065Y315933D01*
G01X1674162Y288930D02*
Y315030D01*
G01X1673050Y287818D02*
X1674162Y288930D01*
G01X1673050Y282666D02*
Y287818D01*
G01X1652250Y283750D02*
Y283250D01*
G01X1678198Y286593D02*
X1679100D01*
G01X1676375Y284770D02*
X1678198Y286593D01*
G01X1676375Y281102D02*
Y284770D01*
G01X1661248Y301864D02*
Y305211D01*
G01X1662526Y300586D02*
X1661248Y301864D01*
G01X1675450Y285623D02*
Y281486D01*
G01X1679100Y289273D02*
X1675450Y285623D01*
G01X1679100Y289500D02*
Y289273D01*
G01X1671625Y288409D02*
Y283257D01*
G01X1672737Y289521D02*
X1671625Y288409D01*
G01X1672737Y315621D02*
Y289521D01*
G01X1673640Y316524D02*
X1672737Y315621D01*
G01X1673640Y433154D02*
Y316524D01*
G01X1656873Y336136D02*
X1653132D01*
G01X1657658Y336921D02*
X1656873Y336136D01*
G01X1657658Y338639D02*
Y336921D01*
G01X1661091Y342072D02*
X1657658Y338639D01*
G01X1658849Y394917D02*
Y446060D01*
G01X1656806Y392874D02*
X1658849Y394917D01*
G01X1656806Y371865D02*
Y392874D01*
G01X1658241Y370430D02*
X1656806Y371865D01*
G01X1658241Y345277D02*
Y370430D01*
G01X1662697Y396749D02*
Y405706D01*
G01X1658231Y392283D02*
X1662697Y396749D01*
G01X1658231Y372456D02*
Y392283D01*
G01X1659666Y371021D02*
X1658231Y372456D01*
G01X1659666Y343301D02*
Y371021D01*
G01X1666647Y396968D02*
Y407639D01*
G01X1666621Y396942D02*
X1666647Y396968D01*
G01X1666621Y361929D02*
Y396942D01*
G01X1664716Y360024D02*
X1666621Y361929D01*
G01X1664716Y342172D02*
Y360024D01*
G01X1665388Y341500D02*
X1664716Y342172D01*
G01X1662358Y375839D02*
X1663291Y374906D01*
G01X1662358Y379344D02*
Y375839D01*
G01X1665222Y382208D02*
X1662358Y379344D01*
G01X1665222Y406753D02*
Y382208D01*
G01X1662191Y374450D02*
Y341610D01*
G01X1661258Y375383D02*
X1662191Y374450D01*
G01X1661258Y379800D02*
Y375383D01*
G01X1664122Y382664D02*
X1661258Y379800D01*
G01X1664122Y406297D02*
Y382664D01*
G01X1669690Y358727D02*
Y417110D01*
G01X1668735Y357772D02*
X1669690Y358727D01*
G01X1668735Y344282D02*
Y357772D01*
G01X1666141Y342763D02*
X1666900Y342004D01*
G01X1666141Y357194D02*
Y342763D01*
G01X1668046Y359099D02*
X1666141Y357194D01*
G01X1668046Y396351D02*
Y359099D01*
G01X1668072Y396377D02*
X1668046Y396351D01*
G01X1668072Y408706D02*
Y396377D01*
G01X1655598Y402434D02*
Y461512D01*
G01X1654809Y401645D02*
X1655598Y402434D01*
G01X1650500Y354500D02*
Y345334D01*
G01X1654065Y367453D02*
Y347556D01*
G01X1651163Y400351D02*
Y384645D01*
G01X1654673Y403861D02*
X1651163Y400351D01*
G01Y376313D02*
Y384645D01*
G01X1651493Y375983D02*
X1651163Y376313D01*
G01X1651493Y372064D02*
Y375983D01*
G01X1654990Y368567D02*
X1651493Y372064D01*
G01X1654990Y347172D02*
Y368567D01*
G01X1657424Y395508D02*
Y455732D01*
G01X1655381Y393465D02*
X1657424Y395508D01*
G01X1655381Y371274D02*
Y393465D01*
G01X1656816Y369839D02*
X1655381Y371274D01*
G01X1656816Y345868D02*
Y369839D01*
G01X1661091Y371665D02*
Y342072D01*
G01X1659656Y373100D02*
X1661091Y371665D01*
G01X1659656Y386605D02*
Y373100D01*
G01X1660934Y387883D02*
X1659656Y386605D01*
G01X1670574Y459290D02*
X1676304Y465020D01*
G01X1670574Y457785D02*
Y459290D01*
G01X1658849Y446060D02*
X1670574Y457785D01*
G01X1677729Y464429D02*
Y472933D01*
G01X1672000Y458700D02*
X1677729Y464429D01*
G01X1672000Y457195D02*
Y458700D01*
G01X1660274Y445469D02*
X1672000Y457195D01*
G01X1660274Y408129D02*
Y445469D01*
G01X1662697Y405706D02*
X1660274Y408129D01*
G01X1664803Y434008D02*
X1669076Y438281D01*
G01X1664803Y409483D02*
Y434008D01*
G01X1666647Y407639D02*
X1664803Y409483D01*
G01X1685222Y439395D02*
X1677415Y431588D01*
G01X1685222Y456091D02*
Y439395D01*
G01X1684481Y456832D02*
X1685222Y456091D01*
G01X1684435Y456832D02*
X1684481D01*
G01X1706018Y436046D02*
X1713449Y443477D01*
G01X1683182Y436046D02*
X1706018D01*
G01X1678891Y431755D02*
X1683182Y436046D01*
G01X1662799Y409176D02*
X1665222Y406753D01*
G01X1662799Y436072D02*
Y409176D01*
G01X1664762Y438035D02*
X1662799Y436072D01*
G01X1681336Y456925D02*
Y457690D01*
G01X1684297Y453964D02*
X1681336Y456925D01*
G01X1684297Y439779D02*
Y453964D01*
G01X1676490Y431972D02*
X1684297Y439779D01*
G01X1682551Y459421D02*
X1684435D01*
G01X1681336Y458206D02*
X1682551Y459421D01*
G01X1681336Y457690D02*
Y458206D01*
G01X1661699Y408720D02*
X1664122Y406297D01*
G01X1661699Y444400D02*
Y408720D01*
G01X1664299Y447000D02*
X1661699Y444400D01*
G01X1665900Y447000D02*
X1664299D01*
G01X1667863D02*
X1665900D01*
G01X1669816Y448953D02*
X1667863Y447000D01*
G01X1669690Y417110D02*
X1668100Y418700D01*
G01X1683566Y435121D02*
X1679916Y431471D01*
G01X1706402Y435121D02*
X1683566D01*
G01X1714374Y443093D02*
X1706402Y435121D01*
G01X1678303Y439833D02*
X1672215Y433745D01*
G01X1678303Y442765D02*
Y439833D01*
G01X1673050Y436136D02*
X1671115Y434201D01*
G01X1673050Y442196D02*
Y436136D01*
G01X1673550Y442696D02*
X1673050Y442196D01*
G01X1666228Y410550D02*
X1668072Y408706D01*
G01X1666228Y419180D02*
Y410550D01*
G01X1669690Y422642D02*
X1666228Y419180D01*
G01X1669690Y434792D02*
Y422642D01*
G01X1671625Y436727D02*
X1669690Y434792D01*
G01X1671625Y443324D02*
Y436727D01*
G01X1672660Y444359D02*
X1671625Y443324D01*
G01X1675754Y444359D02*
X1672660D01*
G01X1678891Y447496D02*
X1675754Y444359D01*
G01X1678891Y458830D02*
Y447496D01*
G01X1681074Y461013D02*
X1678891Y458830D01*
G01X1681074Y472751D02*
Y461013D01*
G01X1681215Y451784D02*
Y451786D01*
G01X1682817Y450182D02*
X1681215Y451784D01*
G01X1682817Y440315D02*
Y450182D01*
G01X1675065Y432563D02*
X1682817Y440315D01*
G01X1651113Y463613D02*
Y405613D01*
G01X1667500Y480000D02*
X1651113Y463613D01*
G01X1655598Y461512D02*
X1673736Y479650D01*
G01X1652538Y462538D02*
Y404538D01*
G01X1669387Y479387D02*
X1652538Y462538D01*
G01X1653748Y462280D02*
Y404403D01*
G01X1671050Y479582D02*
X1653748Y462280D01*
G01X1654673Y461896D02*
Y403861D01*
G01X1672713Y479936D02*
X1654673Y461896D01*
G01X1670113Y460902D02*
X1674879Y465668D01*
G01X1662594Y460902D02*
X1670113D01*
G01X1657424Y455732D02*
X1662594Y460902D01*
G01X1680520Y440034D02*
X1673640Y433154D01*
G01X1680520Y445012D02*
Y440034D01*
G01Y448652D02*
Y445012D01*
G01X1681154Y449286D02*
X1680520Y448652D01*
G01X1677694Y475464D02*
X1715729D01*
G01X1676304Y474074D02*
X1677694Y475464D01*
G01X1676304Y465020D02*
Y474074D01*
G01X1677729Y472933D02*
X1678001Y473205D01*
G01X1676719Y477814D02*
X1723438D01*
G01X1673954Y475049D02*
X1676719Y477814D01*
G01X1673954Y472937D02*
Y475049D01*
G01X1672774Y471757D02*
X1673954Y472937D01*
G01X1668427Y471757D02*
X1672774D01*
G01X1665047Y468377D02*
X1668427Y471757D01*
G01X1665047Y467257D02*
Y468377D01*
G01X1655318Y480264D02*
Y478856D01*
G01X1655317Y480265D02*
X1655318Y480264D01*
G01X1655317Y496386D02*
Y480265D01*
G01X1651486Y500217D02*
X1655317Y496386D01*
G01X1656496Y498975D02*
X1658482D01*
G01X1653141Y502330D02*
X1656496Y498975D01*
G01X1650544Y502330D02*
X1653141D01*
G01X1663462Y496789D02*
Y479306D01*
G01X1661276Y498975D02*
X1663462Y496789D01*
G01X1658482Y498975D02*
X1661276D01*
G01X1664587Y481383D02*
Y478840D01*
G01X1664588Y481384D02*
X1664587Y481383D01*
G01X1664588Y482314D02*
Y481384D01*
G01X1664587Y482315D02*
X1664588Y482314D01*
G01X1664587Y497460D02*
Y482315D01*
G01X1658495Y503552D02*
X1664587Y497460D01*
G01X1656197Y503552D02*
X1658495D01*
G01X1656197D02*
X1651647Y508102D01*
G01X1685447Y490755D02*
X1712354D01*
G01X1674286Y501916D02*
X1685447Y490755D01*
G01X1667790Y501916D02*
X1674286D01*
G01X1654944Y514762D02*
X1667790Y501916D01*
G01X1651867Y484741D02*
X1651026Y483900D01*
G01X1680500Y473325D02*
X1681074Y472751D01*
G01X1667500Y497500D02*
Y480000D01*
G01X1667962Y497962D02*
X1667500Y497500D01*
G01X1667962Y500153D02*
Y497962D01*
G01X1654780Y513335D02*
X1667962Y500153D01*
G01X1651168Y513335D02*
X1654780D01*
G01X1673736Y479650D02*
X1725684D01*
G01X1669387Y496726D02*
Y479387D01*
G01X1672481Y499820D02*
X1669387Y496726D01*
G01X1672606Y499820D02*
X1672481D01*
G01X1671050Y481000D02*
Y479582D01*
G01X1698400Y521331D02*
X1697261Y520192D01*
G01X1698400Y526701D02*
Y521331D01*
G01X1672713Y481937D02*
Y479936D01*
G01X1671050Y483600D02*
X1672713Y481937D01*
G01X1699425Y520628D02*
X1699861Y520192D01*
G01X1699425Y526276D02*
Y520628D01*
G01X1700355Y527206D02*
X1699425Y526276D01*
G01X1677103Y476889D02*
X1722011D01*
G01X1674879Y474665D02*
X1677103Y476889D01*
G01X1674879Y465668D02*
Y474665D01*
G01X1653617Y494232D02*
Y479560D01*
G01X1651926Y482197D02*
X1651248Y482875D01*
G01X1694000Y580079D02*
Y588854D01*
G01X1697700Y581130D02*
X1701960Y585390D01*
G01X1697700Y570646D02*
Y581130D01*
G01X1694000Y566946D02*
X1697700Y570646D01*
G01X1694000Y565118D02*
Y566946D01*
G01X1704020Y580727D02*
X1705683D01*
G01X1703490Y581257D02*
X1704020Y580727D01*
G01X1703490Y583860D02*
Y581257D01*
G01X1701960Y585390D02*
X1703490Y583860D01*
G01X1699930Y528231D02*
X1698400Y526701D01*
G01X1715788Y528231D02*
X1699930D01*
G01X1705683Y584727D02*
Y589300D01*
G01X1691047Y573397D02*
Y570630D01*
G01X1696500Y578850D02*
X1691047Y573397D01*
G01X1696500Y585550D02*
Y578850D01*
G01X1700267Y589317D02*
X1696500Y585550D01*
G01X1716213Y527206D02*
X1700355D01*
G01X1700646Y595500D02*
X1703500D01*
G01X1694000Y588854D02*
X1700646Y595500D01*
G01X1691047Y607147D02*
Y615512D01*
G01X1693694Y604500D02*
X1691047Y607147D01*
G01X1703500Y604500D02*
X1693694D01*
G01X1707280Y621952D02*
X1713450Y615782D01*
G01X1705683Y589317D02*
X1700267D01*
G01X1705683Y589300D02*
Y589317D01*
G01X1707705Y622977D02*
X1714475Y616207D01*
G01X1696685Y600551D02*
X1691047D01*
G01X1697236Y600000D02*
X1696685Y600551D01*
G01X1703500Y600000D02*
X1697236D01*
G01X1734242Y11169D02*
X1730186Y7113D01*
G01X1734242Y14938D02*
Y11169D01*
G01X1728887Y20293D02*
X1734242Y14938D01*
G01X1728887Y21849D02*
Y20293D01*
G01X1733024Y25986D02*
X1728887Y21849D01*
G01X1758140Y25986D02*
X1733024D01*
G01X1761663Y29509D02*
X1758140Y25986D01*
G01X1761663Y41737D02*
Y29509D01*
G01X1732617Y11843D02*
X1729512Y8738D01*
G01X1732617Y14264D02*
Y11843D01*
G01X1727262Y19619D02*
X1732617Y14264D01*
G01X1727262Y22523D02*
Y19619D01*
G01X1732350Y27611D02*
X1727262Y22523D01*
G01X1757466Y27611D02*
X1732350D01*
G01X1760038Y30183D02*
X1757466Y27611D01*
G01X1760038Y40665D02*
Y30183D01*
G01X1767320Y-21007D02*
X1774853D01*
G01X1764863Y-18550D02*
X1767320Y-21007D01*
G01X1764863Y3540D02*
Y-18550D01*
G01X1759093Y9310D02*
X1764863Y3540D01*
G01X1772700Y7100D02*
X1769730Y10070D01*
G01X1772700Y632D02*
Y7100D01*
G01X1774372Y-1040D02*
X1772700Y632D01*
G01X1769504Y-15000D02*
X1774372Y-10132D01*
G01X1769730Y13830D02*
Y10070D01*
G01X1771100Y15200D02*
X1769730Y13830D01*
G01X1773100Y15200D02*
X1771100D01*
G01X1761872Y-16978D02*
Y-7220D01*
G01X1758762Y-20088D02*
X1761872Y-16978D01*
G01X1732120Y60120D02*
X1732650Y60650D01*
G01X1726750Y60120D02*
X1732120D01*
G01X1761558Y81060D02*
X1763250D01*
G01X1758726Y78228D02*
X1761558Y81060D01*
G01X1751578Y78228D02*
X1758726D01*
G01X1750500Y77150D02*
X1751578Y78228D01*
G01X1750500Y74313D02*
Y77150D01*
G01X1748717Y72530D02*
X1750500Y74313D01*
G01X1740783Y72530D02*
X1748717D01*
G01X1739100Y74213D02*
X1740783Y72530D01*
G01X1739100Y87350D02*
Y74213D01*
G01X1739700Y87950D02*
X1739100Y87350D01*
G01X1742150Y87950D02*
X1739700D01*
G01X1767577Y81060D02*
X1763250D01*
G01X1767587Y81070D02*
X1767577Y81060D01*
G01X1769250Y81070D02*
X1767587D01*
G01X1773450D02*
X1776380Y84000D01*
G01X1769250Y81070D02*
X1773450D01*
G01X1770550Y57500D02*
X1780929D01*
G01X1767250Y60800D02*
X1770550Y57500D01*
G01X1762100Y60800D02*
X1767250D01*
G01X1759525Y58225D02*
X1762100Y60800D01*
G01X1759525Y56400D02*
Y58225D01*
G01Y43875D02*
X1761663Y41737D01*
G01X1759525Y56400D02*
Y43875D01*
G01X1772314Y62395D02*
X1768628D01*
G01X1774159Y60550D02*
X1772314Y62395D01*
G01X1761880Y94500D02*
X1760461Y93081D01*
G01X1757676Y43027D02*
X1760038Y40665D01*
G01X1757659Y43027D02*
X1757676D01*
G01X1753700Y46986D02*
X1757659Y43027D01*
G01X1753700Y65950D02*
Y46986D01*
G01X1750108Y69542D02*
X1753700Y65950D01*
G01X1731119Y69542D02*
X1750108D01*
G01X1729077Y67500D02*
X1731119Y69542D01*
G01X1722450Y67500D02*
X1729077D01*
G01X1722220Y67270D02*
X1722450Y67500D01*
G01X1718990Y67270D02*
X1722220D01*
G01X1717050Y69210D02*
X1718990Y67270D01*
G01X1717050Y71510D02*
Y69210D01*
G01X1712420Y76140D02*
X1717050Y71510D01*
G01X1712420Y76148D02*
Y76140D01*
G01X1773750Y91250D02*
Y89500D01*
G01X1773200Y91800D02*
X1773750Y91250D01*
G01X1764900Y91800D02*
X1773200D01*
G01X1726750Y52440D02*
X1720500D01*
G01X1735050Y50450D02*
X1735850Y49650D01*
G01X1733050Y50450D02*
X1735050D01*
G01X1731060Y52440D02*
X1733050Y50450D01*
G01X1726750Y52440D02*
X1731060D01*
G01X1732060Y57560D02*
X1732650Y58150D01*
G01X1726750Y57560D02*
X1732060D01*
G01X1713600Y72000D02*
X1715100Y70500D01*
G01X1756961Y90985D02*
X1757772Y90174D01*
G01X1756961Y93081D02*
Y90985D01*
G01X1724513Y71300D02*
X1728460D01*
G01X1721713Y68500D02*
X1724513Y71300D01*
G01X1719500Y68500D02*
X1721713D01*
G01X1718400Y69600D02*
X1719500Y68500D01*
G01X1718400Y71901D02*
Y69600D01*
G01X1753040Y75940D02*
X1756750D01*
G01X1752210Y75110D02*
X1753040Y75940D01*
G01X1752210Y73610D02*
Y75110D01*
G01X1749430Y70830D02*
X1752210Y73610D01*
G01X1732070Y70830D02*
X1749430D01*
G01X1731600Y71300D02*
X1732070Y70830D01*
G01X1728460Y71300D02*
X1731600D01*
G01X1743650Y83950D02*
Y82200D01*
G01X1745650Y85950D02*
X1743650Y83950D01*
G01X1745650Y87950D02*
Y85950D01*
G01Y87950D02*
Y91850D01*
G01X1756879Y85310D02*
Y87674D01*
G01X1757395Y84794D02*
X1756879Y85310D01*
G01X1754216Y87674D02*
X1756879D01*
G01X1753370Y88520D02*
X1754216Y87674D01*
G01X1734089Y64630D02*
Y63639D01*
G01X1734957Y65498D02*
X1734089Y64630D01*
G01X1741044Y65498D02*
X1734957D01*
G01X1733130Y62680D02*
X1734089Y63639D01*
G01X1726750Y62680D02*
X1733130D01*
G01X1722201Y89100D02*
X1723681D01*
G01X1721101Y88000D02*
X1722201Y89100D01*
G01X1719750Y88000D02*
X1721101D01*
G01X1723681Y91180D02*
Y89100D01*
G01X1726421Y93920D02*
X1723681Y91180D01*
G01X1727860Y93920D02*
X1726421D01*
G01X1729570D02*
X1731350Y92140D01*
G01X1727860Y93920D02*
X1729570D01*
G01X1737600Y44700D02*
X1736600D01*
G01X1741700Y48800D02*
X1737600Y44700D01*
G01X1745900Y48800D02*
X1741700D01*
G01X1747300Y47400D02*
X1745900Y48800D01*
G01X1750400Y47400D02*
X1747300D01*
G01X1731420Y49880D02*
X1726750D01*
G01X1732500Y48800D02*
X1731420Y49880D01*
G01X1732500Y45700D02*
Y48800D01*
G01X1733500Y44700D02*
X1732500Y45700D01*
G01X1736600Y44700D02*
X1733500D01*
G01X1769949Y55500D02*
X1779258D01*
G01X1766333Y59116D02*
X1769949Y55500D01*
G01X1743600Y43099D02*
Y43900D01*
G01X1743001Y42500D02*
X1743600Y43099D01*
G01Y46100D02*
Y43900D01*
G01X1742594Y47106D02*
X1743600Y46100D01*
G01X1733965Y89220D02*
X1731280D01*
G01X1735150Y88035D02*
X1733965Y89220D01*
G01X1735150Y78450D02*
Y88035D01*
G01X1729540Y79500D02*
X1723500D01*
G01X1731960Y81920D02*
X1729540Y79500D01*
G01X1731960Y83830D02*
Y81920D01*
G01Y84940D02*
Y83830D01*
G01X1730430Y86470D02*
X1731960Y84940D01*
G01X1730430Y88795D02*
Y86470D01*
G01X1730855Y89220D02*
X1730430Y88795D01*
G01X1731280Y89220D02*
X1730855D01*
G01X1726562Y95605D02*
G02X1720287Y93006I-6275J6275D01*
G01X1770250Y89500D02*
X1767250D01*
G01X1762373Y87674D02*
X1760379D01*
G01X1764199Y89500D02*
X1762373Y87674D01*
G01X1767250Y89500D02*
X1764199D01*
G01X1748279Y149836D02*
Y151165D01*
G01X1748550Y149565D02*
X1748279Y149836D01*
G01X1748550Y148138D02*
Y149565D01*
G01X1747854Y153250D02*
X1746189D01*
G01X1748279Y152825D02*
X1747854Y153250D01*
G01X1748279Y151165D02*
Y152825D01*
G01X1745162Y148138D02*
X1748550D01*
G01X1744600Y148700D02*
X1745162Y148138D01*
G01X1744600Y150900D02*
Y148700D01*
G01X1739514Y150450D02*
Y156490D01*
G01X1737589Y150450D02*
G03X1739514I962J0D01*
G01X1737589Y155050D02*
Y150450D01*
G01X1735663Y155050D02*
G02X1737589I963J0D01*
G01X1735663Y149376D02*
Y155050D01*
G01X1735989Y149050D02*
X1735663Y149376D01*
G01X1751189Y120950D02*
Y123542D01*
G01X1752589Y119550D02*
X1751189Y120950D01*
G01X1755389Y119550D02*
X1752589D01*
G01X1757639Y121800D02*
X1755389Y119550D01*
G01X1760439Y121800D02*
X1757639D01*
G01X1761189Y122550D02*
X1760439Y121800D01*
G01X1761189Y124050D02*
Y122550D01*
G01X1759158Y126081D02*
X1761189Y124050D01*
G01X1759158Y127750D02*
Y126081D01*
G01X1764220Y127750D02*
X1759158D01*
G01X1740664Y125300D02*
X1739064Y126900D01*
G01X1743639Y125300D02*
X1740664D01*
G01X1745589Y127250D02*
X1743639Y125300D01*
G01X1749889Y127250D02*
X1745589D01*
G01X1751189Y125950D02*
X1749889Y127250D01*
G01X1751189Y123542D02*
Y125950D01*
G01X1773750Y96250D02*
Y94500D01*
G01X1773000Y97000D02*
X1773750Y96250D01*
G01X1764900Y97000D02*
X1773000D01*
G01X1770250Y94500D02*
X1767250D01*
G01D02*
X1761880D01*
G01X1725196Y97282D02*
X1735914Y108000D01*
G01X1719811Y95051D02*
G03X1725196Y97282I-1J7616D01*
G01X1729189Y151550D02*
Y150153D01*
G01X1728389Y152350D02*
X1729189Y151550D01*
G01X1726089Y152350D02*
X1728389D01*
G01X1722539Y155900D02*
X1726089Y152350D01*
G01X1722539Y157150D02*
Y155900D01*
G01X1723714Y142250D02*
X1723314Y142650D01*
G01X1726689Y142250D02*
X1723714D01*
G01X1729189Y144750D02*
X1726689Y142250D01*
G01X1729189Y150153D02*
Y144750D01*
G01X1717297Y109600D02*
G02X1715253Y110447I0J2890D01*
G01X1727490Y109600D02*
X1717297D01*
G01X1727490Y107674D02*
G03Y109600I0J963D01*
G01X1725579Y107674D02*
X1727490D01*
G01X1725579Y105748D02*
G02Y107674I0J963D01*
G01X1728416Y105748D02*
X1725579D01*
G01X1728416Y103822D02*
G03Y105748I0J963D01*
G01X1723962Y103822D02*
X1728416D01*
G01X1723314Y104470D02*
G03X1723962Y103822I648J0D01*
G01X1723314Y104850D02*
Y104470D01*
G01X1724475Y149025D02*
X1717117Y156383D01*
G01X1726464Y145800D02*
G03X1724475Y149025I-7797J-2583D01*
G01X1722595Y138781D02*
X1723314Y139500D01*
G01X1720589Y137950D02*
G03X1722595Y138781I0J2837D01*
G01X1716840Y137950D02*
X1720589D01*
G01X1716094Y138259D02*
G03X1716840Y137950I746J746D01*
G01X1724864Y141050D02*
X1723314Y139500D01*
G01X1726989Y141050D02*
X1724864D01*
G01X1730689Y144750D02*
X1726989Y141050D01*
G01X1730689Y152550D02*
Y144750D01*
G01X1729289Y153950D02*
X1730689Y152550D01*
G01X1727689Y153950D02*
X1729289D01*
G01X1727189Y154450D02*
X1727689Y153950D01*
G01X1727189Y156338D02*
Y154450D01*
G01X1740889Y155450D02*
Y151176D01*
G01X1741489Y156050D02*
X1740889Y155450D01*
G01X1743989Y156050D02*
X1741489D01*
G01X1745589Y157650D02*
X1743989Y156050D01*
G01X1736289Y142750D02*
X1734989D01*
G01X1736989Y143450D02*
X1736289Y142750D01*
G01X1736989Y144350D02*
Y143450D01*
G01X1735689Y145650D02*
X1736989Y144350D01*
G01X1735689Y146450D02*
Y145650D01*
G01X1736189Y146950D02*
X1735689Y146450D01*
G01X1737489Y146950D02*
X1736189D01*
G01X1738389Y147850D02*
X1737489Y146950D01*
G01X1740389Y147850D02*
X1738389D01*
G01X1740889Y148350D02*
X1740389Y147850D01*
G01X1740889Y151176D02*
Y148350D01*
G01X1714712Y122938D02*
G03X1714041Y123216I-671J-671D01*
G01X1718211Y119439D02*
X1714712Y122938D01*
G01X1719150Y119050D02*
G02X1718211Y119439I0J1328D01*
G01X1723858Y119050D02*
X1719150D01*
G01X1724256Y119215D02*
G02X1723858Y119050I-398J398D01*
G01X1723681Y120601D02*
G02X1724256Y119215I1J-812D01*
G01X1723314Y120601D02*
X1723681D01*
G01X1717950Y124227D02*
G03X1716777Y125400I-1173J0D01*
G01X1717950Y122976D02*
Y124227D01*
G01X1718776Y122150D02*
G02X1717950Y122976I0J826D01*
G01X1726441Y122150D02*
X1718776D01*
G01X1726902Y121037D02*
G03X1726441Y122150I-461J461D01*
G01X1726464Y120600D02*
X1726902Y121037D01*
G01X1716202Y154772D02*
X1716228D01*
G01X1719900Y151100D02*
X1716228Y154772D01*
G01X1720915Y148650D02*
G03X1719900Y151100I-3466J0D01*
G01X1720915Y147613D02*
Y148650D01*
G01X1720164Y145800D02*
G03X1720915Y147613I-1814J1813D01*
G01X1726464Y133121D02*
Y133200D01*
G01X1725119Y131776D02*
X1726464Y133121D01*
G01X1724815Y131650D02*
G03X1725119Y131776I0J430D01*
G01X1716449Y131650D02*
X1724815D01*
G01X1715000Y132250D02*
G03X1716449Y131650I1449J1449D01*
G01X1714027Y132653D02*
G02X1715000Y132250I0J-1376D01*
G01X1713322Y132653D02*
X1714027D01*
G01X1720889Y155250D02*
Y164962D01*
G01X1728189Y147950D02*
X1720889Y155250D01*
G01X1728189Y145250D02*
Y147950D01*
G01X1727139Y144200D02*
X1728189Y145250D01*
G01X1722651Y144200D02*
X1727139D01*
G01X1721739Y143288D02*
X1722651Y144200D01*
G01X1721739Y141075D02*
Y143288D01*
G01X1720164Y139500D02*
X1721739Y141075D01*
G01X1717047Y141050D02*
G02X1715893Y141528I0J1632D01*
G01X1719234Y141050D02*
X1717047D01*
G01X1720164Y140120D02*
G03X1719234Y141050I-930J0D01*
G01X1720164Y139500D02*
Y140120D01*
G01X1764220Y136750D02*
X1759158D01*
G01X1749089Y136950D02*
X1750253Y135786D01*
G01X1745089Y136950D02*
X1749089D01*
G01X1744689Y136550D02*
X1745089Y136950D01*
G01X1744689Y135450D02*
Y136550D01*
G01X1742689Y135450D02*
G03X1744689I1000J0D01*
G01X1742689Y136750D02*
Y135450D01*
G01X1742289Y137150D02*
X1742689Y136750D01*
G01X1741189Y137150D02*
X1742289D01*
G01X1740889Y136850D02*
X1741189Y137150D01*
G01X1740889Y135250D02*
Y136850D01*
G01X1740089Y134450D02*
X1740889Y135250D01*
G01X1738689Y134450D02*
X1740089D01*
G01X1736789Y136350D02*
X1738689Y134450D01*
G01X1734789Y136350D02*
X1736789D01*
G01X1734389Y135950D02*
X1734789Y136350D01*
G01X1734389Y133550D02*
Y135950D01*
G01X1734689Y133250D02*
X1734389Y133550D01*
G01X1735989Y133250D02*
X1734689D01*
G01X1759158Y135219D02*
Y136750D01*
G01X1758489Y134550D02*
X1759158Y135219D01*
G01X1751489Y134550D02*
X1758489D01*
G01X1750253Y135786D02*
X1751489Y134550D01*
G01X1727823Y135850D02*
G03X1728789Y136250I0J1366D01*
G01X1714488Y135850D02*
X1727823D01*
G01X1713059Y136442D02*
G03X1714488Y135850I1429J1429D01*
G01X1712880Y136621D02*
X1713059Y136442D01*
G01X1734078Y156050D02*
X1735678Y157650D01*
G01X1734078Y145050D02*
Y156050D01*
G01X1730100Y141072D02*
X1734078Y145050D01*
G01X1730100Y137561D02*
Y141072D01*
G01X1728789Y136250D02*
X1730100Y137561D01*
G01X1717014Y142650D02*
G03X1716663Y143496I-1197J-1D01*
G01X1749089Y155850D02*
X1747654D01*
G01X1752789Y159550D02*
X1749089Y155850D01*
G01X1740664Y144250D02*
X1739064Y142650D01*
G01X1743189Y144250D02*
X1740664D01*
G01X1743789Y144850D02*
X1743189Y144250D01*
G01X1743789Y147050D02*
Y144850D01*
G01X1742589Y148250D02*
X1743789Y147050D01*
G01X1742589Y154050D02*
Y148250D01*
G01X1742989Y154450D02*
X1742589Y154050D01*
G01X1744689Y154450D02*
X1742989D01*
G01X1746089Y155850D02*
X1744689Y154450D01*
G01X1747654Y155850D02*
X1746089D01*
G01X1743789Y133050D02*
X1740779D01*
G01X1744089Y132750D02*
X1743789Y133050D01*
G01X1744089Y129250D02*
Y132750D01*
G01X1744689Y128650D02*
X1744089Y129250D01*
G01X1747389Y128650D02*
X1744689D01*
G01X1748089Y129350D02*
X1747389Y128650D01*
G01X1748089Y133050D02*
Y129350D01*
G01X1748689Y133650D02*
X1748089Y133050D01*
G01X1749689Y133650D02*
X1748689D01*
G01X1750289Y133050D02*
X1749689Y133650D01*
G01X1750289Y130650D02*
Y133050D01*
G01X1750889Y130050D02*
X1750289Y130650D01*
G01X1758689Y130050D02*
X1750889D01*
G01X1759158Y130519D02*
X1758689Y130050D01*
G01X1759158Y132250D02*
Y130519D01*
G01X1764220Y132250D02*
X1759158D01*
G01X1737939Y131175D02*
X1739064Y130050D01*
G01X1737939Y132500D02*
Y131175D01*
G01X1738489Y133050D02*
X1737939Y132500D01*
G01X1740779Y133050D02*
X1738489D01*
G01X1729689Y155710D02*
Y156450D01*
G01X1730449Y154950D02*
X1729689Y155710D01*
G01X1731989Y154950D02*
X1730449D01*
G01X1732589Y154350D02*
X1731989Y154950D01*
G01X1732589Y145150D02*
Y154350D01*
G01X1727700Y140261D02*
X1732589Y145150D01*
G01X1727350Y140261D02*
X1727700D01*
G01X1726539Y139450D02*
X1727350Y140261D01*
G01X1727258Y139450D02*
X1726539D01*
G01X1727579Y139317D02*
G03X1727258Y139450I-321J-321D01*
G01X1727958Y138402D02*
G03X1727579Y139317I-1294J0D01*
G01X1727958Y137906D02*
Y138402D01*
G01X1727102Y137050D02*
G03X1727958Y137906I0J856D01*
G01X1716202Y137050D02*
X1727102D01*
G01X1713324Y138242D02*
G03X1716202Y137050I2878J2878D01*
G01X1748589Y141050D02*
X1747300D01*
G01X1750989Y143450D02*
X1748589Y141050D01*
G01X1750989Y147850D02*
Y143450D01*
G01X1751889Y148750D02*
X1750989Y147850D01*
G01X1756189Y148750D02*
X1751889D01*
G01X1757389Y149950D02*
X1756189Y148750D01*
G01X1757389Y150866D02*
Y149950D01*
G01X1759158Y150866D02*
G03X1757389I-885J0D01*
G01X1759158Y145798D02*
Y150866D01*
G01X1764172Y145798D02*
X1759158D01*
G01X1737464Y141050D02*
X1735914Y139500D01*
G01X1747300Y141050D02*
X1737464D01*
G01X1727799Y96735D02*
G02X1726562Y95605I-13121J13121D01*
G01X1728042Y96978D02*
X1727799Y96735D01*
G01X1728978Y96978D02*
G03X1728042I-468J-468D01*
G01X1729584Y96372D02*
X1728978Y96978D01*
G01X1730946Y97734D02*
G02X1729584Y96372I-681J-681D01*
G01X1730553Y98127D02*
X1730946Y97734D01*
G01X1731915Y99489D02*
G03X1730553Y98127I-681J-681D01*
G01X1732354Y99050D02*
X1731915Y99489D01*
G01X1733716Y100412D02*
G02X1732354Y99050I-681J-681D01*
G01X1733277Y100851D02*
X1733716Y100412D01*
G01X1733277Y102213D02*
G03Y100851I681J-681D01*
G01X1735914Y104850D02*
X1733277Y102213D01*
G01X1716791Y106450D02*
G02X1715951Y106798I0J1188D01*
G01X1720925Y106450D02*
X1716791D01*
G01X1721541Y106195D02*
G03X1720925Y106450I-616J-616D01*
G01X1721738Y105719D02*
G03X1721541Y106195I-673J0D01*
G01X1721738Y104171D02*
Y105719D01*
G01X1721476Y103538D02*
G03X1721738Y104171I-633J633D01*
G01X1720695Y103314D02*
G03X1721476Y103538I-1J1475D01*
G01X1719367Y103314D02*
X1720695D01*
G01X1718785Y103896D02*
G03X1719367Y103314I582J0D01*
G01X1718785Y104425D02*
Y103896D01*
G01X1719210Y104850D02*
G03X1718785Y104425I0J-425D01*
G01X1720164Y104850D02*
X1719210D01*
G01X1715557Y134676D02*
X1713211D01*
G01X1716356Y134850D02*
G03X1715557Y134676I-1J-1919D01*
G01X1720989Y134850D02*
X1716356D01*
G01X1722142Y134373D02*
G03X1720989Y134850I-1153J-1155D01*
G01X1723314Y133200D02*
X1722142Y134373D01*
G01X1724821Y134707D02*
X1723314Y133200D01*
G01X1727088Y134707D02*
X1724821D01*
G01X1727245Y134550D02*
X1727088Y134707D01*
G01X1729489Y134550D02*
X1727245D01*
G01X1732889Y137950D02*
X1729489Y134550D01*
G01X1739689Y137950D02*
X1732889D01*
G01X1740689Y138950D02*
X1739689Y137950D01*
G01X1756858Y138950D02*
X1740689D01*
G01X1759158Y141250D02*
X1756858Y138950D01*
G01X1764220Y141250D02*
X1759158D01*
G01X1721875Y145275D02*
G02X1723264Y145850I1389J-1390D01*
G01X1721400Y144800D02*
X1721875Y145275D01*
G01X1720072Y144250D02*
G03X1721400Y144800I0J1878D01*
G01X1720042Y144250D02*
X1720072D01*
G01X1718000Y146292D02*
G03X1720042Y144250I2042J0D01*
G01X1718000Y146293D02*
Y146292D01*
G01X1718500Y147500D02*
G03X1718000Y146293I1207J-1207D01*
G01X1718501Y147501D02*
X1718500Y147500D01*
G01X1718501Y149668D02*
G02Y147501I-1083J-1083D01*
G01X1742489Y157650D02*
X1741419D01*
G01X1743489Y158650D02*
X1742489Y157650D01*
G01X1743489Y165000D02*
Y158650D01*
G01X1742770Y165719D02*
X1743489Y165000D01*
G01X1741189Y165719D02*
X1742770D01*
G01X1741189Y169675D02*
Y165719D01*
G01X1740674Y157650D02*
X1741419D01*
G01X1739514Y156490D02*
X1740674Y157650D01*
G01X1715500Y182500D02*
X1713000Y185000D01*
G01X1783926Y182500D02*
X1715500D01*
G01X1828212Y216287D02*
X1719297D01*
G01X1722839Y157450D02*
X1722539Y157150D01*
G01X1724349Y157450D02*
X1722839D01*
G01X1725489Y158590D02*
X1724349Y157450D01*
G01X1725489Y165011D02*
Y158590D01*
G01X1724781Y165719D02*
X1725489Y165011D01*
G01X1723189Y165719D02*
X1724781D01*
G01X1723189Y169675D02*
Y165719D01*
G01X1725250Y193650D02*
Y191500D01*
G01X1721850Y197050D02*
X1725250Y193650D01*
G01X1721850Y198700D02*
Y197050D01*
G01X1723206Y191500D02*
X1725250D01*
G01X1721000Y193706D02*
X1723206Y191500D01*
G01X1719000Y191706D02*
X1721000Y193706D01*
G01X1719000Y190500D02*
Y191706D01*
G01X1714050Y162694D02*
G03X1713748Y162819I-302J-302D01*
G01X1715802Y160942D02*
X1714050Y162694D01*
G01X1716049Y160346D02*
G03X1715802Y160942I-842J0D01*
G01X1716049Y158962D02*
Y160346D01*
G01X1717117Y156383D02*
G02X1716049Y158962I2580J2579D01*
G01X1729889Y159038D02*
X1727189Y156338D01*
G01X1729889Y165110D02*
Y159038D01*
G01X1729280Y165719D02*
X1729889Y165110D01*
G01X1727689Y165719D02*
X1729280D01*
G01X1727689Y169675D02*
Y165719D01*
G01X1747389Y157650D02*
X1745589D01*
G01X1747989Y158250D02*
X1747389Y157650D01*
G01X1747989Y164850D02*
Y158250D01*
G01X1747120Y165719D02*
X1747989Y164850D01*
G01X1745689Y165719D02*
X1747120D01*
G01X1745689Y169675D02*
Y165719D01*
G01X1714120Y200675D02*
X1712811D01*
G01X1717116Y197679D02*
X1714120Y200675D01*
G01X1717116Y190032D02*
Y197679D01*
G01X1717330Y189818D02*
X1717116Y190032D01*
G01X1717330Y189810D02*
Y189818D01*
G01X1718310Y188830D02*
X1717330Y189810D01*
G01X1719690Y188830D02*
X1718310D01*
G01X1720330Y189470D02*
X1719690Y188830D01*
G01X1841280Y189470D02*
X1720330D01*
G01X1718689Y169675D02*
Y165719D01*
G01X1720132D02*
X1718689D01*
G01X1720889Y164962D02*
X1720132Y165719D01*
G01X1738434D02*
X1736689D01*
G01X1738989Y165164D02*
X1738434Y165719D01*
G01X1738989Y158890D02*
Y165164D01*
G01X1737749Y157650D02*
X1738989Y158890D01*
G01X1735678Y157650D02*
X1737749D01*
G01X1736689Y169675D02*
Y165719D01*
G01X1752789Y165000D02*
Y159550D01*
G01X1752070Y165719D02*
X1752789Y165000D01*
G01X1750189Y165719D02*
X1752070D01*
G01X1750189Y169675D02*
Y165719D01*
G01X1717212Y217213D02*
X1829507D01*
G01X1713137Y213138D02*
X1717212Y217213D01*
G01X1733881Y165719D02*
X1732189D01*
G01X1734389Y165211D02*
X1733881Y165719D01*
G01X1734389Y159138D02*
Y165211D01*
G01X1732551Y157300D02*
X1734389Y159138D01*
G01X1730539Y157300D02*
X1732551D01*
G01X1729689Y156450D02*
X1730539Y157300D01*
G01X1732189Y169675D02*
Y165719D01*
G01X1717406Y187250D02*
X1839000D01*
G01X1716191Y188465D02*
X1717406Y187250D01*
G01X1716191Y197295D02*
Y188465D01*
G01X1713736Y199750D02*
X1716191Y197295D01*
G01X1714443Y188526D02*
X1713839D01*
G01X1717069Y185900D02*
X1714443Y188526D01*
G01X1824224Y185900D02*
X1717069D01*
G01X1716364Y184200D02*
X1819750D01*
G01X1713751Y186813D02*
X1716364Y184200D01*
G01X1712951Y186813D02*
X1713751D01*
G01X1753304Y243400D02*
X1746900Y249804D01*
G01X1755900Y243400D02*
X1753304D01*
G01X1720766Y265225D02*
X1800382D01*
G01X1715078Y259537D02*
X1720766Y265225D01*
G01X1715078Y250231D02*
Y259537D01*
G01X1830098Y218638D02*
X1715837D01*
G01X1738460Y228410D02*
X1738430Y228440D01*
G01X1742420Y228410D02*
X1738460D01*
G01X1742420Y234659D02*
X1742398Y234681D01*
G01X1742420Y228410D02*
Y234659D01*
G01X1721834Y262375D02*
X1800025D01*
G01X1718820Y259361D02*
X1721834Y262375D01*
G01X1718820Y249032D02*
Y259361D01*
G01X1834672Y222000D02*
X1713882D01*
G01X1835493Y219463D02*
X1715495D01*
G01X1719053Y239800D02*
X1794227D01*
G01X1716083Y236830D02*
X1719053Y239800D01*
G01X1716083Y226819D02*
Y236830D01*
G01X1718638Y240800D02*
X1798820D01*
G01X1715043Y237205D02*
X1718638Y240800D01*
G01X1715043Y227143D02*
Y237205D01*
G01X1712941Y245337D02*
Y248576D01*
G01X1714805Y243473D02*
X1712941Y245337D01*
G01X1725194Y243473D02*
X1714805D01*
G01X1727896Y246175D02*
X1725194Y243473D01*
G01X1719080Y228611D02*
X1719132Y228559D01*
G01X1719080Y232852D02*
Y228611D01*
G01X1713866Y245721D02*
Y249091D01*
G01X1715155Y244432D02*
X1713866Y245721D01*
G01X1718942Y244432D02*
X1715155D01*
G01X1720651Y246141D02*
X1718942Y244432D01*
G01X1751900Y247300D02*
Y249700D01*
G01X1752800Y246400D02*
X1751900Y247300D01*
G01X1755900Y246400D02*
X1752800D01*
G01X1736543Y444400D02*
X1839201D01*
G01X1730550Y450393D02*
X1736543Y444400D01*
G01X1730550Y470702D02*
Y450393D01*
G01X1721493Y436302D02*
X1844402D01*
G01X1717571Y440224D02*
X1721493Y436302D01*
G01X1717571Y443534D02*
Y440224D01*
G01X1718587Y444550D02*
X1717571Y443534D01*
G01X1718900Y444863D02*
X1718587Y444550D01*
G01X1718900Y448000D02*
Y444863D01*
G01X1736154Y443462D02*
X1839862D01*
G01X1729625Y449991D02*
X1736154Y443462D01*
G01X1729625Y453821D02*
Y449991D01*
G01X1726186Y457260D02*
X1729625Y453821D01*
G01X1718436Y457260D02*
X1726186D01*
G01X1714169Y452993D02*
X1718436Y457260D01*
G01X1714169Y446343D02*
Y452993D01*
G01X1713449Y445623D02*
X1714169Y446343D01*
G01X1713449Y443477D02*
Y445623D01*
G01X1714374Y445239D02*
Y443093D01*
G01X1715094Y445959D02*
X1714374Y445239D01*
G01X1715094Y452609D02*
Y445959D01*
G01X1718820Y456335D02*
X1715094Y452609D01*
G01X1725802Y456335D02*
X1718820D01*
G01X1728700Y453437D02*
X1725802Y456335D01*
G01X1728700Y451143D02*
Y453437D01*
G01X1728699Y451142D02*
X1728700Y451143D01*
G01X1728699Y449608D02*
Y451142D01*
G01X1735770Y442537D02*
X1728699Y449608D01*
G01X1840246Y442537D02*
X1735770D01*
G01X1725794Y437727D02*
X1843811D01*
G01X1721990Y441531D02*
X1725794Y437727D01*
G01X1721990Y444521D02*
Y441531D01*
G01X1716730Y445243D02*
X1716037Y444550D01*
G01X1716730Y448947D02*
Y445243D01*
G01X1718230Y450447D02*
X1716730Y448947D01*
G01X1718230Y452955D02*
Y450447D01*
G01X1720902Y434877D02*
X1845877D01*
G01X1716037Y439742D02*
X1720902Y434877D01*
G01X1716037Y444550D02*
Y439742D01*
G01X1766790Y446238D02*
X1803310D01*
G01X1766789Y446237D02*
X1766790Y446238D01*
G01X1765411Y446237D02*
X1766789D01*
G01X1765410Y446238D02*
X1765411Y446237D01*
G01X1737305Y446238D02*
X1765410D01*
G01X1732536Y451007D02*
X1737305Y446238D01*
G01X1732536Y472798D02*
Y451007D01*
G01X1727999Y441112D02*
X1844065D01*
G01X1724590Y444521D02*
X1727999Y441112D01*
G01X1715729Y475464D02*
X1719089Y472104D01*
G01X1765500Y506800D02*
X1759900D01*
G01X1766600Y505700D02*
X1765500Y506800D01*
G01X1768200Y505700D02*
X1766600D01*
G01X1769755D02*
X1776695Y512640D01*
G01X1768200Y505700D02*
X1769755D01*
G01X1723438Y477814D02*
X1730550Y470702D01*
G01X1765000Y518800D02*
Y517000D01*
G01X1762715Y521085D02*
X1765000Y518800D01*
G01X1764000Y517000D02*
X1765000D01*
G01X1762700Y515700D02*
X1764000Y517000D01*
G01X1762700Y512700D02*
Y515700D01*
G01X1761918Y511918D02*
X1762700Y512700D01*
G01X1759900Y511918D02*
X1761918D01*
G01X1728399Y506800D02*
X1752900D01*
G01X1715489Y493890D02*
X1728399Y506800D01*
G01X1712354Y490755D02*
X1715489Y493890D01*
G01X1723000Y521500D02*
Y555500D01*
G01X1719500Y518000D02*
X1723000Y521500D01*
G01X1773900Y507300D02*
X1778200Y511600D01*
G01X1771502Y501944D02*
X1773900Y504342D01*
G01X1725684Y479650D02*
X1732536Y472798D01*
G01X1722011Y476889D02*
X1728700Y470200D01*
G01X1752900Y514000D02*
Y511918D01*
G01X1750800Y516100D02*
X1752900Y514000D01*
G01X1765300Y560809D02*
X1762519D01*
G01X1766309Y559800D02*
X1765300Y560809D01*
G01X1767500Y559800D02*
X1766309D01*
G01X1774800Y581900D02*
X1772500D01*
G01X1733950Y581100D02*
Y582504D01*
G01X1733368Y580518D02*
X1733950Y581100D01*
G01X1733368Y579868D02*
Y580518D01*
G01X1737760Y581700D02*
X1738500D01*
G01X1735928Y579868D02*
X1737760Y581700D01*
G01X1733368Y579868D02*
X1735928D01*
G01X1739069Y581131D02*
X1738500Y581700D01*
G01X1739069Y576869D02*
Y581131D01*
G01X1738114Y575914D02*
X1739069Y576869D01*
G01X1733369Y575914D02*
X1738114D01*
G01X1754448Y571552D02*
Y569942D01*
G01X1753500Y572500D02*
X1754448Y571552D01*
G01X1751500Y572500D02*
X1753500D01*
G01X1749000Y570000D02*
X1751500Y572500D01*
G01X1743000Y570000D02*
X1749000D01*
G01X1760354Y573354D02*
Y569942D01*
G01X1761300Y574300D02*
X1760354Y573354D01*
G01X1764900Y574300D02*
X1761300D01*
G01X1765300Y574700D02*
X1764900Y574300D01*
G01X1772550Y588100D02*
Y585000D01*
G01X1772850Y588400D02*
X1772550Y588100D01*
G01X1765250Y570900D02*
X1764300D01*
G01X1766225Y569925D02*
X1765250Y570900D01*
G01X1771530Y569925D02*
X1766225D01*
G01X1773300Y571695D02*
X1771530Y569925D01*
G01X1758386Y572998D02*
Y569942D01*
G01X1756584Y574800D02*
X1758386Y572998D01*
G01X1747700Y574800D02*
X1756584D01*
G01X1746000Y576500D02*
X1747700Y574800D01*
G01X1741025Y576500D02*
X1746000D01*
G01X1740037Y575512D02*
X1741025Y576500D01*
G01X1740037Y567563D02*
Y575512D01*
G01X1740437Y567163D02*
X1740037Y567563D01*
G01X1740437Y566155D02*
Y567163D01*
G01X1741500Y565092D02*
X1740437Y566155D01*
G01X1741500Y563300D02*
Y565092D01*
G01X1743100Y561700D02*
X1741500Y563300D01*
G01X1728254Y569254D02*
Y565314D01*
G01X1725694Y571814D02*
X1728254Y569254D01*
G01X1726850Y559000D02*
X1723000D01*
G01X1728254Y562754D02*
Y565314D01*
G01X1726850Y561350D02*
X1728254Y562754D01*
G01X1726850Y559000D02*
Y561350D01*
G01X1768979Y567650D02*
X1767529Y566200D01*
G01X1773300Y567650D02*
X1768979D01*
G01X1744400Y568500D02*
X1743200Y567300D01*
G01X1749800Y568500D02*
X1744400D01*
G01X1751242Y569942D02*
X1749800Y568500D01*
G01X1752480Y569942D02*
X1751242D01*
G01X1760354Y556146D02*
Y557738D01*
G01X1761500Y555000D02*
X1760354Y556146D01*
G01X1761500Y551941D02*
Y555000D01*
G01X1759559Y550000D02*
X1761500Y551941D01*
G01X1752500Y550000D02*
X1759559D01*
G01X1751500Y551000D02*
X1752500Y550000D01*
G01X1738088Y551000D02*
X1751500D01*
G01X1740009Y559200D02*
X1738697Y557888D01*
G01X1741200Y559200D02*
X1740009D01*
G01X1756417Y554583D02*
X1756500Y554500D01*
G01X1756417Y557738D02*
Y554583D01*
G01X1741200Y560700D02*
Y559200D01*
G01X1738600Y563300D02*
X1741200Y560700D01*
G01X1738600Y565100D02*
Y563300D01*
G01X1772750Y578650D02*
X1772500Y578900D01*
G01X1776200Y578650D02*
X1772750D01*
G01X1745793Y566793D02*
X1750315D01*
G01X1743500Y564500D02*
X1745793Y566793D01*
G01X1758386Y555614D02*
X1759500Y554500D01*
G01X1758386Y557738D02*
Y555614D01*
G01X1759500Y553056D02*
Y554500D01*
G01X1757944Y551500D02*
X1759500Y553056D01*
G01X1752905Y551500D02*
X1757944D01*
G01X1752133Y552272D02*
X1752905Y551500D01*
G01X1752133Y555135D02*
Y552272D01*
G01X1752480Y555482D02*
X1752133Y555135D01*
G01X1752480Y557738D02*
Y555482D01*
G01X1756417Y572082D02*
Y569942D01*
G01X1755084Y573415D02*
X1756417Y572082D01*
G01X1754085Y573415D02*
X1755084D01*
G01X1754000Y573500D02*
X1754085Y573415D01*
G01X1751000Y573500D02*
X1754000D01*
G01X1748500Y571000D02*
X1751000Y573500D01*
G01X1746500Y571000D02*
X1748500D01*
G01X1744801Y572699D02*
X1746500Y571000D01*
G01X1741925Y572699D02*
X1744801D01*
G01X1741137Y571911D02*
X1741925Y572699D01*
G01X1741137Y568163D02*
Y571911D01*
G01X1741537Y567763D02*
X1741137Y568163D01*
G01X1741537Y566611D02*
Y567763D01*
G01X1742624Y565524D02*
X1741537Y566611D01*
G01X1742624Y565376D02*
Y565524D01*
G01X1743500Y564500D02*
X1742624Y565376D01*
G01X1725694Y565314D02*
Y568814D01*
G01X1730950Y580136D02*
X1730774Y579960D01*
G01X1730950Y582500D02*
Y580136D01*
G01X1730814Y579920D02*
X1730774Y579960D01*
G01X1730814Y575914D02*
Y579920D01*
G01X1725694Y580834D02*
Y575914D01*
G01X1723186Y583342D02*
X1725694Y580834D01*
G01X1723186Y585387D02*
Y583342D01*
G01X1724299Y586500D02*
X1723186Y585387D01*
G01X1725095Y586500D02*
X1724299D01*
G01X1727937Y589342D02*
X1725095Y586500D01*
G01X1747900Y578251D02*
X1746292D01*
G01X1748561Y578912D02*
X1747900Y578251D01*
G01X1750792Y578912D02*
X1748561D01*
G01X1754735D02*
X1754897Y578750D01*
G01X1750792Y578912D02*
X1754735D01*
G01X1720582Y533025D02*
X1715788Y528231D01*
G01X1720582Y542900D02*
Y533025D01*
G01X1718150Y545332D02*
X1720582Y542900D01*
G01X1718150Y559650D02*
Y545332D01*
G01X1715671Y562129D02*
X1718150Y559650D01*
G01X1715671Y584111D02*
Y562129D01*
G01X1713513Y586269D02*
X1715671Y584111D01*
G01X1713513Y592184D02*
Y586269D01*
G01X1759067Y583878D02*
Y586743D01*
G01X1757792Y582603D02*
X1759067Y583878D01*
G01X1757792Y581471D02*
Y582603D01*
G01X1763209Y586743D02*
X1759067D01*
G01X1765016Y588550D02*
X1763209Y586743D01*
G01X1719200Y530193D02*
X1716213Y527206D01*
G01X1719200Y530334D02*
Y530193D01*
G01X1721507Y532641D02*
X1719200Y530334D01*
G01X1721507Y543284D02*
Y532641D01*
G01X1719200Y545591D02*
X1721507Y543284D01*
G01X1719200Y560050D02*
Y545591D01*
G01X1716596Y562654D02*
X1719200Y560050D01*
G01X1716596Y584531D02*
Y562654D01*
G01X1714475Y586652D02*
X1716596Y584531D01*
G01X1714475Y616207D02*
Y586652D01*
G01X1754448Y553948D02*
X1754000Y553500D01*
G01X1754448Y557738D02*
Y553948D01*
G01X1729610Y613582D02*
X1735000D01*
G01X1728341Y614851D02*
X1729610Y613582D01*
G01X1772500Y591100D02*
X1777551D01*
G01X1739400Y618700D02*
X1742000D01*
G01X1737498Y616798D02*
X1739400Y618700D01*
G01X1727035Y616798D02*
X1737498D01*
G01X1725133Y614896D02*
X1727035Y616798D01*
G01X1775900Y588400D02*
X1772850D01*
G01X1757319Y610581D02*
X1754300Y613600D01*
G01X1757319Y606953D02*
Y610581D01*
G01Y606758D02*
Y606953D01*
G01X1753625Y603064D02*
X1757319Y606758D01*
G01X1753625Y598775D02*
Y603064D01*
G01X1754108Y598292D02*
X1753625Y598775D01*
G01X1757057Y598292D02*
X1754108D01*
G01X1756508Y596151D02*
Y593743D01*
G01X1757057Y596700D02*
X1756508Y596151D01*
G01X1757057Y598292D02*
Y596700D01*
G01X1771650Y599750D02*
X1774900D01*
G01X1770600Y600800D02*
X1771650Y599750D01*
G01X1756241Y616159D02*
X1754300D01*
G01X1757900Y614500D02*
X1756241Y616159D01*
G01X1757900Y612500D02*
Y614500D01*
G01X1762700Y607700D02*
X1757900Y612500D01*
G01X1767100Y607700D02*
X1762700D01*
G01X1769900Y604900D02*
X1767100Y607700D01*
G01X1769900Y601500D02*
Y604900D01*
G01X1770600Y600800D02*
X1769900Y601500D01*
G01X1750259Y616159D02*
X1754300D01*
G01X1748100Y614000D02*
X1750259Y616159D01*
G01X1748100Y607000D02*
Y614000D01*
G01X1766400Y596000D02*
Y599400D01*
G01X1742000Y593700D02*
X1744700D01*
G01X1740370Y592070D02*
X1742000Y593700D01*
G01X1739179Y592070D02*
X1740370D01*
G01X1719363Y600400D02*
X1716438D01*
G01X1721808Y597955D02*
X1719363Y600400D01*
G01X1715900Y599862D02*
X1716438Y600400D01*
G01X1715900Y595601D02*
Y599862D01*
G01X1716817Y594684D02*
X1715900Y595601D01*
G01X1718037Y594684D02*
X1716817D01*
G01X1760722Y618718D02*
X1761300D01*
G01X1757940Y621500D02*
X1760722Y618718D01*
G01X1750250Y621500D02*
X1757940D01*
G01X1744891Y616141D02*
X1750250Y621500D01*
G01X1742000Y616141D02*
X1744891D01*
G01X1761300Y618718D02*
X1764912D01*
G01X1728537Y589342D02*
X1727937D01*
G01X1738116Y593359D02*
X1736097D01*
G01X1739176Y594419D02*
X1738116Y593359D01*
G01X1740270Y594419D02*
X1739176D01*
G01X1734124Y589342D02*
X1728537D01*
G01X1736097Y591315D02*
X1734124Y589342D01*
G01X1736097Y593359D02*
Y591315D01*
G01X1713450Y592247D02*
X1713513Y592184D01*
G01X1713450Y615782D02*
Y592247D01*
G01X1765016Y591116D02*
Y588550D01*
G01X1767500Y593600D02*
X1765016Y591116D01*
G01X1777400Y593600D02*
X1767500D01*
G01X1719813Y603450D02*
X1716950D01*
G01X1721808Y601455D02*
X1719813Y603450D01*
G01X1799504Y1603D02*
Y-5000D01*
G01X1793720Y7387D02*
X1799504Y1603D01*
G01X1779568Y18168D02*
X1780915D01*
G01X1777685Y16285D02*
X1779568Y18168D01*
G01X1777685Y12830D02*
Y16285D01*
G01X1814536Y-10032D02*
X1819504Y-15000D01*
G01X1786832Y-10032D02*
X1814536D01*
G01X1785408Y-8608D02*
X1786832Y-10032D01*
G01X1785408Y-108D02*
Y-8608D01*
G01X1777685Y7615D02*
X1785408Y-108D01*
G01X1777685Y12830D02*
Y7615D01*
G01X1824858Y-9504D02*
X1828874Y-13520D01*
G01X1816505Y-9504D02*
X1824858D01*
G01X1814301Y-7300D02*
X1816505Y-9504D01*
G01X1814301Y-4201D02*
Y-7300D01*
G01X1807100Y3000D02*
X1814301Y-4201D01*
G01X1801200Y3000D02*
X1807100D01*
G01X1797000Y7200D02*
X1801200Y3000D01*
G01X1797000Y16600D02*
Y7200D01*
G01X1779504Y-16356D02*
Y-15000D01*
G01X1774853Y-21007D02*
X1779504Y-16356D01*
G01X1822400Y28200D02*
Y33300D01*
G01X1777600Y21700D02*
X1778700D01*
G01X1775000Y19100D02*
X1777600Y21700D01*
G01X1775000Y13400D02*
Y19100D01*
G01X1774600Y13000D02*
X1775000Y13400D01*
G01X1774600Y8800D02*
Y13000D01*
G01X1783627Y-9123D02*
X1789504Y-15000D01*
G01X1783627Y-1843D02*
Y-9123D01*
G01X1774600Y7184D02*
X1783627Y-1843D01*
G01X1774600Y8800D02*
Y7184D01*
G01X1807149Y31700D02*
X1801488Y37361D01*
G01X1810500Y31700D02*
X1807149D01*
G01X1813235Y28965D02*
X1810500Y31700D01*
G01X1813235Y28641D02*
Y28965D01*
G01X1813250Y28626D02*
X1813235Y28641D01*
G01X1813250Y20550D02*
Y28626D01*
G01X1814550Y19250D02*
X1813250Y20550D01*
G01X1819083Y19250D02*
X1814550D01*
G01X1823525Y14808D02*
X1819083Y19250D01*
G01X1823525Y12788D02*
Y14808D01*
G01X1828013Y8300D02*
X1823525Y12788D01*
G01X1833700Y8300D02*
X1828013D01*
G01X1836800Y11400D02*
X1833700Y8300D01*
G01X1834600Y8000D02*
X1838700D01*
G01X1834000Y7400D02*
X1834600Y8000D01*
G01X1827700Y7400D02*
X1834000D01*
G01X1822700Y12400D02*
X1827700Y7400D01*
G01X1822600Y12400D02*
X1822700D01*
G01X1822600Y13100D02*
Y12400D01*
G01X1822700Y13200D02*
X1822600Y13100D01*
G01X1822700Y14466D02*
Y13200D01*
G01X1818741Y18425D02*
X1822700Y14466D01*
G01X1814994Y18425D02*
X1818741D01*
G01X1814993Y18424D02*
X1814994Y18425D01*
G01X1813661Y18424D02*
X1814993D01*
G01X1812425Y19660D02*
X1813661Y18424D01*
G01X1812425Y28284D02*
Y19660D01*
G01X1812410Y28299D02*
X1812425Y28284D01*
G01X1812410Y28623D02*
Y28299D01*
G01X1810223Y30810D02*
X1812410Y28623D01*
G01X1806510Y30810D02*
X1810223D01*
G01X1789327Y47993D02*
X1806510Y30810D01*
G01X1774372Y-10132D02*
Y-1040D01*
G01X1819837Y23837D02*
Y21700D01*
G01X1820700Y24700D02*
X1819837Y23837D01*
G01X1822400Y24700D02*
X1820700D01*
G01X1789504Y996D02*
Y-5000D01*
G01X1782900Y7600D02*
X1789504Y996D01*
G01X1782900Y9500D02*
Y7600D01*
G01Y9665D02*
Y9500D01*
G01X1780915Y11650D02*
X1782900Y9665D01*
G01X1780915Y15168D02*
Y11650D01*
G01X1809822Y25685D02*
Y26585D01*
G01X1810000Y25507D02*
X1809822Y25685D01*
G01X1810000Y19269D02*
Y25507D01*
G01X1813469Y15800D02*
X1810000Y19269D01*
G01X1817900Y15800D02*
X1813469D01*
G01X1819600Y14100D02*
X1817900Y15800D01*
G01X1819600Y7900D02*
Y14100D01*
G01X1822138Y5362D02*
X1819600Y7900D01*
G01X1834711Y5362D02*
X1822138D01*
G01X1835324Y5975D02*
X1834711Y5362D01*
G01X1844850Y5975D02*
X1835324D01*
G01X1825700Y21757D02*
Y26250D01*
G01X1825870Y21587D02*
X1825700Y21757D01*
G01X1832842Y13558D02*
Y13500D01*
G01X1832250Y14150D02*
X1832842Y13558D01*
G01X1832250Y17500D02*
Y14150D01*
G01Y17500D02*
X1835250D01*
G01X1835600Y13730D02*
X1836850Y14980D01*
G01X1834900Y6900D02*
X1844400D01*
G01X1834387Y6387D02*
X1834900Y6900D01*
G01X1822613Y6387D02*
X1834387D01*
G01X1820575Y8425D02*
X1822613Y6387D01*
G01X1820575Y14575D02*
Y8425D01*
G01X1818325Y16825D02*
X1820575Y14575D01*
G01X1813894Y16825D02*
X1818325D01*
G01X1811500Y19219D02*
X1813894Y16825D01*
G01X1811500Y27900D02*
Y19219D01*
G01X1810700Y28700D02*
X1811500Y27900D01*
G01X1808909Y28700D02*
X1810700D01*
G01X1807127Y26918D02*
X1808909Y28700D01*
G01X1781967Y84000D02*
X1778000D01*
G01X1785250Y87283D02*
X1781967Y84000D01*
G01X1785250Y106043D02*
Y87283D01*
G01X1776380Y84000D02*
X1778000D01*
G01X1833358Y37420D02*
X1838875D01*
G01X1831653Y35715D02*
X1833358Y37420D01*
G01X1827686Y35715D02*
X1831653D01*
G01X1827457Y35486D02*
X1827686Y35715D01*
G01X1826414Y35486D02*
X1827457D01*
G01X1783468Y63968D02*
X1784341Y64841D01*
G01X1783468Y60039D02*
Y63968D01*
G01X1780929Y57500D02*
X1783468Y60039D01*
G01X1780514Y60550D02*
X1774159D01*
G01X1781768Y61804D02*
X1780514Y60550D01*
G01X1781768Y64832D02*
Y61804D01*
G01X1783590Y66654D02*
X1781768Y64832D01*
G01X1786652Y66654D02*
X1783590D01*
G01X1788137Y68139D02*
X1786652Y66654D01*
G01X1788137Y72805D02*
Y68139D01*
G01X1794078Y78746D02*
X1788137Y72805D01*
G01X1794078Y101453D02*
Y78746D01*
G01X1798454Y81290D02*
Y82256D01*
G01X1797628Y80464D02*
X1798454Y81290D01*
G01X1797628Y77273D02*
Y80464D01*
G01X1791687Y71332D02*
X1797628Y77273D01*
G01X1791687Y66666D02*
Y71332D01*
G01X1789650Y64629D02*
X1791687Y66666D01*
G01X1789650Y60631D02*
Y64629D01*
G01X1788216Y59197D02*
X1789650Y60631D01*
G01X1827100Y84300D02*
Y81600D01*
G01X1825000Y86400D02*
X1827100Y84300D01*
G01X1825000Y91479D02*
Y86400D01*
G01X1823170Y93309D02*
X1825000Y91479D01*
G01X1823170Y104460D02*
Y93309D01*
G01X1800821Y84623D02*
X1801314D01*
G01X1798454Y82256D02*
X1800821Y84623D01*
G01X1835128Y34790D02*
X1837268Y32650D01*
G01X1828070Y34790D02*
X1835128D01*
G01X1827103Y33823D02*
X1828070Y34790D01*
G01X1822923Y33823D02*
X1827103D01*
G01X1822400Y33300D02*
X1822923Y33823D01*
G01X1831559Y38571D02*
X1837694D01*
G01X1831430Y38700D02*
X1831559Y38571D01*
G01X1829500Y38700D02*
X1831430D01*
G01X1829500Y38620D02*
Y38700D01*
G01X1829580Y38620D02*
X1829500D01*
G01X1797460Y50100D02*
X1797840Y49720D01*
G01X1794724Y50100D02*
X1797460D01*
G01X1786432Y58392D02*
X1794724Y50100D01*
G01X1786432Y60181D02*
Y58392D01*
G01X1788178Y61927D02*
X1786432Y60181D01*
G01X1788178Y64466D02*
Y61927D01*
G01X1790762Y67050D02*
X1788178Y64466D01*
G01X1790762Y71716D02*
Y67050D01*
G01X1796703Y77657D02*
X1790762Y71716D01*
G01X1796703Y87139D02*
Y77657D01*
G01X1797787Y88223D02*
X1796703Y87139D01*
G01X1797787Y106773D02*
Y88223D01*
G01X1801488Y46072D02*
X1797840Y49720D01*
G01X1801488Y37361D02*
Y46072D01*
G01X1792378Y79451D02*
Y100492D01*
G01X1785903Y72976D02*
X1792378Y79451D01*
G01X1785903Y69879D02*
Y72976D01*
G01X1775711Y66161D02*
Y67650D01*
G01X1774400Y64850D02*
X1775711Y66161D01*
G01X1774400Y63250D02*
Y64850D01*
G01X1775250Y62400D02*
X1774400Y63250D01*
G01X1777623Y62400D02*
X1775250D01*
G01X1777628Y62395D02*
X1777623Y62400D01*
G01X1784379Y69879D02*
X1785903D01*
G01X1779900Y65400D02*
X1784379Y69879D01*
G01X1778300Y65400D02*
X1779900D01*
G01X1777628Y64728D02*
X1778300Y65400D01*
G01X1777628Y62395D02*
Y64728D01*
G01X1786765Y47993D02*
X1787969D01*
G01X1779258Y55500D02*
X1786765Y47993D01*
G01X1787969D02*
X1789327D01*
G01X1786700Y76550D02*
Y77950D01*
G01X1785650Y75500D02*
X1786700Y76550D01*
G01X1781750Y75500D02*
X1785650D01*
G01X1781750Y71726D02*
X1779903Y69879D01*
G01X1781750Y75500D02*
Y71726D01*
G01X1778205Y69879D02*
X1779903D01*
G01X1777434Y70650D02*
X1778205Y69879D01*
G01X1775711Y70650D02*
X1777434D01*
G01X1785012Y62012D02*
X1786341Y63341D01*
G01X1785012Y57087D02*
Y62012D01*
G01X1797771Y44328D02*
X1785012Y57087D01*
G01X1799438Y44328D02*
X1797771D01*
G01X1786341Y63938D02*
Y63341D01*
G01X1789837Y67434D02*
X1786341Y63938D01*
G01X1789837Y72100D02*
Y67434D01*
G01X1795778Y78041D02*
X1789837Y72100D01*
G01X1795778Y102158D02*
Y78041D01*
G01X1824500Y93900D02*
Y103130D01*
G01X1829000Y89400D02*
X1824500Y93900D01*
G01X1829000Y83800D02*
Y89400D01*
G01X1832500Y80300D02*
X1829000Y83800D01*
G01X1846423Y80300D02*
X1832500D01*
G01X1784912Y138922D02*
Y158000D01*
G01X1789604Y134230D02*
X1784912Y138922D01*
G01X1796482Y134230D02*
X1789604D01*
G01X1797136Y133576D02*
X1796482Y134230D01*
G01X1797136Y129136D02*
Y133576D01*
G01X1795377Y127377D02*
X1797136Y129136D01*
G01X1795377Y126231D02*
Y127377D01*
G01X1800032Y120825D02*
X1785250Y106043D01*
G01X1801543Y120825D02*
X1800032D01*
G01X1802605Y121887D02*
X1801543Y120825D01*
G01X1802605Y123894D02*
Y121887D01*
G01X1800268Y126231D02*
X1802605Y123894D01*
G01X1798377Y126231D02*
X1800268D01*
G01X1798377D02*
X1795377D01*
G01X1792635Y102896D02*
X1794078Y101453D01*
G01X1792635Y107992D02*
Y102896D01*
G01X1802006Y117363D02*
X1792635Y107992D01*
G01X1803863Y117363D02*
X1802006D01*
G01X1809831Y123331D02*
X1803863Y117363D01*
G01X1809831Y125013D02*
Y123331D01*
G01X1809322Y125522D02*
X1809831Y125013D01*
G01X1809322Y129251D02*
Y125522D01*
G01X1808260Y130313D02*
X1809322Y129251D01*
G01X1805787Y130313D02*
X1808260D01*
G01X1803363Y132737D02*
X1805787Y130313D01*
G01X1803363Y137663D02*
Y132737D01*
G01X1806421Y140721D02*
X1803363Y137663D01*
G01X1806421Y143626D02*
Y140721D01*
G01X1808979Y146184D02*
X1806421Y143626D01*
G01X1808979Y148152D02*
Y146184D01*
G01X1807007Y150124D02*
X1808979Y148152D01*
G01X1800476Y150124D02*
X1807007D01*
G01X1796600Y154000D02*
X1800476Y150124D01*
G01X1790100Y154000D02*
X1796600D01*
G01X1824481Y105771D02*
X1823170Y104460D01*
G01X1842522Y105771D02*
X1824481D01*
G01X1802300Y106530D02*
Y104500D01*
G01X1803297Y107527D02*
X1802300Y106530D01*
G01X1815273Y107527D02*
X1803297D01*
G01X1817767Y105033D02*
X1815273Y107527D01*
G01X1817767Y101100D02*
Y105033D01*
G01X1788627Y121442D02*
X1787373Y120188D01*
G01X1788627Y122981D02*
Y121442D01*
G01X1787373Y115127D02*
X1788000Y114500D01*
G01X1787373Y120188D02*
Y115127D01*
G01X1782949Y155900D02*
Y161449D01*
G01X1788000Y129900D02*
Y129000D01*
G01X1784000Y133900D02*
X1788000Y129900D01*
G01X1784000Y138525D02*
Y133900D01*
G01X1783987Y138538D02*
X1784000Y138525D01*
G01X1783987Y153500D02*
Y138538D01*
G01X1782949Y154538D02*
X1783987Y153500D01*
G01X1782949Y155900D02*
Y154538D01*
G01X1803070Y112056D02*
X1797787Y106773D01*
G01X1804456Y112056D02*
X1803070D01*
G01X1805600Y113200D02*
X1804456Y112056D01*
G01X1805600Y115386D02*
Y113200D01*
G01X1812600Y122386D02*
X1805600Y115386D01*
G01X1812600Y124158D02*
Y122386D01*
G01X1816418Y127976D02*
X1812600Y124158D01*
G01X1804721Y144956D02*
X1807166Y147401D01*
G01X1804721Y141611D02*
Y144956D01*
G01X1801663Y138553D02*
X1804721Y141611D01*
G01X1801663Y138368D02*
Y138553D01*
G01X1801662Y138367D02*
X1801663Y138368D01*
G01X1801662Y136959D02*
Y138367D01*
G01X1801663Y136958D02*
X1801662Y136959D01*
G01X1801663Y127241D02*
Y136958D01*
G01X1804305Y124599D02*
X1801663Y127241D01*
G01X1804305Y121182D02*
Y124599D01*
G01X1802186Y119063D02*
X1804305Y121182D01*
G01X1800855Y119063D02*
X1802186D01*
G01X1789646Y107854D02*
X1800855Y119063D01*
G01X1789646Y103224D02*
Y107854D01*
G01X1792378Y100492D02*
X1789646Y103224D01*
G01X1800752Y122731D02*
X1800792Y122691D01*
G01X1798377Y122731D02*
X1800752D01*
G01X1793425Y131481D02*
X1795436D01*
G01X1792908Y130964D02*
X1793425Y131481D01*
G01X1792908Y128508D02*
Y130964D01*
G01X1792127Y127727D02*
X1792908Y128508D01*
G01X1792127Y125981D02*
Y127727D01*
G01Y122981D02*
Y125981D01*
G01X1793569Y122981D02*
X1792127D01*
G01X1793819Y122731D02*
X1793569Y122981D01*
G01X1795377Y122731D02*
X1793819D01*
G01X1792127Y118227D02*
X1792000Y118100D01*
G01X1792127Y122981D02*
Y118227D01*
G01X1794396Y103540D02*
X1795778Y102158D01*
G01X1794396Y107348D02*
Y103540D01*
G01X1802711Y115663D02*
X1794396Y107348D01*
G01X1804568Y115663D02*
X1802711D01*
G01X1811531Y122626D02*
X1804568Y115663D01*
G01X1811531Y125718D02*
Y122626D01*
G01X1811022Y126227D02*
X1811531Y125718D01*
G01X1811022Y129956D02*
Y126227D01*
G01X1808965Y132013D02*
X1811022Y129956D01*
G01X1807187Y132013D02*
X1808965D01*
G01X1805306Y133894D02*
X1807187Y132013D01*
G01X1805306Y137144D02*
Y133894D01*
G01X1809159Y140997D02*
X1805306Y137144D01*
G01X1809159Y143959D02*
Y140997D01*
G01X1810700Y145500D02*
X1809159Y143959D01*
G01X1821059Y145500D02*
X1810700D01*
G01X1824959Y149400D02*
X1821059Y145500D01*
G01X1827780Y149400D02*
X1824959D01*
G01X1828340Y149960D02*
X1827780Y149400D01*
G01X1792877Y142600D02*
Y138481D01*
G01X1785837Y149640D02*
X1792877Y142600D01*
G01X1785837Y155859D02*
Y149640D01*
G01X1788678Y158700D02*
X1785837Y155859D01*
G01X1803335Y153565D02*
X1799426Y157474D01*
G01X1824735Y153565D02*
X1803335D01*
G01X1828340Y149960D02*
X1824735Y153565D01*
G01X1824500Y103130D02*
X1824990Y103620D01*
G01X1800420Y148240D02*
X1797620D01*
G01X1834627Y148050D02*
X1832177Y150500D01*
G01X1839720Y148050D02*
X1834627D01*
G01X1829667Y153010D02*
X1832177Y150500D01*
G01X1828960Y153010D02*
X1829667D01*
G01X1811400Y140600D02*
Y137600D01*
G01Y134800D02*
Y137600D01*
G01X1812923Y133277D02*
X1811400Y134800D01*
G01X1815883Y133277D02*
X1812923D01*
G01X1785330Y181096D02*
X1783926Y182500D01*
G01X1785330Y172559D02*
Y181096D01*
G01X1783500Y170729D02*
X1785330Y172559D01*
G01X1783500Y167000D02*
Y170729D01*
G01X1784500Y166000D02*
X1783500Y167000D01*
G01X1786000Y166000D02*
X1784500D01*
G01X1787500Y164500D02*
X1786000Y166000D01*
G01X1787500Y160588D02*
Y164500D01*
G01X1784912Y158000D02*
X1787500Y160588D01*
G01X1845000Y199499D02*
X1828212Y216287D01*
G01X1817715Y171082D02*
Y172398D01*
G01X1816125Y169492D02*
X1817715Y171082D01*
G01X1842136Y206600D02*
X1830098Y218638D01*
G01X1782949Y161449D02*
X1784023Y162523D01*
G01X1829507Y217213D02*
X1842620Y204100D01*
G01X1792674Y158700D02*
X1788678D01*
G01X1793900Y157474D02*
X1792674Y158700D01*
G01X1799426Y157474D02*
X1793900D01*
G01X1834103Y176021D02*
X1824224Y185900D01*
G01X1788800Y168000D02*
X1785500D01*
G01X1789300Y167500D02*
X1788800Y168000D01*
G01X1789300Y172250D02*
Y171000D01*
G01X1788350Y173200D02*
X1789300Y172250D01*
G01X1787425Y173200D02*
X1788350D01*
G01X1787000Y173625D02*
X1787425Y173200D01*
G01X1787000Y175500D02*
Y173625D01*
G01X1829750Y174200D02*
X1841900D01*
G01X1819750Y184200D02*
X1829750Y174200D01*
G01X1827649Y236034D02*
X1829971Y233712D01*
G01X1826085Y236034D02*
X1827649D01*
G01X1834683Y229000D02*
X1841831D01*
G01X1829971Y233712D02*
X1834683Y229000D01*
G01X1810991Y254616D02*
X1820341D01*
G01X1800382Y265225D02*
X1810991Y254616D01*
G01X1823513Y257788D02*
X1820341Y254616D01*
G01X1832956Y257788D02*
X1823513D01*
G01X1840844Y249900D02*
X1832956Y257788D01*
G01X1824900Y252400D02*
X1824300Y251800D01*
G01X1828900Y252400D02*
X1824900D01*
G01X1831100Y250200D02*
X1828900Y252400D01*
G01X1834300Y250200D02*
X1831100D01*
G01X1834500Y250000D02*
X1834300Y250200D01*
G01X1834500Y247309D02*
Y250000D01*
G01X1835246Y246563D02*
X1834500Y247309D01*
G01X1836713Y246563D02*
X1835246D01*
G01X1834337Y254938D02*
X1836837Y252438D01*
G01X1824838Y254938D02*
X1834337D01*
G01X1822198Y252298D02*
X1824838Y254938D01*
G01X1819325Y252298D02*
X1822198D01*
G01X1818227Y253396D02*
X1819325Y252298D01*
G01X1809004Y253396D02*
X1818227D01*
G01X1806032Y256368D02*
X1809004Y253396D01*
G01X1800025Y262375D02*
X1806032Y256368D01*
G01X1826662Y232191D02*
Y228000D01*
G01X1827462Y227200D02*
X1826662Y228000D01*
G01X1839800Y227200D02*
X1827462D01*
G01X1846134Y210538D02*
X1834672Y222000D01*
G01X1845353Y209603D02*
X1835493Y219463D01*
G01X1794227Y239800D02*
X1795358Y238669D01*
G01X1822300Y240400D02*
X1821100Y239200D01*
G01X1826200Y240400D02*
X1822300D01*
G01X1836525Y230075D02*
X1826200Y240400D01*
G01X1821100Y237629D02*
X1822877Y235852D01*
G01X1821100Y239200D02*
Y237629D01*
G01X1800700Y238920D02*
X1800728D01*
G01X1798820Y240800D02*
X1800700Y238920D01*
G01X1823000Y225800D02*
X1836000D01*
G01X1821600Y227200D02*
X1823000Y225800D01*
G01X1832400Y248100D02*
X1835900Y244600D01*
G01X1828187Y248100D02*
X1832400D01*
G01X1826287Y250000D02*
X1828187Y248100D01*
G01X1804690Y446238D02*
X1838400D01*
G01X1804689Y446237D02*
X1804690Y446238D01*
G01X1803311Y446237D02*
X1804689D01*
G01X1803310Y446238D02*
X1803311Y446237D01*
G01X1806076Y524077D02*
Y523525D01*
G01X1810052Y528053D02*
X1806076Y524077D01*
G01X1806600Y523001D02*
X1809052D01*
G01X1806076Y523525D02*
X1806600Y523001D01*
G01X1806100Y526200D02*
X1808083Y528183D01*
G01X1804500Y526200D02*
X1806100D01*
G01X1810350Y525650D02*
X1812021Y527321D01*
G01X1827600Y507200D02*
X1825000D01*
G01X1828300Y507900D02*
X1827600Y507200D01*
G01X1836400Y507900D02*
X1828300D01*
G01X1817350Y507200D02*
X1825000D01*
G01X1816662Y506512D02*
X1817350Y507200D01*
G01X1811689Y506512D02*
X1816662D01*
G01X1810525Y505348D02*
X1811689Y506512D01*
G01X1810525Y498125D02*
Y505348D01*
G01X1808134Y495734D02*
X1810525Y498125D01*
G01X1803900Y491500D02*
X1808134Y495734D01*
G01X1822900Y517500D02*
X1817950D01*
G01X1824500Y519100D02*
X1822900Y517500D01*
G01X1828100Y519100D02*
X1824500D01*
G01X1828200Y519000D02*
X1828100Y519100D01*
G01X1789300Y509100D02*
Y506600D01*
G01X1790400Y510200D02*
X1789300Y509100D01*
G01X1792400Y510200D02*
X1790400D01*
G01X1794200Y512000D02*
X1792400Y510200D01*
G01X1794200Y514599D02*
Y512000D01*
G01X1798501Y518900D02*
X1794200Y514599D01*
G01X1812900Y518900D02*
X1798501D01*
G01X1814300Y517500D02*
X1812900Y518900D01*
G01X1817950Y517500D02*
X1814300D01*
G01X1807100Y512300D02*
Y510600D01*
G01X1808100Y513300D02*
X1807100Y512300D01*
G01X1810200Y513300D02*
X1808100D01*
G01X1812800Y510600D02*
X1807100D01*
G01X1783300Y519100D02*
X1779300D01*
G01X1783300Y519900D02*
Y519100D01*
G01X1786000Y522600D02*
X1783300Y519900D01*
G01X1809000Y506175D02*
X1809700Y506875D01*
G01X1809000Y504025D02*
Y506175D01*
G01X1808575Y503600D02*
X1809000Y504025D01*
G01X1807100Y503600D02*
X1808575D01*
G01X1807100Y506900D02*
Y503600D01*
G01X1809100Y508900D02*
X1807100Y506900D01*
G01X1810813Y508900D02*
X1809100D01*
G01X1811776Y507937D02*
X1810813Y508900D01*
G01X1813936Y507937D02*
X1811776D01*
G01X1815359Y509360D02*
X1813936Y507937D01*
G01X1815359Y510600D02*
Y509360D01*
G01X1801982Y506118D02*
Y503600D01*
G01X1796153Y511947D02*
X1801982Y506118D01*
G01X1796153Y514200D02*
Y511947D01*
G01X1779300Y511600D02*
Y515600D01*
G01X1781300Y513600D02*
X1784182D01*
G01X1779300Y515600D02*
X1781300Y513600D01*
G01X1778200Y511600D02*
X1779300D01*
G01X1773900Y504342D02*
Y507300D01*
G01X1801982Y512537D02*
X1798883Y515636D01*
G01X1801982Y510600D02*
Y512537D01*
G01X1817918Y502282D02*
Y503600D01*
G01X1819100Y501100D02*
X1817918Y502282D01*
G01X1820400Y501100D02*
X1819100D01*
G01X1821052Y524853D02*
Y523001D01*
G01X1822400Y526201D02*
X1821052Y524853D01*
G01X1822400Y528001D02*
Y526201D01*
G01X1778000Y583900D02*
X1779400Y582500D01*
G01X1776400Y583900D02*
X1778000D01*
G01X1776400Y583500D02*
X1774800Y581900D01*
G01X1776400Y583900D02*
Y583500D01*
G01X1810052Y529899D02*
Y528053D01*
G01X1780150Y567650D02*
X1780500Y568000D01*
G01X1776800Y567650D02*
X1780150D01*
G01X1783400Y570900D02*
X1780500Y568000D01*
G01X1826599Y537501D02*
X1825552D01*
G01X1827785Y536315D02*
X1826599Y537501D01*
G01X1829000Y536315D02*
X1827785D01*
G01X1808083Y528183D02*
Y529899D01*
G01X1801251Y526800D02*
X1803752Y529301D01*
G01X1797800Y526800D02*
X1801251D01*
G01X1796100Y528500D02*
X1797800Y526800D01*
G01X1796100Y537500D02*
Y528500D01*
G01X1797554Y538954D02*
X1796100Y537500D01*
G01X1803950Y538954D02*
X1797554D01*
G01X1812021Y527321D02*
Y529899D01*
G01X1804350D02*
X1806115D01*
G01X1803752Y529301D02*
X1804350Y529899D01*
G01X1810052Y542103D02*
Y545103D01*
G01X1828601Y572501D02*
X1825552D01*
G01X1829000Y572900D02*
X1828601Y572501D01*
G01X1829300Y572900D02*
X1829000D01*
G01X1825552Y572501D02*
X1822052D01*
G01X1789188Y570488D02*
Y568724D01*
G01X1792826Y574126D02*
X1789188Y570488D01*
G01X1792826Y574654D02*
Y574126D01*
G01X1792805Y574675D02*
X1792826Y574654D01*
G01X1816097Y553500D02*
X1816280D01*
G01X1808083Y545486D02*
X1816097Y553500D01*
G01X1808083Y542103D02*
Y545486D01*
G01X1802845Y575130D02*
X1800683Y572968D01*
G01X1809550Y575130D02*
X1802845D01*
G01X1812554Y572126D02*
X1809550Y575130D01*
G01X1812554Y559254D02*
Y572126D01*
G01X1811282Y557982D02*
X1812554Y559254D01*
G01X1808400Y557982D02*
X1811282D01*
G01X1803518D02*
X1802400Y559100D01*
G01X1808400Y557982D02*
X1803518D01*
G01X1798400Y570685D02*
Y562600D01*
G01X1800683Y572968D02*
X1798400Y570685D01*
G01X1782000Y566000D02*
X1781000Y565000D01*
G01X1784650Y566000D02*
X1782000D01*
G01X1778450Y562450D02*
X1781000Y565000D01*
G01X1773900Y562450D02*
X1778450D01*
G01X1821895Y586396D02*
Y588200D01*
G01X1819552Y584053D02*
X1821895Y586396D01*
G01X1819552Y581301D02*
Y584053D01*
G01Y580234D02*
Y581301D01*
G01X1818766Y579448D02*
X1819552Y580234D01*
G01X1814894Y579448D02*
X1818766D01*
G01X1811600Y582742D02*
X1814894Y579448D01*
G01X1811600Y586300D02*
Y582742D01*
G01X1811100Y586800D02*
X1811600Y586300D01*
G01X1835390Y557190D02*
X1834700Y556500D01*
G01X1840690Y557190D02*
X1835390D01*
G01X1834600Y532500D02*
X1837000Y534900D01*
G01X1828600Y532500D02*
X1834600D01*
G01X1781900Y555500D02*
X1774000D01*
G01X1782300Y555900D02*
X1781900Y555500D01*
G01X1831600Y529000D02*
X1828600D01*
G01X1830000Y549500D02*
X1831500Y548000D01*
G01X1826600Y549500D02*
X1830000D01*
G01X1789700Y583700D02*
Y580900D01*
G01X1788300Y585100D02*
X1789700Y583700D01*
G01X1793451Y580900D02*
X1802615Y590064D01*
G01X1789700Y580900D02*
X1793451D01*
G01X1778650Y578650D02*
X1776200D01*
G01X1779500Y579500D02*
X1778650Y578650D01*
G01X1801787Y555713D02*
X1798400Y559100D01*
G01X1809309Y555713D02*
X1801787D01*
G01X1827965Y538588D02*
X1825552Y541001D01*
G01X1830088Y538588D02*
X1827965D01*
G01X1830700Y539200D02*
X1830088Y538588D01*
G01X1831700Y539200D02*
X1830700D01*
G01X1832000Y539500D02*
X1831700Y539200D01*
G01X1832500Y539500D02*
X1832000D01*
G01X1814515Y529899D02*
X1813989D01*
G01X1816521Y527893D02*
X1814515Y529899D01*
G01X1818509Y527893D02*
X1816521D01*
G01X1837213Y579001D02*
X1833052D01*
G01X1816300Y576000D02*
X1816100Y576200D01*
G01X1818500Y576000D02*
X1816300D01*
G01X1813989Y543638D02*
Y542103D01*
G01X1814652Y544301D02*
X1813989Y543638D01*
G01X1814652Y546084D02*
Y544301D01*
G01X1816280Y547712D02*
X1814652Y546084D01*
G01X1816280Y550400D02*
Y547712D01*
G01X1794846Y576754D02*
X1793100Y578500D01*
G01X1810104Y576754D02*
X1794846D01*
G01X1813994Y572864D02*
X1810104Y576754D01*
G01X1813994Y567006D02*
Y572864D01*
G01X1815400Y565600D02*
X1813994Y567006D01*
G01X1817300Y565600D02*
X1815400D01*
G01X1819100Y563800D02*
X1817300Y565600D01*
G01X1819100Y561000D02*
Y563800D01*
G01X1818641Y560541D02*
X1819100Y561000D01*
G01X1815400Y560541D02*
X1818641D01*
G01X1789700Y574700D02*
Y577800D01*
G01X1792400D02*
X1793100Y578500D01*
G01X1789700Y577800D02*
X1792400D01*
G01X1833841Y582501D02*
X1833052D01*
G01X1834694Y583354D02*
X1833841Y582501D01*
G01X1839126Y583354D02*
X1834694D01*
G01X1780500Y574750D02*
X1779950Y575300D01*
G01X1780500Y570718D02*
Y574750D01*
G01X1778500Y575300D02*
X1779950D01*
G01X1776800Y573600D02*
X1778500Y575300D01*
G01X1776800Y571695D02*
Y573600D01*
G01X1795200Y554000D02*
X1794000Y552800D01*
G01X1808300Y554000D02*
X1795200D01*
G01X1809700Y552600D02*
X1808300Y554000D01*
G01X1809700Y550078D02*
Y552600D01*
G01X1809290Y549668D02*
X1809700Y550078D01*
G01X1806115Y546493D02*
Y542103D01*
G01X1809290Y549668D02*
X1806115Y546493D01*
G01X1807521Y584879D02*
Y587899D01*
G01X1809600Y582800D02*
X1807521Y584879D01*
G01X1812021Y544570D02*
X1812952Y545501D01*
G01X1812021Y542103D02*
Y544570D01*
G01X1812952Y547258D02*
Y545501D01*
G01X1814138Y548444D02*
X1812952Y547258D01*
G01X1792000Y583900D02*
X1786450Y589450D01*
G01X1792170Y583900D02*
X1792000D01*
G01X1816154Y530972D02*
Y532970D01*
G01X1816584Y530542D02*
X1816154Y530972D01*
G01X1820149Y530252D02*
X1821441Y528960D01*
G01X1816874Y530252D02*
X1820149D01*
G01X1816584Y530542D02*
X1816874Y530252D01*
G01X1821441Y528960D02*
X1822400Y528001D01*
G01X1801821Y592032D02*
X1804450D01*
G01X1800378Y593475D02*
X1801821Y592032D01*
G01X1800378Y593527D02*
Y593475D01*
G01X1805252Y602852D02*
X1805500Y603100D01*
G01X1805252Y601153D02*
Y602852D01*
G01X1804450Y600351D02*
X1805252Y601153D01*
G01X1804450Y597938D02*
Y600351D01*
G01X1813505Y602705D02*
Y600103D01*
G01X1814483Y603683D02*
X1813505Y602705D01*
G01X1814483Y607717D02*
Y603683D01*
G01X1813700Y608500D02*
X1814483Y607717D01*
G01X1803425Y608500D02*
X1813700D01*
G01X1803000Y608075D02*
X1803425Y608500D01*
G01X1803000Y605600D02*
Y608075D01*
G01X1805500Y603100D02*
X1803000Y605600D01*
G01X1819443Y593803D02*
X1819654D01*
G01X1819245Y594001D02*
X1819443Y593803D01*
G01X1816654Y594001D02*
X1819245D01*
G01X1821349Y595970D02*
X1816654D01*
G01X1822273Y595046D02*
X1821349Y595970D01*
G01X1780924Y592224D02*
X1778675D01*
G01X1781300Y592600D02*
X1780924Y592224D01*
G01X1781600Y592600D02*
X1781300D01*
G01X1777551Y591100D02*
X1778675Y592224D01*
G01X1781800Y588500D02*
X1779000D01*
G01X1778900Y588400D02*
X1775900D01*
G01X1779000Y588500D02*
X1778900Y588400D01*
G01X1827211Y592740D02*
Y597431D01*
G01X1826503Y592032D02*
X1827211Y592740D01*
G01X1816654Y592032D02*
X1826503D01*
G01X1827211Y601482D02*
Y597431D01*
G01X1817193Y611500D02*
X1827211Y601482D01*
G01X1800801Y611500D02*
X1817193D01*
G01X1790167Y600866D02*
X1800801Y611500D01*
G01X1790167Y595186D02*
Y600866D01*
G01X1791323Y594030D02*
X1790167Y595186D01*
G01X1782700Y608400D02*
Y610900D01*
G01X1820586Y590064D02*
X1816654D01*
G01X1821895Y588755D02*
X1820586Y590064D01*
G01X1821895Y588200D02*
Y588755D01*
G01X1803182Y595970D02*
X1804450D01*
G01X1801351Y597801D02*
X1803182Y595970D01*
G01X1797800Y597801D02*
X1801351D01*
G01X1795000Y595001D02*
X1797800Y597801D01*
G01X1795000Y592773D02*
Y595001D01*
G01X1791349Y589122D02*
X1795000Y592773D01*
G01X1782700Y604900D02*
X1785700D01*
G01Y602300D02*
X1787500Y600500D01*
G01X1785700Y604900D02*
Y602300D01*
G01X1787004Y612006D02*
X1788290D01*
G01X1785700Y610702D02*
X1787004Y612006D01*
G01X1785700Y608400D02*
Y610702D01*
G01X1802615Y590064D02*
X1804450D01*
G01X1802452Y594001D02*
X1804450D01*
G01X1800352Y596101D02*
X1802452Y594001D01*
G01X1784200Y596400D02*
X1783200Y597400D01*
G01X1784200Y593924D02*
Y596400D01*
G01X1781200Y597400D02*
X1777400Y593600D01*
G01X1783200Y597400D02*
X1781200D01*
G01X1819250Y600534D02*
X1816654Y597938D01*
G01X1819250Y606551D02*
Y600534D01*
G01X1815876Y609925D02*
X1819250Y606551D01*
G01X1801242Y609925D02*
X1815876D01*
G01X1791600Y600283D02*
X1801242Y609925D01*
G01X1791600Y596105D02*
Y600283D01*
G01X1793115Y594590D02*
X1791600Y596105D01*
G01X1793115Y593212D02*
Y594590D01*
G01X1791581Y591678D02*
X1793115Y593212D01*
G01X1788088Y591678D02*
X1791581D01*
G01X1786450Y590040D02*
X1788088Y591678D01*
G01X1786450Y589450D02*
Y590040D01*
G01X1886465Y-11802D02*
X1895945Y-2322D01*
G01X1886465Y-15068D02*
Y-11802D01*
G01X1862590Y32650D02*
X1864706Y34766D01*
G01X1837268Y32650D02*
X1862590D01*
G01X1839500Y11400D02*
X1836800D01*
G01X1840187Y12087D02*
X1839500Y11400D01*
G01X1843274Y12087D02*
X1840187D01*
G01X1843663Y12476D02*
X1843274Y12087D01*
G01X1843663Y16606D02*
Y12476D01*
G01X1843019Y17250D02*
X1843663Y16606D01*
G01X1842000Y17250D02*
X1843019D01*
G01X1842000Y18332D02*
Y17250D01*
G01X1843836Y20168D02*
X1842000Y18332D01*
G01X1844835Y20168D02*
X1843836D01*
G01X1838700Y8000D02*
X1840400Y9700D01*
G01X1889569Y-18568D02*
X1886465D01*
G01X1889575Y-18562D02*
X1889569Y-18568D01*
G01X1895213Y-18562D02*
X1897472Y-20821D01*
G01X1889575Y-18562D02*
X1895213D01*
G01X1845700Y6825D02*
X1844850Y5975D01*
G01X1847818Y6825D02*
X1845700D01*
G01X1853023Y12030D02*
X1847818Y6825D01*
G01X1859210Y12030D02*
X1853023D01*
G01X1862472Y15292D02*
X1859210Y12030D01*
G01X1874982Y15292D02*
X1862472D01*
G01X1876368Y16678D02*
X1874982Y15292D01*
G01X1877361Y16678D02*
X1876368D01*
G01X1878455Y17772D02*
X1877361Y16678D01*
G01X1878455Y20607D02*
Y17772D01*
G01X1876881Y22181D02*
X1878455Y20607D01*
G01X1876582Y22480D02*
X1873336D01*
G01X1876881Y22181D02*
X1876582Y22480D01*
G01X1848322Y12322D02*
X1846500Y10500D01*
G01X1848322Y12723D02*
Y12322D01*
G01X1839440Y13750D02*
X1838850Y13160D01*
G01X1842000Y13750D02*
X1839440D01*
G01X1838690Y13000D02*
X1838850Y13160D01*
G01X1835600Y13000D02*
X1838690D01*
G01X1838750Y15730D02*
Y17500D01*
G01X1838000Y14980D02*
X1838750Y15730D01*
G01X1836850Y14980D02*
X1838000D01*
G01X1835600Y13000D02*
Y13730D01*
G01X1874648Y16317D02*
X1876792Y18461D01*
G01X1861947Y16317D02*
X1874648D01*
G01X1858780Y13150D02*
X1861947Y16317D01*
G01X1852492Y13150D02*
X1858780D01*
G01X1847142Y7800D02*
X1852492Y13150D01*
G01X1845300Y7800D02*
X1847142D01*
G01X1844400Y6900D02*
X1845300Y7800D01*
G01X1876273Y18980D02*
X1873336D01*
G01X1876792Y18461D02*
X1876273Y18980D01*
G01X1842916Y33660D02*
X1847236Y37980D01*
G01X1839880Y33660D02*
X1842916D01*
G01X1839300Y34240D02*
X1839880Y33660D01*
G01X1839300Y36995D02*
Y34240D01*
G01X1838875Y37420D02*
X1839300Y36995D01*
G01X1839580Y41480D02*
X1843236D01*
G01X1838500Y40400D02*
X1839580Y41480D01*
G01X1875912Y39088D02*
X1871812D01*
G01X1877454Y37546D02*
X1875912Y39088D01*
G01X1878997Y37546D02*
X1877454D01*
G01X1867619Y37679D02*
Y39779D01*
G01X1864706Y34766D02*
X1867619Y37679D01*
G01X1870450Y47250D02*
X1866100Y51600D01*
G01X1871988Y47250D02*
X1870450D01*
G01X1841040Y37980D02*
X1843236D01*
G01X1840340Y38680D02*
X1841040Y37980D01*
G01X1839415Y38680D02*
X1840340D01*
G01X1839272Y38537D02*
X1839415Y38680D01*
G01X1837728Y38537D02*
X1839272D01*
G01X1837694Y38571D02*
X1837728Y38537D01*
G01X1866039Y74021D02*
Y75138D01*
G01X1866670Y73390D02*
X1866039Y74021D01*
G01X1871460Y73390D02*
X1866670D01*
G01X1866039Y78537D02*
Y75138D01*
G01X1843236Y45556D02*
Y44980D01*
G01X1844610Y46930D02*
X1843236Y45556D01*
G01X1856350Y46930D02*
X1844610D01*
G01X1860786Y42494D02*
X1856350Y46930D01*
G01X1860786Y41200D02*
Y42494D01*
G01X1855465Y44980D02*
X1847236D01*
G01X1858198Y42247D02*
X1855465Y44980D01*
G01X1858198Y41108D02*
Y42247D01*
G01X1850384Y76339D02*
X1846423Y80300D01*
G01X1850384Y72614D02*
Y76339D01*
G01X1855893Y67105D02*
X1850384Y72614D01*
G01X1866376Y67105D02*
X1855893D01*
G01X1867832Y68561D02*
X1866376Y67105D01*
G01X1875839Y68561D02*
X1867832D01*
G01X1882700Y61700D02*
X1875839Y68561D01*
G01X1882700Y44100D02*
Y61700D01*
G01X1878800Y40200D02*
X1882700Y44100D01*
G01X1894885Y67193D02*
X1898161D01*
G01X1891494Y70584D02*
X1894885Y67193D01*
G01X1891494Y67456D02*
Y70584D01*
G01X1892600Y66350D02*
X1891494Y67456D01*
G01X1892600Y48975D02*
Y66350D01*
G01X1895945Y45630D02*
X1892600Y48975D01*
G01X1873956Y60299D02*
Y55350D01*
G01X1856333Y34746D02*
Y34518D01*
G01X1854109Y36970D02*
X1856333Y34746D01*
G01X1852390Y36970D02*
X1854109D01*
G01X1847880Y41480D02*
X1852390Y36970D01*
G01X1847236Y41480D02*
X1847880D01*
G01X1895000Y59245D02*
X1900945Y53300D01*
G01X1895000Y61600D02*
Y59245D01*
G01X1896800Y63400D02*
X1895000Y61600D01*
G01X1902701Y63400D02*
X1896800D01*
G01X1845293Y103000D02*
X1842522Y105771D01*
G01X1859428Y103000D02*
X1845293D01*
G01X1866395Y109967D02*
X1859428Y103000D01*
G01X1866606Y109967D02*
X1866395D01*
G01X1860100Y109100D02*
Y111500D01*
G01X1857358Y106358D02*
X1860100Y109100D01*
G01X1851341Y106358D02*
X1857358D01*
G01X1860100Y129900D02*
Y111500D01*
G01X1861015Y130815D02*
X1860100Y129900D01*
G01X1895372Y136099D02*
X1897500Y133971D01*
G01X1895060Y136099D02*
X1895372D01*
G01X1881290Y105712D02*
Y109080D01*
G01X1881165Y105587D02*
X1881290Y105712D01*
G01X1881165Y105561D02*
Y105587D01*
G01X1842618Y150948D02*
X1839720Y148050D01*
G01X1856163Y150948D02*
X1842618D01*
G01X1863500Y147999D02*
X1861932Y146431D01*
G01X1863500Y151000D02*
Y147999D01*
G01X1859663Y148700D02*
Y150948D01*
G01X1861932Y146431D02*
X1859663Y148700D01*
G01X1839623Y170486D02*
X1840783Y169326D01*
G01X1836932Y170486D02*
X1839623D01*
G01X1896710Y194140D02*
X1898250Y192600D01*
G01X1896710Y194380D02*
Y194140D01*
G01X1839000Y181425D02*
Y183750D01*
G01X1837275Y179700D02*
X1839000Y181425D01*
G01X1836100Y179700D02*
X1837275D01*
G01X1845000Y187250D02*
Y199499D01*
G01X1844110Y206600D02*
X1842136D01*
G01X1856901Y200100D02*
X1858500D01*
G01X1850401Y206600D02*
X1856901Y200100D01*
G01X1844110Y206600D02*
X1850401D01*
G01X1842000Y188750D02*
X1841280Y189470D01*
G01X1842000Y187250D02*
Y188750D01*
G01X1852962Y210538D02*
X1846134D01*
G01X1855288Y208212D02*
X1852962Y210538D01*
G01X1861687Y208212D02*
X1855288D01*
G01X1864007Y205892D02*
X1861687Y208212D01*
G01X1872640Y205892D02*
X1864007D01*
G01X1876335Y209587D02*
X1872640Y205892D01*
G01X1878912Y209587D02*
X1876335D01*
G01X1879899Y208600D02*
X1878912Y209587D01*
G01X1891200Y208600D02*
X1879899D01*
G01X1892732Y210132D02*
X1891200Y208600D01*
G01X1896068Y210132D02*
X1892732D01*
G01X1897000Y209200D02*
X1896068Y210132D01*
G01X1849877Y209603D02*
X1845353D01*
G01X1857717Y201763D02*
X1849877Y209603D01*
G01X1859189Y201763D02*
X1857717D01*
G01X1860754Y200198D02*
X1859189Y201763D01*
G01X1866322Y200198D02*
X1860754D01*
G01X1867187Y201063D02*
X1866322Y200198D01*
G01X1877613Y201063D02*
X1867187D01*
G01X1881680Y205130D02*
X1877613Y201063D01*
G01X1891120Y205130D02*
X1881680D01*
G01X1891880Y204370D02*
X1891120Y205130D01*
G01X1865098Y199100D02*
X1864464Y198466D01*
G01X1868000Y199100D02*
X1865098D01*
G01X1895070Y199200D02*
X1901130D01*
G01X1893120Y197250D02*
X1895070Y199200D01*
G01X1885580Y197250D02*
X1893120D01*
G01X1885200Y197630D02*
X1885580Y197250D01*
G01X1877530Y197630D02*
X1885200D01*
G01X1874900Y195000D02*
X1877530Y197630D01*
G01X1859985Y195000D02*
X1874900D01*
G01X1850885Y204100D02*
X1859985Y195000D01*
G01X1842620Y204100D02*
X1850885D01*
G01X1870363Y209637D02*
X1872100Y207900D01*
G01X1867000Y209637D02*
X1870363D01*
G01X1866263Y208900D02*
X1867000Y209637D01*
G01X1863700Y208900D02*
X1866263D01*
G01X1862963Y209637D02*
X1863700Y208900D01*
G01X1857205Y209637D02*
X1862963D01*
G01X1854477Y212365D02*
X1857205Y209637D01*
G01X1845300Y216500D02*
X1847000D01*
G01X1836000Y225800D02*
X1845300Y216500D01*
G01X1845000Y180400D02*
Y183750D01*
G01X1845700Y179700D02*
X1845000Y180400D01*
G01X1849013Y196587D02*
X1847000Y198600D01*
G01X1849013Y176873D02*
Y196587D01*
G01X1846340Y174200D02*
X1849013Y176873D01*
G01X1841900Y174200D02*
X1846340D01*
G01X1842000Y180800D02*
Y183750D01*
G01X1840900Y179700D02*
X1842000Y180800D01*
G01X1845831Y225000D02*
X1847000D01*
G01X1841831Y229000D02*
X1845831Y225000D01*
G01X1853264Y249900D02*
X1840844D01*
G01X1854374Y248790D02*
X1853264Y249900D01*
G01X1888376Y230300D02*
X1889463Y231387D01*
G01X1884800Y230300D02*
X1888376D01*
G01X1882625Y228125D02*
X1884800Y230300D01*
G01X1882625Y225875D02*
Y228125D01*
G01X1884400Y224100D02*
X1882625Y225875D01*
G01X1845600Y237000D02*
X1843600Y239000D01*
G01X1847000Y237000D02*
X1845600D01*
G01X1893222Y233338D02*
X1899810D01*
G01X1893031Y233147D02*
X1893222Y233338D01*
G01X1886480Y233147D02*
X1893031D01*
G01X1885719Y232386D02*
X1886480Y233147D01*
G01X1881800Y224200D02*
X1881900Y224100D01*
G01X1881800Y228467D02*
Y224200D01*
G01X1885719Y232386D02*
X1881800Y228467D01*
G01X1892963Y228387D02*
Y231387D01*
G01X1893198Y231622D02*
X1892963Y231387D01*
G01X1896735Y231622D02*
X1893198D01*
G01X1896735Y223815D02*
Y225622D01*
G01X1897527Y223023D02*
X1896735Y223815D01*
G01Y228622D02*
Y225622D01*
G01Y231622D02*
Y228622D01*
G01X1892963Y227263D02*
Y228387D01*
G01X1891950Y226250D02*
X1892963Y227263D01*
G01X1891950Y225100D02*
Y226250D01*
G01X1836348Y235604D02*
X1835936D01*
G01X1840052Y231900D02*
X1836348Y235604D01*
G01X1843500Y231900D02*
X1840052D01*
G01X1845600Y234000D02*
X1843500Y231900D01*
G01X1847000Y234000D02*
X1845600D01*
G01X1837863Y245413D02*
X1836713Y246563D01*
G01X1837863Y243946D02*
Y245413D01*
G01X1839047Y242762D02*
X1837863Y243946D01*
G01X1844381Y242762D02*
X1839047D01*
G01X1845337Y243718D02*
X1844381Y242762D01*
G01X1845337Y245474D02*
Y243718D01*
G01X1845863Y246000D02*
X1845337Y245474D01*
G01X1847000Y246000D02*
X1845863D01*
G01X1839534Y245040D02*
X1840149Y244425D01*
G01X1839534Y246818D02*
Y245040D01*
G01X1836837Y249515D02*
X1839534Y246818D01*
G01X1836837Y252438D02*
Y249515D01*
G01X1889913Y222239D02*
Y220437D01*
G01X1890795Y223121D02*
X1889913Y222239D01*
G01X1893927Y223121D02*
X1890795D01*
G01X1894968Y222080D02*
X1893927Y223121D01*
G01X1894968Y220827D02*
Y222080D01*
G01X1842200Y224800D02*
X1839800Y227200D01*
G01X1842200Y223900D02*
Y224800D01*
G01X1844100Y222000D02*
X1842200Y223900D01*
G01X1847000Y222000D02*
X1844100D01*
G01X1885887Y228387D02*
X1889463D01*
G01X1885000Y227500D02*
X1885887Y228387D01*
G01X1841764Y240764D02*
X1840300Y239300D01*
G01X1844800Y240764D02*
X1841764D01*
G01X1845564Y240000D02*
X1844800Y240764D01*
G01X1847000Y240000D02*
X1845564D01*
G01X1842300Y230075D02*
X1836525D01*
G01X1844375Y228000D02*
X1842300Y230075D01*
G01X1847000Y228000D02*
X1844375D01*
G01X1838600Y231000D02*
X1836900Y232700D01*
G01X1847000Y231000D02*
X1838600D01*
G01X1845837Y241837D02*
X1847000Y243000D01*
G01X1838663Y241837D02*
X1845837D01*
G01X1835900Y244600D02*
X1838663Y241837D01*
G01X1864700Y453923D02*
Y476300D01*
G01X1865100Y453523D02*
X1864700Y453923D01*
G01X1865100Y452050D02*
Y453523D01*
G01X1866050Y451100D02*
X1865100Y452050D01*
G01X1878500Y450600D02*
X1878100Y450200D01*
G01X1878500Y454750D02*
Y450600D01*
G01X1858633Y454767D02*
X1861312Y457446D01*
G01X1858633Y452803D02*
Y454767D01*
G01X1849487Y457002D02*
Y475977D01*
G01X1850674Y455815D02*
X1849487Y457002D01*
G01X1850674Y452375D02*
Y455815D01*
G01X1848699Y450400D02*
X1850674Y452375D01*
G01X1845201Y450400D02*
X1848699D01*
G01X1839201Y444400D02*
X1845201Y450400D01*
G01X1853000Y463500D02*
Y468906D01*
G01X1853200Y445100D02*
X1855000D01*
G01X1844402Y436302D02*
X1853200Y445100D01*
G01X1850412Y457386D02*
Y470701D01*
G01X1851599Y456199D02*
X1850412Y457386D01*
G01X1851599Y451990D02*
Y456199D01*
G01X1849084Y449475D02*
X1851599Y451990D01*
G01X1845875Y449475D02*
X1849084D01*
G01X1839862Y443462D02*
X1845875Y449475D01*
G01X1861100Y441500D02*
X1858500D01*
G01X1867500Y447900D02*
X1861100Y441500D01*
G01X1846259Y448550D02*
X1840246Y442537D01*
G01X1849468Y448550D02*
X1846259D01*
G01X1852524Y451606D02*
X1849468Y448550D01*
G01X1852524Y456583D02*
Y451606D01*
G01X1851337Y457770D02*
X1852524Y456583D01*
G01X1851337Y470317D02*
Y457770D01*
G01X1866900Y454102D02*
Y458400D01*
G01X1868015Y452987D02*
X1866900Y454102D01*
G01X1874785Y463285D02*
X1874750Y463250D01*
G01X1874785Y472585D02*
Y463285D01*
G01X1869350Y463250D02*
X1874750D01*
G01X1866900Y460800D02*
X1869350Y463250D01*
G01X1866900Y458400D02*
Y460800D01*
G01X1856000Y456848D02*
Y460000D01*
G01X1856422Y456426D02*
X1856000Y456848D01*
G01X1856422Y456400D02*
Y456426D01*
G01Y449650D02*
Y456400D01*
G01X1853297Y446525D02*
X1856422Y449650D01*
G01X1852609Y446525D02*
X1853297D01*
G01X1843811Y437727D02*
X1852609Y446525D01*
G01X1852500Y441500D02*
X1855000D01*
G01X1845877Y434877D02*
X1852500Y441500D01*
G01X1847037Y456868D02*
Y481796D01*
G01X1848848Y455057D02*
X1847037Y456868D01*
G01X1848848Y453132D02*
Y455057D01*
G01X1848016Y452300D02*
X1848848Y453132D01*
G01X1844462Y452300D02*
X1848016D01*
G01X1838400Y446238D02*
X1844462Y452300D01*
G01X1857900Y463500D02*
X1856000D01*
G01X1859200Y464800D02*
X1857900Y463500D01*
G01X1853000Y458123D02*
Y460000D01*
G01X1853949Y457174D02*
X1853000Y458123D01*
G01X1853949Y450996D02*
Y457174D01*
G01X1848511Y445558D02*
X1853949Y450996D01*
G01X1844065Y441112D02*
X1848511Y445558D01*
G01X1858916Y445100D02*
X1858500D01*
G01X1861902Y448086D02*
X1858916Y445100D01*
G01X1861902Y451169D02*
Y448086D01*
G01X1861174Y451897D02*
X1861902Y451169D01*
G01X1861174Y453774D02*
Y451897D01*
G01X1863800Y456400D02*
X1861174Y453774D01*
G01X1863800Y477001D02*
Y456400D01*
G01X1880776Y479000D02*
X1899500D01*
G01X1878526Y476750D02*
X1880776Y479000D01*
G01X1876374Y476750D02*
X1878526D01*
G01X1875351Y477773D02*
X1876374Y476750D01*
G01X1866173Y477773D02*
X1875351D01*
G01X1864700Y476300D02*
X1866173Y477773D01*
G01X1867500Y468522D02*
Y472200D01*
G01X1868167Y467855D02*
X1867500Y468522D01*
G01X1838280Y509780D02*
X1836400Y507900D01*
G01X1838280Y513800D02*
Y509780D01*
G01X1871850Y503457D02*
X1869347Y500954D01*
G01X1871850Y509560D02*
Y503457D01*
G01X1881293Y516993D02*
X1880242Y515942D01*
G01X1881293Y519486D02*
Y516993D01*
G01X1878389Y514089D02*
X1880242Y515942D01*
G01X1872360Y514089D02*
X1878389D01*
G01X1871850Y513579D02*
X1872360Y514089D01*
G01X1871850Y509560D02*
Y513579D01*
G01X1842600Y516600D02*
X1842400Y516800D01*
G01X1847000Y516600D02*
X1842600D01*
G01X1855510Y482000D02*
X1851150Y477640D01*
G01X1863800Y482000D02*
X1855510D01*
G01X1865800Y480000D02*
X1863800Y482000D01*
G01X1874074Y480000D02*
X1865800D01*
G01X1875100Y481026D02*
X1874074Y480000D01*
G01X1899726Y481026D02*
X1875100D01*
G01X1849487Y475977D02*
X1851150Y477640D01*
G01X1853000Y468906D02*
X1855206Y471112D01*
G01X1867014Y514325D02*
X1869914Y517225D01*
G01X1865755Y514325D02*
X1867014D01*
G01X1862547Y511117D02*
X1865755Y514325D01*
G01X1862547Y505533D02*
Y511117D01*
G01X1864062Y504018D02*
X1862547Y505533D01*
G01X1865799Y504018D02*
X1864062D01*
G01X1859711Y480000D02*
X1863000D01*
G01X1850412Y470701D02*
X1859711Y480000D01*
G01X1875408Y475700D02*
X1867500D01*
G01X1875908Y475200D02*
X1875408Y475700D01*
G01X1878992Y475200D02*
X1875908D01*
G01X1880992Y477200D02*
X1878992Y475200D01*
G01X1900890Y477200D02*
X1880992D01*
G01X1863995Y525936D02*
X1861327Y528604D01*
G01X1863995Y523016D02*
Y525936D01*
G01X1867757Y519254D02*
X1863995Y523016D01*
G01X1867757Y518197D02*
Y519254D01*
G01X1866688Y517128D02*
X1867757Y518197D01*
G01X1865031Y500954D02*
X1865847D01*
G01X1863955Y502030D02*
X1865031Y500954D01*
G01X1863955Y502816D02*
Y502030D01*
G01X1861622Y505149D02*
X1863955Y502816D01*
G01X1861622Y511501D02*
Y505149D01*
G01X1865371Y515250D02*
X1861622Y511501D01*
G01X1866174Y515250D02*
X1865371D01*
G01X1867069Y516145D02*
X1866174Y515250D01*
G01X1867069Y516747D02*
Y516145D01*
G01X1866688Y517128D02*
X1867069Y516747D01*
G01X1841204Y524306D02*
X1836924Y528586D01*
G01X1844474Y524306D02*
X1841204D01*
G01X1845768Y525600D02*
X1844474Y524306D01*
G01X1847000Y525600D02*
X1845768D01*
G01X1847000D02*
X1853900D01*
G01Y528000D02*
Y525600D01*
G01X1895000Y488500D02*
X1897900Y485600D01*
G01X1888600Y488500D02*
X1895000D01*
G01X1884100Y493000D02*
X1888600Y488500D01*
G01X1859360Y516600D02*
X1859530Y516430D01*
G01X1853900Y516600D02*
X1859360D01*
G01X1857220Y476200D02*
X1851337Y470317D01*
G01X1859600Y476200D02*
X1857220D01*
G01X1875650Y473450D02*
X1874785Y472585D01*
G01X1881158Y473450D02*
X1875650D01*
G01X1881703Y473995D02*
X1881158Y473450D01*
G01X1883016Y473995D02*
X1881703D01*
G01X1873298Y497163D02*
X1875973Y499838D01*
G01X1857908Y497163D02*
X1873298D01*
G01X1856190Y498881D02*
X1857908Y497163D01*
G01X1856190Y502590D02*
Y498881D01*
G01X1856350Y502750D02*
X1856190Y502590D01*
G01X1856350Y502850D02*
Y502750D01*
G01X1858050Y504550D02*
X1856350Y502850D01*
G01X1858050Y505510D02*
Y504550D01*
G01Y506350D02*
Y505510D01*
G01X1858090Y506390D02*
X1858050Y506350D01*
G01X1858090Y508600D02*
Y506390D01*
G01X1889365Y516685D02*
Y527335D01*
G01X1893400Y512650D02*
X1889365Y516685D01*
G01X1893400Y508750D02*
Y512650D01*
G01X1891900Y507250D02*
X1893400Y508750D01*
G01X1880700Y507250D02*
X1891900D01*
G01X1878390Y509560D02*
X1880700Y507250D01*
G01X1874410Y509560D02*
X1878390D01*
G01X1846000Y491168D02*
Y496000D01*
G01X1844512Y489680D02*
X1846000Y491168D01*
G01X1844512Y489663D02*
Y489680D01*
G01X1844349Y489500D02*
X1844512Y489663D01*
G01X1844349Y484484D02*
Y489500D01*
G01X1847037Y481796D02*
X1844349Y484484D01*
G01X1859200Y467300D02*
Y464800D01*
G01X1860500Y468600D02*
X1859200Y467300D01*
G01X1860500Y469800D02*
Y468600D01*
G01Y472200D02*
Y469800D01*
G01X1859046Y473654D02*
X1860500Y472200D01*
G01X1857450Y473654D02*
X1859046D01*
G01X1847000Y486000D02*
Y487500D01*
G01X1850175Y482825D02*
X1847000Y486000D01*
G01X1864142Y482825D02*
X1850175D01*
G01X1866142Y480825D02*
X1864142Y482825D01*
G01X1873732Y480825D02*
X1866142D01*
G01X1874758Y481851D02*
X1873732Y480825D01*
G01X1878825Y481851D02*
X1874758D01*
G01X1879574Y482600D02*
X1878825Y481851D01*
G01X1899999Y482600D02*
X1879574D01*
G01X1869299Y504318D02*
Y504018D01*
G01X1869290Y504327D02*
X1869299Y504318D01*
G01X1869290Y509560D02*
Y504327D01*
G01Y513360D02*
Y509560D01*
G01X1871045Y515115D02*
X1869290Y513360D01*
G01X1876594Y515115D02*
X1871045D01*
G01X1878272Y516793D02*
X1876594Y515115D01*
G01X1878272Y519465D02*
Y516793D01*
G01X1865845Y479046D02*
X1863800Y477001D01*
G01X1877407Y479046D02*
X1865845D01*
G01X1859028Y545028D02*
X1858528Y544528D01*
G01X1864804Y545028D02*
X1859028D01*
G01X1855782Y542468D02*
X1864804D01*
G01X1855750Y542500D02*
X1855782Y542468D01*
G01X1855750Y545500D02*
Y548000D01*
G01Y545500D02*
Y542500D01*
G01X1869935Y565816D02*
Y563612D01*
G01X1869934Y565817D02*
X1869935Y565816D01*
G01X1869934Y567654D02*
Y565817D01*
G01X1871704Y569424D02*
X1869934Y567654D01*
G01X1871704Y572718D02*
Y569424D01*
G01X1851250Y568874D02*
X1838843D01*
G01X1890472Y545028D02*
X1887004D01*
G01X1891100Y544400D02*
X1890472Y545028D01*
G01X1891100Y542900D02*
Y544400D01*
G01X1891200Y542800D02*
X1891100Y542900D01*
G01X1891200Y542600D02*
Y542800D01*
G01X1897300Y536500D02*
X1891200Y542600D01*
G01X1893900Y543500D02*
X1898300Y539100D01*
G01X1893900Y543700D02*
Y543500D01*
G01X1893800Y543800D02*
X1893900Y543700D01*
G01X1893800Y545200D02*
Y543800D01*
G01X1893900Y545300D02*
X1893800Y545200D01*
G01X1893900Y546234D02*
Y545300D01*
G01X1892125Y548009D02*
X1893900Y546234D01*
G01X1892125Y550869D02*
Y548009D01*
G01X1890286Y552708D02*
X1892125Y550869D01*
G01X1887004Y552708D02*
X1890286D01*
G01X1845354Y534847D02*
X1845341Y534860D01*
G01X1855130Y534847D02*
X1845354D01*
G01X1855182Y534795D02*
X1855130Y534847D01*
G01X1855219Y534795D02*
X1855182D01*
G01X1856193Y533821D02*
X1855219Y534795D01*
G01X1856193Y532443D02*
Y533821D01*
G01X1856167Y532417D02*
X1856193Y532443D01*
G01X1856167Y530770D02*
Y532417D01*
G01X1856166Y530769D02*
X1856167Y530770D01*
G01X1856166Y530013D02*
Y530769D01*
G01X1857575Y528604D02*
X1856166Y530013D01*
G01X1861327Y528604D02*
X1857575D01*
G01X1868704Y566040D02*
X1868442Y565778D01*
G01X1868704Y572718D02*
Y566040D01*
G01X1836924Y528586D02*
X1836909D01*
G01X1864804Y552708D02*
X1859708D01*
G01X1852500Y531102D02*
X1854530Y533132D01*
G01X1852500Y530700D02*
Y531102D01*
G01Y529400D02*
X1853900Y528000D01*
G01X1852500Y530700D02*
Y529400D01*
G01X1897300Y582587D02*
X1893850D01*
G01X1897578Y582865D02*
X1897300Y582587D01*
G01X1848970Y542220D02*
X1849250Y542500D01*
G01X1848970Y539510D02*
Y542220D01*
G01X1847070Y537610D02*
X1848970Y539510D01*
G01X1852250Y542500D02*
X1849250D01*
G01X1868463Y587613D02*
X1869529Y588679D01*
G01X1868463Y586113D02*
Y587613D01*
G01X1867300Y584950D02*
X1868463Y586113D01*
G01X1865300Y584950D02*
X1867300D01*
G01X1893000Y543200D02*
X1897900Y538300D01*
G01X1893000Y543400D02*
Y543200D01*
G01X1892900Y543500D02*
X1893000Y543400D01*
G01X1892900Y545500D02*
Y543500D01*
G01X1893000Y545600D02*
X1892900Y545500D01*
G01X1893000Y545967D02*
Y545600D01*
G01X1891300Y547667D02*
X1893000Y545967D01*
G01X1891300Y549300D02*
Y547667D01*
G01X1890452Y550148D02*
X1891300Y549300D01*
G01X1887004Y550148D02*
X1890452D01*
G01X1848800Y551400D02*
X1851600D01*
G01X1847069Y588803D02*
X1851250Y584622D01*
G01X1875208Y539908D02*
X1864804D01*
G01X1876100Y540800D02*
X1875208Y539908D01*
G01X1876100Y550800D02*
Y540800D01*
G01X1869800Y557100D02*
X1876100Y550800D01*
G01X1837534Y579322D02*
X1837213Y579001D01*
G01X1859628Y547588D02*
X1857108Y550108D01*
G01X1864804Y547588D02*
X1859628D01*
G01X1896800Y553100D02*
X1901337Y557637D01*
G01X1896800Y551900D02*
Y553100D01*
G01Y551700D02*
X1898700Y549800D01*
G01X1896800Y551900D02*
Y551700D01*
G01X1899550Y586365D02*
X1895523D01*
G01X1860915Y557828D02*
X1864804D01*
G01X1860332Y557245D02*
X1860915Y557828D01*
G01X1857812Y557245D02*
X1860332D01*
G01X1861352Y550148D02*
X1864804D01*
G01X1860455Y551045D02*
X1861352Y550148D01*
G01X1858771Y551045D02*
X1860455D01*
G01X1857108Y552708D02*
X1858771Y551045D01*
G01X1871500Y581000D02*
Y579500D01*
G01X1874075Y583575D02*
X1871500Y581000D01*
G01X1882825Y583575D02*
X1874075D01*
G01X1885350Y581050D02*
X1882825Y583575D01*
G01X1885350Y578837D02*
Y581050D01*
G01X1863933Y576534D02*
X1856573D01*
G01X1866899Y579500D02*
X1863933Y576534D01*
G01X1871500Y579500D02*
X1866899D01*
G01X1896400Y544900D02*
X1899300Y542000D01*
G01X1896400Y547300D02*
Y544900D01*
G01X1894800Y548900D02*
X1896400Y547300D01*
G01X1894800Y554700D02*
Y548900D01*
G01X1889112Y560388D02*
X1894800Y554700D01*
G01X1887004Y560388D02*
X1889112D01*
G01X1856143Y554343D02*
X1854508Y552708D01*
G01X1856391Y554343D02*
X1856143D01*
G01X1856419Y554371D02*
X1856391Y554343D01*
G01X1859003Y554371D02*
X1856419D01*
G01X1859900Y555268D02*
X1859003Y554371D01*
G01X1864804Y555268D02*
X1859900D01*
G01X1872146Y535202D02*
Y533140D01*
G01X1872722Y535778D02*
X1872146Y535202D01*
G01X1871850Y531451D02*
Y527560D01*
G01X1872146Y531747D02*
X1871850Y531451D01*
G01X1872146Y533140D02*
Y531747D01*
G01X1881600Y586119D02*
X1879115D01*
G01X1882100Y586619D02*
X1881600Y586119D01*
G01X1882100Y588254D02*
Y586619D01*
G01X1892550Y586258D02*
X1897392Y591100D01*
G01X1882461Y586258D02*
X1892550D01*
G01X1882100Y586619D02*
X1882461Y586258D01*
G01X1891810Y529780D02*
X1904104D01*
G01X1889365Y527335D02*
X1891810Y529780D01*
G01X1895550Y544518D02*
X1899068Y541000D01*
G01X1895550Y546918D02*
Y544518D01*
G01X1893850Y548618D02*
X1895550Y546918D01*
G01X1893850Y554150D02*
Y548618D01*
G01X1890172Y557828D02*
X1893850Y554150D01*
G01X1887004Y557828D02*
X1890172D01*
G01X1897000Y535600D02*
X1939100D01*
G01X1890300Y542300D02*
X1897000Y535600D01*
G01X1890300Y542468D02*
Y542300D01*
G01X1887004Y542468D02*
X1890300D01*
G01X1890212Y547588D02*
X1887004D01*
G01X1890400Y547400D02*
X1890212Y547588D01*
G01X1890400Y547300D02*
Y547400D01*
G01X1892000Y545700D02*
X1890400Y547300D01*
G01X1892000Y543200D02*
Y545700D01*
G01X1892100Y543100D02*
X1892000Y543200D01*
G01X1892100Y542900D02*
Y543100D01*
G01X1897600Y537400D02*
X1892100Y542900D01*
G01X1890236Y555268D02*
X1887004D01*
G01X1892950Y552554D02*
X1890236Y555268D01*
G01X1892950Y548351D02*
Y552554D01*
G01X1894725Y546576D02*
X1892950Y548351D01*
G01X1894725Y544925D02*
Y546576D01*
G01X1894700Y544900D02*
X1894725Y544925D01*
G01X1894700Y544100D02*
Y544900D01*
G01X1894725Y544075D02*
X1894700Y544100D01*
G01X1894725Y543960D02*
Y544075D01*
G01X1898585Y540100D02*
X1894725Y543960D01*
G01X1869529Y588679D02*
X1872115D01*
G01X1875421D02*
X1875600Y588500D01*
G01X1872115Y588679D02*
X1875421D01*
G01X1840016Y588803D02*
X1847069D01*
G01X1839200Y589619D02*
X1840016Y588803D01*
G01X1881675Y588679D02*
X1882100Y588254D01*
G01X1879115Y588679D02*
X1881675D01*
G01X1900945Y-11584D02*
Y-6318D01*
G01X1904564Y-15203D02*
X1900945Y-11584D01*
G01X1904564Y-16768D02*
Y-15203D01*
G01X1907368Y-19572D02*
X1904564Y-16768D01*
G01X1909643Y-19572D02*
X1907368D01*
G01X1901755Y-20821D02*
X1903160Y-19416D01*
G01X1897472Y-20821D02*
X1901755D01*
G01X1901643Y67211D02*
X1901661Y67193D01*
G01X1901643Y70589D02*
Y67211D01*
G01Y72140D02*
Y70589D01*
G01X1907956Y78453D02*
X1901643Y72140D01*
G01X1911471Y78453D02*
X1907956D01*
G01X1913942Y75982D02*
X1911471Y78453D01*
G01X1913942Y69348D02*
Y75982D01*
G01X1915183Y68107D02*
X1913942Y69348D01*
G01X1920107Y68107D02*
X1915183D01*
G01X1920300Y68300D02*
X1920107Y68107D01*
G01X1928379Y87258D02*
X1936725Y95604D01*
G01X1928379Y78770D02*
Y87258D01*
G01X1909113Y70607D02*
X1908236D01*
G01X1913720Y66000D02*
X1909113Y70607D01*
G01X1917600Y66000D02*
X1913720D01*
G01X1908236Y67143D02*
X1908166Y67073D01*
G01X1908236Y70607D02*
Y67143D01*
G01X1918090Y71500D02*
X1916660Y70070D01*
G01X1920500Y71500D02*
X1918090D01*
G01X1920500Y73201D02*
Y71500D01*
G01X1920999Y73700D02*
X1920500Y73201D01*
G01X1922954Y73700D02*
X1920999D01*
G01X1923379Y74125D02*
X1922954Y73700D01*
G01X1923379Y78770D02*
Y74125D01*
G01X1942528Y94179D02*
X1946499Y98150D01*
G01X1937316Y94179D02*
X1942528D01*
G01X1933379Y90242D02*
X1937316Y94179D01*
G01X1933379Y78770D02*
Y90242D01*
G01X1900945Y53300D02*
Y49626D01*
G01X1904666Y65365D02*
X1902701Y63400D01*
G01X1904666Y67073D02*
Y65365D01*
G01X1942900Y150000D02*
X1944600Y151700D01*
G01X1942900Y146415D02*
Y150000D01*
G01X1941937Y145452D02*
X1942900Y146415D01*
G01X1937800Y134600D02*
X1966194D01*
G01X1931600Y128400D02*
X1937800Y134600D01*
G01X1931600Y122900D02*
Y128400D01*
G01X1929903Y121203D02*
X1931600Y122900D01*
G01X1926892Y121203D02*
X1929903D01*
G01X1918701Y127500D02*
X1919702Y128501D01*
G01X1916800Y127500D02*
X1918701D01*
G01X1916400Y127900D02*
X1916800Y127500D01*
G01X1918200Y135753D02*
Y137600D01*
G01X1917532Y135085D02*
X1918200Y135753D01*
G01X1917532Y135032D02*
Y135085D01*
G01X1916700Y134200D02*
X1917532Y135032D01*
G01X1916700Y128200D02*
Y134200D01*
G01X1916400Y127900D02*
X1916700Y128200D01*
G01X1926785Y139548D02*
X1929937D01*
G01X1925137Y137900D02*
X1926785Y139548D01*
G01X1918500Y137900D02*
X1925137D01*
G01X1918200Y137600D02*
X1918500Y137900D01*
G01X1926952Y156049D02*
X1924901Y158100D01*
G01X1949161Y149724D02*
X1948458Y149021D01*
G01X1952821Y149724D02*
X1949161D01*
G01X1958643Y135700D02*
X1959619Y136676D01*
G01X1941289Y135700D02*
X1958643D01*
G01X1940700Y136289D02*
X1941289Y135700D01*
G01X1940700Y136300D02*
Y136289D01*
G01X1958775Y137520D02*
X1959619Y136676D01*
G01X1951140Y137520D02*
X1958775D01*
G01X1948949Y139711D02*
X1951140Y137520D01*
G01X1948949Y144358D02*
Y139711D01*
G01X1948458Y144849D02*
X1948949Y144358D01*
G01X1948458Y149021D02*
Y144849D01*
G01X1916700Y122918D02*
Y122700D01*
G01X1919702Y125920D02*
X1916700Y122918D01*
G01X1927292Y111900D02*
X1930000Y114608D01*
G01X1925135Y111900D02*
X1927292D01*
G01X1925135Y110510D02*
Y111900D01*
G01X1928379Y107266D02*
X1925135Y110510D01*
G01X1928379Y105370D02*
Y107266D01*
G01X1936700Y146900D02*
X1937100D01*
G01X1933284Y143484D02*
X1936700Y146900D01*
G01X1929937Y143484D02*
X1933284D01*
G01X1937900Y146900D02*
X1940900Y149900D01*
G01X1937100Y146900D02*
X1937900D01*
G01X1917100Y145600D02*
X1915700Y144200D01*
G01X1917100Y147116D02*
Y145600D01*
G01X1919484Y149500D02*
X1917100Y147116D01*
G01X1923379Y101984D02*
Y105370D01*
G01X1925904Y99459D02*
X1923379Y101984D01*
G01X1934256Y99459D02*
X1925904D01*
G01X1927300Y151900D02*
X1929800D01*
G01X1927000Y152200D02*
X1927300Y151900D01*
G01X1941084Y95604D02*
X1943660Y98180D01*
G01X1936725Y95604D02*
X1941084D01*
G01X1933690Y141516D02*
X1929937D01*
G01X1936187Y144013D02*
X1933690Y141516D01*
G01X1927091D02*
X1929937D01*
G01X1925507Y143100D02*
X1927091Y141516D01*
G01X1923600Y143100D02*
X1925507D01*
G01X1951129Y143535D02*
X1956376D01*
G01X1950934Y143730D02*
X1951129Y143535D01*
G01X1952267Y141567D02*
X1956376D01*
G01X1951700Y141000D02*
X1952267Y141567D01*
G01X1897500Y133971D02*
Y131500D01*
G01X1962354Y139599D02*
X1956376D01*
G01X1945916Y141516D02*
X1947000Y142600D01*
G01X1941937Y141516D02*
X1945916D01*
G01X1945484Y143484D02*
X1941937D01*
G01X1946300Y144300D02*
X1945484Y143484D01*
G01X1946300Y147493D02*
Y144300D01*
G01X1944609Y149184D02*
X1946300Y147493D01*
G01X1946499Y98150D02*
X1946770D01*
G01X1897500Y124457D02*
X1897507Y124450D01*
G01X1897500Y128000D02*
Y124457D01*
G01X1925189Y96040D02*
X1933914D01*
G01X1923639Y97590D02*
X1925189Y96040D01*
G01X1922210Y97590D02*
X1923639D01*
G01X1918379Y101421D02*
X1922210Y97590D01*
G01X1918379Y105370D02*
Y101421D01*
G01X1921620Y111900D02*
X1917953D01*
G01X1918379Y110122D02*
Y105370D01*
G01X1917953Y110548D02*
X1918379Y110122D01*
G01X1917953Y111900D02*
Y110548D01*
G01X1951481Y154175D02*
X1949389Y152083D01*
G01X1951481Y156109D02*
Y154175D01*
G01X1957800Y152300D02*
X1960400D01*
G01X1956321Y150821D02*
X1957800Y152300D01*
G01X1956321Y149724D02*
Y150821D01*
G01X1898250Y192600D02*
Y191000D01*
G01X1924901Y158100D02*
X1921900D01*
G01X1922650Y158850D02*
Y163100D01*
G01X1921900Y158100D02*
X1922650Y158850D01*
G01X1936750Y157600D02*
X1940500D01*
G01X1933054Y183722D02*
X1930449D01*
G01X1934070Y182706D02*
X1933054Y183722D01*
G01X1934070Y181230D02*
Y182706D01*
G01X1935080Y180220D02*
X1934070Y181230D01*
G01X1938010Y180220D02*
X1935080D01*
G01X1938928Y181138D02*
X1938010Y180220D01*
G01X1938928Y183204D02*
Y181138D01*
G01X1921524Y193624D02*
X1921500Y193600D01*
G01X1921524Y198876D02*
Y193624D01*
G01X1921100Y199300D02*
X1921524Y198876D01*
G01X1921100Y199269D02*
Y199300D01*
G01X1947646Y175344D02*
X1947662Y175328D01*
G01X1947646Y178328D02*
Y175344D01*
G01X1952908Y175040D02*
X1955081D01*
G01X1949620Y178328D02*
X1952908Y175040D01*
G01X1947646Y178328D02*
X1949620D01*
G01X1915889Y199339D02*
X1912850Y196300D01*
G01X1918239Y199339D02*
X1915889D01*
G01X1920132Y201232D02*
X1918239Y199339D01*
G01X1922167Y201232D02*
X1920132D01*
G01X1925400Y197999D02*
X1922167Y201232D01*
G01X1925400Y196300D02*
Y197999D01*
G01X1941487Y181287D02*
Y183204D01*
G01X1938400Y178200D02*
X1941487Y181287D01*
G01X1900086Y211414D02*
Y213827D01*
G01X1900500Y211000D02*
X1900086Y211414D01*
G01X1900500Y209200D02*
Y211000D01*
G01Y204770D02*
X1900230Y204500D01*
G01X1900500Y209200D02*
Y204770D01*
G01X1904030Y196300D02*
X1909350D01*
G01X1901130Y199200D02*
X1904030Y196300D01*
G01X1916764Y200411D02*
X1917568Y201215D01*
G01X1912359Y200411D02*
X1916764D01*
G01X1909350Y197402D02*
X1912359Y200411D01*
G01X1909350Y196300D02*
Y197402D01*
G01X1938928Y188210D02*
Y190204D01*
G01X1938468Y187750D02*
X1938928Y188210D01*
G01X1937680Y187750D02*
X1938468D01*
G01X1937420Y187490D02*
X1937680Y187750D01*
G01X1935210Y187490D02*
X1937420D01*
G01X1933999Y188701D02*
X1935210Y187490D01*
G01X1933689Y188701D02*
X1933999D01*
G01X1933670Y188720D02*
X1933689Y188701D01*
G01X1932000Y188720D02*
X1933670D01*
G01X1931981Y188701D02*
X1932000Y188720D01*
G01X1930341Y188701D02*
X1931981D01*
G01X1948157Y163364D02*
X1948921D01*
G01X1947805Y163012D02*
X1948157Y163364D01*
G01X1943482Y163012D02*
X1947805D01*
G01X1938400Y163600D02*
X1937800Y163000D01*
G01X1942894Y163600D02*
X1938400D01*
G01X1943482Y163012D02*
X1942894Y163600D01*
G01X1953930Y168064D02*
X1964700Y178834D01*
G01X1950981Y168064D02*
X1953930D01*
G01X1931347Y169100D02*
X1930300Y170147D01*
G01X1932400Y169100D02*
X1931347D01*
G01X1933900Y167600D02*
X1932400Y169100D01*
G01X1951318Y179224D02*
Y181882D01*
G01X1953454Y177088D02*
X1951318Y179224D01*
G01X1954070Y177088D02*
X1953454D01*
G01X1935300Y176000D02*
Y172600D01*
G01X1935600Y176300D02*
X1935300Y176000D01*
G01X1943776Y168000D02*
Y169512D01*
G01X1943482Y167706D02*
X1943776Y168000D01*
G01X1943482Y166512D02*
Y167706D01*
G01X1943332Y169512D02*
X1943776D01*
G01X1942307Y170537D02*
X1943332Y169512D01*
G01X1942307Y171306D02*
Y170537D01*
G01X1941788Y171825D02*
X1942307Y171306D01*
G01X1941788Y174032D02*
Y171825D01*
G01X1944206Y176450D02*
X1941788Y174032D01*
G01X1944550Y176450D02*
X1944206D01*
G01X1952560Y170417D02*
X1954143Y172000D01*
G01X1950556Y170417D02*
X1952560D01*
G01X1946651Y166512D02*
X1950556Y170417D01*
G01X1943482Y166512D02*
X1946651D01*
G01X1955400Y172000D02*
X1962551Y179151D01*
G01X1954143Y172000D02*
X1955400D01*
G01X1917024Y196376D02*
Y193600D01*
G01X1916700Y196700D02*
X1917024Y196376D01*
G01X1947686Y190522D02*
Y193522D01*
G01X1946023Y191988D02*
X1944611Y193400D01*
G01X1946023Y191030D02*
Y191988D01*
G01X1946531Y190522D02*
X1946023Y191030D01*
G01X1947686Y190522D02*
X1946531D01*
G01X1941487Y188854D02*
Y190204D01*
G01Y197758D02*
X1944173Y200444D01*
G01X1941487Y190204D02*
Y197758D01*
G01X1900235Y232913D02*
Y231622D01*
G01X1899810Y233338D02*
X1900235Y232913D01*
G01X1897527Y220827D02*
Y223023D01*
G01X1902981Y228368D02*
X1903032D01*
G01X1900235Y225622D02*
X1902981Y228368D01*
G01X1902907Y231294D02*
X1900235Y228622D01*
G01X1938600Y458750D02*
Y458767D01*
G01X1935850Y458750D02*
X1938600D01*
G01X1934800Y457700D02*
X1935850Y458750D01*
G01X1938600Y463615D02*
X1937430Y464785D01*
G01X1938600Y458767D02*
Y463615D01*
G01X1929860Y483950D02*
Y486480D01*
G01X1928620Y482710D02*
X1929860Y483950D01*
G01X1928620Y481553D02*
X1927138Y480071D01*
G01X1928620Y482710D02*
Y481553D01*
G01X1939280Y471000D02*
X1943500D01*
G01X1937640Y472640D02*
X1939280Y471000D01*
G01X1934530Y472640D02*
X1937640D01*
G01X1932580Y470690D02*
X1934530Y472640D01*
G01X1919360Y470690D02*
X1932580D01*
G01X1916790Y473260D02*
X1919360Y470690D01*
G01X1916790Y481489D02*
Y473260D01*
G01X1914799Y483480D02*
X1916790Y481489D01*
G01X1909080Y483480D02*
X1914799D01*
G01X1908424Y482824D02*
X1909080Y483480D01*
G01X1903324Y482824D02*
X1908424D01*
G01X1899500Y479000D02*
X1903324Y482824D01*
G01X1949301Y471901D02*
X1962301D01*
G01X1948400Y471000D02*
X1949301Y471901D01*
G01X1943500Y471000D02*
X1948400D01*
G01X1912800Y508250D02*
Y510700D01*
G01X1944225Y474775D02*
X1945000Y474000D01*
G01X1942284Y474775D02*
X1944225D01*
G01X1941484Y473975D02*
X1942284Y474775D01*
G01X1937916Y473975D02*
X1941484D01*
G01X1935691Y476200D02*
X1937916Y473975D01*
G01X1934950Y476200D02*
X1935691D01*
G01X1934150Y475400D02*
X1934950Y476200D01*
G01X1957300Y517600D02*
X1959100Y515800D01*
G01X1957300Y520056D02*
Y517600D01*
G01X1961500Y524256D02*
X1957300Y520056D01*
G01X1948880Y526250D02*
Y528110D01*
G01X1902349Y483649D02*
X1899726Y481026D01*
G01X1908082Y483649D02*
X1902349D01*
G01X1915623Y491190D02*
X1908082Y483649D01*
G01X1934770Y491190D02*
X1915623D01*
G01X1937180Y488780D02*
X1934770Y491190D01*
G01X1942740Y488780D02*
X1937180D01*
G01X1943100Y488420D02*
X1942740Y488780D01*
G01X1946800Y475700D02*
X1948200Y474300D01*
G01X1941900Y475700D02*
X1946800D01*
G01X1941100Y474900D02*
X1941900Y475700D01*
G01X1938300Y474900D02*
X1941100D01*
G01X1936075Y477125D02*
X1938300Y474900D01*
G01X1935425Y477125D02*
X1936075D01*
G01X1934150Y478400D02*
X1935425Y477125D01*
G01X1909800Y508250D02*
Y510700D01*
G01X1929510Y476540D02*
X1930650Y475400D01*
G01X1920950Y476540D02*
X1929510D01*
G01X1919510Y475100D02*
X1920950Y476540D01*
G01X1940100Y477700D02*
X1939000Y476600D01*
G01X1951600Y477700D02*
X1940100D01*
G01X1951800Y477900D02*
X1951600Y477700D01*
G01X1953440Y479540D02*
X1951800Y477900D01*
G01X1953440Y488450D02*
Y479540D01*
G01X1954800Y515900D02*
X1956300D01*
G01X1953998Y516702D02*
X1954800Y515900D01*
G01X1953998Y519250D02*
Y516702D01*
G01Y521700D02*
Y519250D01*
G01X1955098Y522800D02*
X1953998Y521700D01*
G01X1956600Y522800D02*
X1955098D01*
G01X1959300Y525500D02*
X1956600Y522800D01*
G01X1911100Y503050D02*
X1912800Y504750D01*
G01X1911100Y489209D02*
Y503050D01*
G01X1907491Y485600D02*
X1911100Y489209D01*
G01X1897900Y485600D02*
X1907491D01*
G01X1929740Y477490D02*
X1930650Y478400D01*
G01X1921220Y477490D02*
X1929740D01*
G01X1919510Y479200D02*
X1921220Y477490D01*
G01X1937430Y464785D02*
Y469860D01*
G01X1910175Y504375D02*
X1909800Y504750D01*
G01X1910175Y489593D02*
Y504375D01*
G01X1907107Y486525D02*
X1910175Y489593D01*
G01X1898601Y486525D02*
X1907107D01*
G01X1898101Y487025D02*
X1898601Y486525D01*
G01X1898101Y487901D02*
Y487025D01*
G01X1903200Y493000D02*
X1898101Y487901D01*
G01X1904100Y493000D02*
X1903200D01*
G01X1947400Y509946D02*
Y528457D01*
G01X1945023Y507569D02*
X1947400Y509946D01*
G01X1943941Y507569D02*
X1945023D01*
G01X1942722Y506350D02*
X1943941Y507569D01*
G01X1942722Y505100D02*
Y506350D01*
G01X1949940Y491950D02*
X1953440D01*
G01X1947840Y494050D02*
X1949940Y491950D01*
G01X1947840Y498100D02*
Y494050D01*
G01X1953440Y491950D02*
Y495050D01*
G01X1930402Y521762D02*
Y516640D01*
G01X1932540Y523900D02*
X1930402Y521762D01*
G01X1934720Y523900D02*
X1932540D01*
G01X1940959Y523059D02*
Y524500D01*
G01X1939737Y521837D02*
X1940959Y523059D01*
G01X1937283Y521837D02*
X1939737D01*
G01X1935220Y523900D02*
X1937283Y521837D01*
G01X1934720Y523900D02*
X1935220D01*
G01X1928262Y514500D02*
X1908300D01*
G01X1930402Y516640D02*
X1928262Y514500D01*
G01X1910825Y525415D02*
X1908469D01*
G01X1914240Y522000D02*
X1910825Y525415D01*
G01X1927240Y522000D02*
X1914240D01*
G01X1931800Y526560D02*
X1927240Y522000D01*
G01X1937410Y524500D02*
X1935350Y526560D01*
G01X1938400Y524500D02*
X1937410D01*
G01X1938400Y527799D02*
Y524500D01*
G01X1904104Y529780D02*
X1908469Y525415D01*
G01X1943781Y508712D02*
X1942328D01*
G01X1945170Y510101D02*
X1943781Y508712D01*
G01X1945170Y510870D02*
Y510101D01*
G01X1943518Y515482D02*
Y517500D01*
G01X1945170Y513830D02*
X1943518Y515482D01*
G01X1945170Y510870D02*
Y513830D01*
G01X1956185Y526250D02*
X1956606Y526671D01*
G01X1953998Y526250D02*
X1956185D01*
G01X1901999Y484600D02*
X1899999Y482600D01*
G01X1907800Y484600D02*
X1901999D01*
G01X1915320Y492120D02*
X1907800Y484600D01*
G01X1936680Y492120D02*
X1915320D01*
G01X1939010Y494450D02*
X1936680Y492120D01*
G01X1939010Y499180D02*
Y494450D01*
G01X1941310Y501480D02*
X1939010Y499180D01*
G01X1944150Y501480D02*
X1941310D01*
G01X1945480Y502810D02*
X1944150Y501480D01*
G01X1945480Y506480D02*
Y502810D01*
G01X1948880Y509880D02*
X1945480Y506480D01*
G01X1948880Y519250D02*
Y509880D01*
G01X1943130Y491950D02*
X1943100Y491920D01*
G01X1946350Y491950D02*
X1943130D01*
G01X1945281Y493019D02*
X1946350Y491950D01*
G01X1945281Y498100D02*
Y493019D01*
G01X1920670Y588250D02*
X1918880Y586460D01*
G01X1929790Y587500D02*
X1932390Y590100D01*
G01X1925900Y587500D02*
X1929790D01*
G01X1924800Y586400D02*
X1925900Y587500D01*
G01X1918000Y584220D02*
X1911520Y590700D01*
G01X1918000Y582000D02*
Y584220D01*
G01X1954300Y532700D02*
X1959600D01*
G01X1953450Y531850D02*
X1954300Y532700D01*
G01X1952620Y531850D02*
X1953450D01*
G01X1948880Y528110D02*
X1952620Y531850D01*
G01X1923500Y579500D02*
X1927785D01*
G01X1934600Y565111D02*
Y561900D01*
G01X1933526Y566185D02*
X1934600Y565111D01*
G01X1930625Y566185D02*
X1933526D01*
G01X1935300Y536500D02*
X1897300D01*
G01X1939700Y540900D02*
X1935300Y536500D01*
G01X1948870Y578200D02*
X1952756Y582086D01*
G01X1942200Y578200D02*
X1948870D01*
G01X1939600Y580800D02*
X1942200Y578200D01*
G01X1932585Y580800D02*
X1939600D01*
G01X1931285Y579500D02*
X1932585Y580800D01*
G01X1931285Y578885D02*
Y579500D01*
G01X1932470Y577700D02*
X1931285Y578885D01*
G01X1934200Y577700D02*
X1932470D01*
G01X1935400Y547300D02*
X1937800Y549700D01*
G01X1935400Y543301D02*
Y547300D01*
G01X1931199Y539100D02*
X1935400Y543301D01*
G01X1898300Y539100D02*
X1931199D01*
G01X1909300Y573300D02*
X1918000Y564600D01*
G01X1906000Y573300D02*
X1909300D01*
G01X1918000Y560400D02*
Y564600D01*
G01X1919500Y558900D02*
X1918000Y560400D01*
G01X1899550Y582865D02*
X1897578D01*
G01X1901415D02*
X1899550D01*
G01X1904790Y586240D02*
X1901415Y582865D01*
G01X1924437Y561127D02*
Y558237D01*
G01X1925808Y562498D02*
X1924437Y561127D01*
G01X1915963Y553000D02*
X1912750D01*
G01X1916363Y552600D02*
X1915963Y553000D01*
G01X1920500Y552600D02*
X1916363D01*
G01X1921000Y553100D02*
X1920500Y552600D01*
G01X1921000Y554400D02*
Y553100D01*
G01X1928500Y556200D02*
Y553500D01*
G01X1927600Y557100D02*
X1928500Y556200D01*
G01X1925574Y557100D02*
X1927600D01*
G01X1924437Y558237D02*
X1925574Y557100D01*
G01X1921000Y555700D02*
Y554400D01*
G01X1923537Y558237D02*
X1921000Y555700D01*
G01X1924437Y558237D02*
X1923537D01*
G01X1958940Y538890D02*
X1960550Y540500D01*
G01X1957550Y537500D02*
X1958940Y538890D01*
G01X1956100Y537500D02*
X1957550D01*
G01X1923400Y583000D02*
X1927785D01*
G01X1915100Y573300D02*
X1918000D01*
G01X1906400Y582000D02*
X1915100Y573300D01*
G01X1906000Y582000D02*
X1906400D01*
G01X1904800Y580800D02*
X1906000Y582000D01*
G01X1904800Y577700D02*
Y580800D01*
G01X1936400Y544300D02*
X1937200Y545100D01*
G01X1936400Y543100D02*
Y544300D01*
G01X1931600Y538300D02*
X1936400Y543100D01*
G01X1931566Y538300D02*
X1931600D01*
G01X1931541Y538275D02*
X1931566Y538300D01*
G01X1897958Y538275D02*
X1931541D01*
G01X1897933Y538300D02*
X1897958Y538275D01*
G01X1897900Y538300D02*
X1897933D01*
G01X1937648Y572000D02*
X1931285D01*
G01X1939348Y570300D02*
X1937648Y572000D01*
G01X1948844Y570300D02*
X1939348D01*
G01X1952756Y574212D02*
X1948844Y570300D01*
G01X1932200Y569400D02*
X1934400D01*
G01X1931250Y570350D02*
X1932200Y569400D01*
G01X1931250Y572000D02*
Y570350D01*
G01X1931285Y572000D02*
X1931250D01*
G01X1940200Y544100D02*
X1939800Y543700D01*
G01X1942982Y544100D02*
X1940200D01*
G01X1943750Y543332D02*
X1942982Y544100D01*
G01X1943750Y541100D02*
Y543332D01*
G01X1922500Y548900D02*
X1921500Y549900D01*
G01X1922500Y546700D02*
Y548900D01*
G01X1922700Y546500D02*
X1922500Y546700D01*
G01X1925941Y546500D02*
X1922700D01*
G01X1921500Y548700D02*
Y549900D01*
G01X1916000Y543200D02*
X1921500Y548700D01*
G01X1900900Y543200D02*
X1916000D01*
G01X1898850Y545250D02*
X1900900Y543200D01*
G01X1940500Y545600D02*
X1939800Y546300D01*
G01X1943600Y545600D02*
X1940500D01*
G01X1945413Y543787D02*
X1943600Y545600D01*
G01X1945413Y542927D02*
Y543787D01*
G01X1945940Y542400D02*
X1945413Y542927D01*
G01X1946800Y542400D02*
X1945940D01*
G01X1957174Y547717D02*
X1956191Y548700D01*
G01X1957174Y546526D02*
Y547717D01*
G01X1959100Y544600D02*
X1957174Y546526D01*
G01X1956650Y540050D02*
X1959100Y542500D01*
G01X1955501Y540050D02*
X1956650D01*
G01X1954100Y538649D02*
X1955501Y540050D01*
G01X1954100Y534200D02*
Y538649D01*
G01X1952900Y533000D02*
X1954100Y534200D01*
G01X1952198Y533000D02*
X1952900D01*
G01X1948111Y528913D02*
X1952198Y533000D01*
G01X1947856Y528913D02*
X1948111D01*
G01X1947400Y528457D02*
X1947856Y528913D01*
G01X1949800Y540400D02*
X1948100Y538700D01*
G01X1949800Y542350D02*
Y540400D01*
G01X1906000Y561000D02*
Y564600D01*
G01X1905300Y560300D02*
X1906000Y561000D01*
G01X1903100Y560300D02*
X1905300D01*
G01X1901337Y558537D02*
X1903100Y560300D01*
G01X1901337Y557637D02*
Y558537D01*
G01X1901400Y549250D02*
X1904250D01*
G01X1900850Y549800D02*
X1901400Y549250D01*
G01X1898700Y549800D02*
X1900850D01*
G01X1899300Y542000D02*
X1901671D01*
G01X1952756Y555156D02*
Y558464D01*
G01X1951800Y554200D02*
X1952756Y555156D01*
G01X1951800Y546400D02*
Y554200D01*
G01X1951250Y545850D02*
X1951800Y546400D01*
G01X1949800Y545850D02*
X1951250D01*
G01X1949800Y551100D02*
Y545850D01*
G01X1947100Y553800D02*
X1949800Y551100D01*
G01X1934600Y553800D02*
X1947100D01*
G01X1932600Y551800D02*
X1934600Y553800D01*
G01X1932600Y544300D02*
Y551800D01*
G01X1930300Y542000D02*
X1932600Y544300D01*
G01X1901671Y542000D02*
X1930300D01*
G01X1923300Y568700D02*
X1923000D01*
G01X1924800Y567200D02*
X1923300Y568700D01*
G01X1925500Y567200D02*
X1924800D01*
G01X1925800Y567500D02*
X1925500Y567200D01*
G01X1927785Y569485D02*
X1925800Y567500D01*
G01X1927785Y572000D02*
Y569485D01*
G01X1935350Y526560D02*
X1931800D01*
G01X1954350Y550398D02*
Y545350D01*
G01X1955163Y551211D02*
X1954350Y550398D01*
G01X1955163Y552391D02*
Y551211D01*
G01X1960772Y558000D02*
X1955163Y552391D01*
G01X1938901Y528300D02*
X1938400Y527799D01*
G01X1945200Y528300D02*
X1938901D01*
G01X1945682Y528782D02*
X1945200Y528300D01*
G01X1945682Y530782D02*
Y528782D01*
G01X1947500Y532600D02*
X1945682Y530782D01*
G01X1949600Y534700D02*
X1947500Y532600D01*
G01X1949600Y537300D02*
Y534700D01*
G01X1954350Y542050D02*
X1949600Y537300D01*
G01X1954350Y545350D02*
Y542050D01*
G01X1923600Y575500D02*
X1927785D01*
G01X1931059Y558800D02*
Y553500D01*
G01X1930600Y559259D02*
X1931059Y558800D01*
G01X1930600Y561000D02*
Y559259D01*
G01X1945900Y546800D02*
Y549900D01*
G01X1946800Y545900D02*
X1945900Y546800D01*
G01X1908245Y541000D02*
X1908295Y541050D01*
G01X1899068Y541000D02*
X1908245D01*
G01X1947600Y546700D02*
X1946800Y545900D01*
G01X1947600Y550700D02*
Y546700D01*
G01X1945600Y552700D02*
X1947600Y550700D01*
G01X1934699Y552700D02*
X1945600D01*
G01X1933600Y551601D02*
X1934699Y552700D01*
G01X1933600Y544001D02*
Y551601D01*
G01X1930649Y541050D02*
X1933600Y544001D01*
G01X1908295Y541050D02*
X1930649D01*
G01X1931250Y583000D02*
X1931285D01*
G01X1931250Y584575D02*
Y583000D01*
G01X1931675Y585000D02*
X1931250Y584575D01*
G01X1941968Y585000D02*
X1931675D01*
G01X1944882Y582086D02*
X1941968Y585000D01*
G01X1935400Y583000D02*
X1931285D01*
G01X1939100Y535600D02*
X1940800Y537300D01*
G01X1931785Y576000D02*
X1931285Y575500D01*
G01X1943094Y576000D02*
X1931785D01*
G01X1944882Y574212D02*
X1943094Y576000D01*
G01X1933100Y537400D02*
X1897600D01*
G01X1937300Y541600D02*
X1933100Y537400D01*
G01X1931710Y573700D02*
X1934200D01*
G01X1931285Y574125D02*
X1931710Y573700D01*
G01X1931285Y575500D02*
Y574125D01*
G01X1931059Y548941D02*
Y546500D01*
G01X1930700Y549300D02*
X1931059Y548941D01*
G01X1928900Y549300D02*
X1930700D01*
G01X1928500Y548900D02*
X1928900Y549300D01*
G01X1928500Y546500D02*
Y548900D01*
G01X1930900Y540100D02*
X1915085D01*
G01X1934500Y543700D02*
X1930900Y540100D01*
G01X1934500Y549900D02*
Y543700D01*
G01X1935400Y550800D02*
X1934500Y549900D01*
G01X1915085Y540100D02*
X1898585D01*
G01X1960346Y535000D02*
X1958500D01*
G01X1923230Y588250D02*
X1920670D01*
G01X1926240Y591260D02*
X1923230Y588250D01*
G01X1911520Y590700D02*
X1906000D01*
G01Y602300D02*
Y590700D01*
G01X1906900Y603200D02*
X1906000Y602300D01*
G01X1956300Y609900D02*
X1959200Y612800D01*
G01X1956300Y603300D02*
Y609900D01*
G01X1954700Y601700D02*
X1956300Y603300D01*
G01X1941200Y601700D02*
X1954700D01*
G01X1938800Y599300D02*
X1941200Y601700D01*
G01X1933848Y599300D02*
X1938800D01*
G01X1933548Y599000D02*
X1933848Y599300D01*
G01X1931059Y599000D02*
X1933548D01*
G01X1927050Y611550D02*
X1927750D01*
G01X1925100Y613500D02*
X1927050Y611550D01*
G01X1921700Y613500D02*
X1925100D01*
G01X1925941Y609741D02*
X1927750Y611550D01*
G01X1925941Y606000D02*
Y609741D01*
G01X1929349Y614500D02*
X1927000D01*
G01X1931250Y612599D02*
X1929349Y614500D01*
G01X1931250Y611550D02*
Y612599D01*
G01X1928500Y608500D02*
Y606000D01*
G01X1929250Y609250D02*
X1928500Y608500D01*
G01X1934350Y609250D02*
X1929250D01*
G01X1933960Y594760D02*
X1929740D01*
G01X1936157Y592563D02*
X1933960Y594760D01*
G01X1941403Y592563D02*
X1936157D01*
G01X1942640Y593800D02*
X1941403Y592563D01*
G01X1948720Y593800D02*
X1942640D01*
G01X1952754Y597834D02*
X1948720Y593800D01*
G01X1952756Y597834D02*
X1952754D01*
G01X1929740Y594760D02*
Y591260D01*
G01X1916800Y596900D02*
X1917750D01*
G01X1915050Y598650D02*
X1916800Y596900D01*
G01X1910900Y598650D02*
X1915050D01*
G01X1910150Y597900D02*
X1910900Y598650D01*
G01X1909200Y595350D02*
X1911750Y592800D01*
G01X1909200Y596950D02*
Y595350D01*
G01X1910150Y597900D02*
X1909200Y596950D01*
G01X1901460Y591100D02*
X1899700D01*
G01X1902040Y591680D02*
X1901460Y591100D01*
G01X1902040Y595634D02*
Y591680D01*
G01X1902800Y596394D02*
X1902040Y595634D01*
G01X1902800Y599200D02*
Y596394D01*
G01X1897392Y591100D02*
X1899700D01*
G01X1918000Y592100D02*
Y590700D01*
G01X1921250Y595350D02*
X1918000Y592100D01*
G01X1921250Y596900D02*
Y595350D01*
G01Y597657D02*
Y596900D01*
G01X1920242Y598665D02*
X1921250Y597657D01*
G01X1916438Y598665D02*
X1920242D01*
G01X1913180Y601923D02*
X1916438Y598665D01*
G01X1958300Y605300D02*
X1961000Y608000D01*
G01X1958300Y603300D02*
Y605300D01*
G01X1956200Y601200D02*
X1958300Y603300D01*
G01X1956200Y593404D02*
Y601200D01*
G01X1952756Y589960D02*
X1956200Y593404D01*
G01X1965485Y145503D02*
X1968376D01*
G01X1964382Y146606D02*
X1965485Y145503D01*
G01X1964382Y147318D02*
Y146606D01*
G01X1966619Y135025D02*
Y136676D01*
G01X1966194Y134600D02*
X1966619Y135025D01*
G01X1965907Y141567D02*
X1968376D01*
G01X1964700Y142774D02*
X1965907Y141567D01*
G01X1964700Y144500D02*
Y142774D01*
G01X1959821Y149379D02*
X1964700Y144500D01*
G01X1959821Y149724D02*
Y149379D01*
G01X1963119Y138834D02*
X1962354Y139599D01*
G01X1963119Y136676D02*
Y138834D01*
G01X1966700Y153000D02*
Y152400D01*
G01X1966311Y153389D02*
X1966700Y153000D01*
G01X1966311Y156309D02*
Y153389D01*
G01X1971890Y143535D02*
X1968376D01*
G01X1972305Y143120D02*
X1971890Y143535D01*
G01X1973004Y143120D02*
X1972305D01*
G01X1962800Y149900D02*
Y149300D01*
G01X1960400Y152300D02*
X1962800Y149900D01*
G01X1963751Y166445D02*
Y163564D01*
G01X1963092Y167104D02*
X1963751Y166445D01*
G01X1963092Y167936D02*
Y167104D01*
G01X1964028Y182172D02*
X1962551D01*
G01X1964700Y181500D02*
X1964028Y182172D01*
G01X1964700Y178834D02*
Y181500D01*
G01X1960252Y182172D02*
X1962551D01*
G01Y180204D02*
X1960252D01*
G01X1962551Y179151D02*
Y180204D01*
G01X1972800Y525516D02*
Y536800D01*
G01X1974247Y524069D02*
X1972800Y525516D01*
G01X1974247Y483847D02*
Y524069D01*
G01X1962301Y471901D02*
X1974247Y483847D01*
G01X1962541Y509681D02*
X1964270Y511410D01*
G01X1960919Y509681D02*
X1962541D01*
G01X1959100Y511500D02*
X1960919Y509681D01*
G01X1959100Y515800D02*
Y511500D01*
G01X1961500Y530800D02*
Y524256D01*
G01X1964270Y508961D02*
Y511410D01*
G01X1964481Y508750D02*
X1964270Y508961D01*
G01X1964481Y506010D02*
Y508750D01*
G01X1967040Y508040D02*
Y506010D01*
G01X1968375Y509375D02*
X1967040Y508040D01*
G01X1961922Y515778D02*
Y513010D01*
G01X1961600Y516100D02*
X1961922Y515778D01*
G01X1961600Y521700D02*
Y516100D01*
G01X1964281Y524381D02*
X1961600Y521700D01*
G01X1964281Y525057D02*
Y524381D01*
G01Y525057D02*
Y531065D01*
G01X1960700Y531600D02*
X1961500Y530800D01*
G01X1959600Y532700D02*
X1960700Y531600D01*
G01X1964640Y554500D02*
X1966100D01*
G01X1963501Y555639D02*
X1964640Y554500D01*
G01X1961715Y555639D02*
X1963501D01*
G01X1960550Y540500D02*
X1963000D01*
G01X1959100Y542500D02*
Y544600D01*
G01X1959200Y584100D02*
Y574929D01*
G01X1962100Y587000D02*
X1959200Y584100D01*
G01X1965000Y587000D02*
X1962100D01*
G01X1966800Y588800D02*
X1965000Y587000D01*
G01X1962400Y570000D02*
X1964882D01*
G01X1959200Y573200D02*
X1962400Y570000D01*
G01X1959200Y574929D02*
Y573200D01*
G01X1962800Y578200D02*
X1962500Y578500D01*
G01X1965700Y578200D02*
X1962800D01*
G01X1967363Y558000D02*
X1960772D01*
G01X1969100Y556263D02*
X1967363Y558000D01*
G01X1969100Y554600D02*
Y556263D01*
G01X1970000Y557163D02*
Y563000D01*
G01X1969100Y556263D02*
X1970000Y557163D01*
G01X1969500Y578400D02*
X1969800Y578100D01*
G01X1969500Y583300D02*
Y578400D01*
G01X1971300Y566700D02*
X1972800Y565200D01*
G01X1967500Y566700D02*
X1971300D01*
G01X1967500Y563059D02*
X1967441Y563000D01*
G01X1967500Y566700D02*
Y563059D01*
G01Y579900D02*
Y566700D01*
G01X1966941Y580459D02*
X1967500Y579900D01*
G01X1966941Y583300D02*
Y580459D01*
G01X1959120Y549835D02*
X1960078Y550793D01*
G01X1959120Y547050D02*
Y549835D01*
G01X1960300Y547050D02*
X1959120D01*
G01X1961850Y545500D02*
X1960300Y547050D01*
G01X1963000Y545500D02*
X1961850D01*
G01X1964281Y531065D02*
X1960346Y535000D01*
G01X1963200Y593173D02*
X1961771Y591744D01*
G01X1963200Y594600D02*
Y593173D01*
G01X1959200Y612800D02*
X1963300D01*
G01X1966800Y592200D02*
Y588800D01*
G01X1969300Y594700D02*
X1966800Y592200D01*
G01X1970000Y594700D02*
X1969300D01*
G01X1964300Y600000D02*
Y601900D01*
G01X1965300Y599000D02*
X1964300Y600000D01*
G01X1965300Y593200D02*
Y599000D01*
G01X1964382Y592282D02*
X1965300Y593200D01*
G01X1964382Y590300D02*
Y592282D01*
G01X1964800Y603100D02*
X1967500D01*
G01X1964300Y602600D02*
X1964800Y603100D01*
G01X1964300Y601900D02*
Y602600D01*
G01X1968300Y608000D02*
X1964100D01*
G01X1971000Y605300D02*
X1968300Y608000D01*
G01X1971000Y603100D02*
Y605300D01*
G01X1961000Y608000D02*
X1964100D01*
G01X1972000Y598200D02*
X1973000Y597200D01*
G01X1970000Y598200D02*
X1972000D01*
M02*
